(kicad_pcb
	(version 20241229)
	(generator "pcbnew")
	(generator_version "9.0")
	(general
		(thickness 1.61)
		(legacy_teardrops no)
	)
	(paper "A3")
	(title_block
		(title "RDIMM DDR5 Tester")
		(date "2026-05-21")
		(rev "2.2.0")
		(company "Antmicro")
	)
	(layers
		(0 "F.Cu" signal)
		(4 "In1.Cu" power)
		(6 "In2.Cu" mixed)
		(8 "In3.Cu" power)
		(10 "In4.Cu" mixed)
		(12 "In5.Cu" power)
		(14 "In6.Cu" mixed)
		(16 "In7.Cu" power)
		(18 "In8.Cu" power)
		(20 "In9.Cu" mixed)
		(22 "In10.Cu" power)
		(2 "B.Cu" signal)
		(9 "F.Adhes" user "F.Adhesive")
		(11 "B.Adhes" user "B.Adhesive")
		(13 "F.Paste" user)
		(15 "B.Paste" user)
		(5 "F.SilkS" user "F.Silkscreen")
		(7 "B.SilkS" user "B.Silkscreen")
		(1 "F.Mask" user)
		(3 "B.Mask" user)
		(17 "Dwgs.User" user "User.Drawings")
		(19 "Cmts.User" user "User.Comments")
		(21 "Eco1.User" user "User.Eco1")
		(23 "Eco2.User" user "User.Eco2")
		(25 "Edge.Cuts" user)
		(27 "Margin" user)
		(31 "F.CrtYd" user "F.Courtyard")
		(29 "B.CrtYd" user "B.Courtyard")
		(35 "F.Fab" user)
		(33 "B.Fab" user)
	)
	(setup
		(stackup
			(layer "F.SilkS"
				(type "Top Silk Screen")
				(color "White")
			)
			(layer "F.Paste"
				(type "Top Solder Paste")
			)
			(layer "F.Mask"
				(type "Top Solder Mask")
				(color "Black")
				(thickness 0.01)
			)
			(layer "F.Cu"
				(type "copper")
				(thickness 0.035)
			)
			(layer "dielectric 1"
				(type "prepreg")
				(thickness 0.07)
				(material "PR1080")
				(epsilon_r 3.92)
				(loss_tangent 0.021) addsublayer
				(thickness 0.07)
				(material "PR1080")
				(epsilon_r 3.92)
				(loss_tangent 0.021)
			)
			(layer "In1.Cu"
				(type "copper")
				(thickness 0.018)
			)
			(layer "dielectric 2"
				(type "core")
				(thickness 0.1)
				(material "Isola 370HR")
				(epsilon_r 4.04)
				(loss_tangent 0.021)
			)
			(layer "In2.Cu"
				(type "copper")
				(thickness 0.018)
			)
			(layer "dielectric 3"
				(type "prepreg")
				(thickness 0.07)
				(material "PR1080")
				(epsilon_r 3.92)
				(loss_tangent 0.021) addsublayer
				(thickness 0.07)
				(material "PR1080")
				(epsilon_r 3.92)
				(loss_tangent 0.021)
			)
			(layer "In3.Cu"
				(type "copper")
				(thickness 0.018)
			)
			(layer "dielectric 4"
				(type "core")
				(thickness 0.1)
				(material "Isola 370HR")
				(epsilon_r 4.04)
				(loss_tangent 0.021)
			)
			(layer "In4.Cu"
				(type "copper")
				(thickness 0.018)
			)
			(layer "dielectric 5"
				(type "prepreg")
				(thickness 0.07)
				(material "PR1080")
				(epsilon_r 3.92)
				(loss_tangent 0.021) addsublayer
				(thickness 0.07)
				(material "PR1080")
				(epsilon_r 3.92)
				(loss_tangent 0.021)
			)
			(layer "In5.Cu"
				(type "copper")
				(thickness 0.018)
			)
			(layer "dielectric 6"
				(type "core")
				(thickness 0.1)
				(material "Isola 370HR")
				(epsilon_r 4.04)
				(loss_tangent 0.021)
			)
			(layer "In6.Cu"
				(type "copper")
				(thickness 0.018)
			)
			(layer "dielectric 7"
				(type "prepreg")
				(thickness 0.07)
				(material "PR1080")
				(epsilon_r 3.92)
				(loss_tangent 0.021) addsublayer
				(thickness 0.07)
				(material "PR1080")
				(epsilon_r 3.92)
				(loss_tangent 0.021)
			)
			(layer "In7.Cu"
				(type "copper")
				(thickness 0.018)
			)
			(layer "dielectric 8"
				(type "core")
				(thickness 0.1)
				(material "Isola 370HR")
				(epsilon_r 4.04)
				(loss_tangent 0.021)
			)
			(layer "In8.Cu"
				(type "copper")
				(thickness 0.018)
			)
			(layer "dielectric 9"
				(type "prepreg")
				(thickness 0.07)
				(material "PR1080")
				(epsilon_r 3.92)
				(loss_tangent 0.021) addsublayer
				(thickness 0.07)
				(material "PR1080")
				(epsilon_r 3.92)
				(loss_tangent 0.021)
			)
			(layer "In9.Cu"
				(type "copper")
				(thickness 0.018)
			)
			(layer "dielectric 10"
				(type "core")
				(thickness 0.1)
				(material "Isola 370HR")
				(epsilon_r 4.04)
				(loss_tangent 0.021)
			)
			(layer "In10.Cu"
				(type "copper")
				(thickness 0.018)
			)
			(layer "dielectric 11"
				(type "prepreg")
				(thickness 0.07)
				(material "PR1080")
				(epsilon_r 3.92)
				(loss_tangent 0.021) addsublayer
				(thickness 0.07)
				(material "PR1080")
				(epsilon_r 3.92)
				(loss_tangent 0.021)
			)
			(layer "B.Cu"
				(type "copper")
				(thickness 0.035)
			)
			(layer "B.Mask"
				(type "Bottom Solder Mask")
				(color "Black")
				(thickness 0.01)
			)
			(layer "B.Paste"
				(type "Bottom Solder Paste")
			)
			(layer "B.SilkS"
				(type "Bottom Silk Screen")
				(color "White")
			)
			(copper_finish "ENIG")
			(dielectric_constraints no)
			(edge_connector bevelled)
		)
		(pad_to_mask_clearance 0)
		(allow_soldermask_bridges_in_footprints no)
		(tenting front back)
		(aux_axis_origin 251.9 83.2)
		(pcbplotparams
			(layerselection 0x00000000_00000000_55555555_57000001)
			(plot_on_all_layers_selection 0x00000000_00000000_00000000_00000000)
			(disableapertmacros no)
			(usegerberextensions no)
			(usegerberattributes no)
			(usegerberadvancedattributes no)
			(creategerberjobfile no)
			(dashed_line_dash_ratio 12.000000)
			(dashed_line_gap_ratio 3.000000)
			(svgprecision 6)
			(plotframeref no)
			(mode 1)
			(useauxorigin no)
			(hpglpennumber 1)
			(hpglpenspeed 20)
			(hpglpendiameter 15.000000)
			(pdf_front_fp_property_popups yes)
			(pdf_back_fp_property_popups yes)
			(pdf_metadata yes)
			(pdf_single_document no)
			(dxfpolygonmode yes)
			(dxfimperialunits yes)
			(dxfusepcbnewfont yes)
			(psnegative no)
			(psa4output no)
			(plot_black_and_white yes)
			(sketchpadsonfab no)
			(plotpadnumbers no)
			(hidednponfab no)
			(sketchdnponfab yes)
			(crossoutdnponfab yes)
			(subtractmaskfromsilk no)
			(outputformat 1)
			(mirror no)
			(drillshape 0)
			(scaleselection 1)
			(outputdirectory "./fab")
		)
	)
	(net 0 "")
	(net 1 "GND")
	(net 2 "/Debug FTDI + VNA/VBUS")
	(net 3 "/Debug FTDI + VNA/FTDI_VPLL")
	(net 4 "/Debug FTDI + VNA/FTDI_XI")
	(net 5 "/Debug FTDI + VNA/FTDI_VPHY")
	(net 6 "/Debug FTDI + VNA/FTDI_3V3")
	(net 7 "/Debug FTDI + VNA/FTDI_XO")
	(net 8 "/HDMI + SD Card/HDMI_CONN_5V")
	(net 9 "/Supply/DC-DC AUX, MGT/QDCDC1_VCC")
	(net 10 "+12V")
	(net 11 "/FPGA MGT Interface/PCIE.CLK_P")
	(net 12 "/FPGA MGT Interface/GTR_REFCLK0_P")
	(net 13 "/FPGA MGT Interface/PCIE.CLK_N")
	(net 14 "/FPGA MGT Interface/GTR_REFCLK0_N")
	(net 15 "/FPGA MGT Interface/PCIE.TXD3_P")
	(net 16 "/FPGA MGT Interface/GTY_225_TX0_P")
	(net 17 "/FPGA MGT Interface/PCIE.TXD2_P")
	(net 18 "/FPGA MGT Interface/GTY_225_TX1_P")
	(net 19 "/FPGA MGT Interface/PCIE.TXD1_P")
	(net 20 "/FPGA MGT Interface/GTY_225_TX2_P")
	(net 21 "/FPGA MGT Interface/PCIE.TXD0_P")
	(net 22 "/FPGA MGT Interface/GTY_225_TX3_P")
	(net 23 "/FPGA MGT Interface/PCIE.TXD3_N")
	(net 24 "/FPGA MGT Interface/GTY_225_TX0_N")
	(net 25 "/FPGA MGT Interface/PCIE.TXD2_N")
	(net 26 "/FPGA MGT Interface/GTY_225_TX1_N")
	(net 27 "/FPGA MGT Interface/PCIE.TXD0_N")
	(net 28 "/FPGA MGT Interface/GTY_225_TX3_N")
	(net 29 "/FPGA MGT Interface/GTY_225_TX2_N")
	(net 30 "/FPGA MGT Interface/PCIE.TXD1_N")
	(net 31 "Net-(C234-Pad1)")
	(net 32 "Net-(D4-A)")
	(net 33 "/HDMI + SD Card/HDMI_5V")
	(net 34 "/Debug FTDI + VNA/FTDI_VCORE")
	(net 35 "VDC")
	(net 36 "/Supply/DC-DC IO/QDCDC2_VCC")
	(net 37 "/Supply/DC-DC AUX, MGT/1V8_local")
	(net 38 "+3V3_AON")
	(net 39 "Net-(D10-A)")
	(net 40 "/FPGA Config/PUDC_B")
	(net 41 "Net-(D11-A)")
	(net 42 "Net-(D12-A)")
	(net 43 "Net-(D13-A)")
	(net 44 "/Debug FTDI + VNA/FTDI_SDA_OUT")
	(net 45 "/Supply/DC-DC IO/3V3_local")
	(net 46 "/Supply/DC-DC IO/5V_local")
	(net 47 "/Supply/DC-DC AUX, MGT/MGTAVCC_local")
	(net 48 "/Supply/DC-DC AUX, MGT/MGTAVTT_local")
	(net 49 "Net-(U36-V_{DRV})")
	(net 50 "/Supply/SEQ_EN")
	(net 51 "/DDR5 RDIMM/A.DQ0")
	(net 52 "/DDR5 RDIMM/A.DQ1")
	(net 53 "/DDR5 RDIMM/A.DQ4")
	(net 54 "/DDR5 RDIMM/A.DQ5")
	(net 55 "/DDR5 RDIMM/A.DQ8")
	(net 56 "/DDR5 RDIMM/A.DQ9")
	(net 57 "/DDR5 RDIMM/A.DQ12")
	(net 58 "/DDR5 RDIMM/A.DQ13")
	(net 59 "/DDR5 RDIMM/A.DQ16")
	(net 60 "/DDR5 RDIMM/A.DQ17")
	(net 61 "/DDR5 RDIMM/A.DQ20")
	(net 62 "/DDR5 RDIMM/A.DQ21")
	(net 63 "/DDR5 RDIMM/A.DQ24")
	(net 64 "/DDR5 RDIMM/A.DQ25")
	(net 65 "/DDR5 RDIMM/A.DQ28")
	(net 66 "/DDR5 RDIMM/A.DQ29")
	(net 67 "/DDR5 RDIMM/A.CB0")
	(net 68 "/DDR5 RDIMM/A.CB1")
	(net 69 "HOT_SWAP_BUTTON")
	(net 70 "/DDR5 RDIMM/A.CB4")
	(net 71 "/DDR5 RDIMM/A.CB5")
	(net 72 "/DDR5 RDIMM/CTRL.~{ALERT}")
	(net 73 "/DDR5 RDIMM/A.CS0_c")
	(net 74 "/DDR5 RDIMM/A.CA0")
	(net 75 "/DDR5 RDIMM/A.CA2")
	(net 76 "/DDR5 RDIMM/A.CA4")
	(net 77 "/DDR5 RDIMM/A.CA6")
	(net 78 "/DDR5 RDIMM/A.PAR")
	(net 79 "/DDR5 RDIMM/B.CA0")
	(net 80 "/DDR5 RDIMM/B.CA1")
	(net 81 "/DDR5 RDIMM/B.CA4")
	(net 82 "/DDR5 RDIMM/B.CA6")
	(net 83 "/DDR5 RDIMM/B.CS0_c")
	(net 84 "/DDR5 RDIMM/CTRL.DLBDQ")
	(net 85 "/DDR5 RDIMM/CTRL.DLBDQS")
	(net 86 "/Ethernet/ETH3_P")
	(net 87 "/Ethernet/ETH2_P")
	(net 88 "/Ethernet/ETH1_P")
	(net 89 "/Ethernet/ETH4_P")
	(net 90 "/Ethernet/ETH2_N")
	(net 91 "/Ethernet/ETH1_N")
	(net 92 "/Ethernet/ETH3_N")
	(net 93 "/Ethernet/ETH4_N")
	(net 94 "/DDR5 RDIMM/A.DQS0_P")
	(net 95 "/Ethernet/AVDDL")
	(net 96 "/Ethernet/AVDDL_PLL")
	(net 97 "/Ethernet/AVDDH")
	(net 98 "PCIE.PWRGD")
	(net 99 "/DDR5 RDIMM/B.CB4")
	(net 100 "/DDR5 RDIMM/B.CB5")
	(net 101 "/DDR5 RDIMM/A.DQS0_N")
	(net 102 "/DDR5 RDIMM/A.DQS1_P")
	(net 103 "/DDR5 RDIMM/B.CB0")
	(net 104 "/DDR5 RDIMM/A.DQS1_N")
	(net 105 "/DDR5 RDIMM/B.CB1")
	(net 106 "/DDR5 RDIMM/B.DQ0")
	(net 107 "/DDR5 RDIMM/B.DQ1")
	(net 108 "/DDR5 RDIMM/A.DQS2_P")
	(net 109 "/DDR5 RDIMM/A.DQS2_N")
	(net 110 "/DDR5 RDIMM/B.DQ4")
	(net 111 "/DDR5 RDIMM/B.DQ5")
	(net 112 "/DDR5 RDIMM/B.DQ8")
	(net 113 "/DDR5 RDIMM/B.DQ9")
	(net 114 "/DDR5 RDIMM/A.DQS3_P")
	(net 115 "/DDR5 RDIMM/A.DQS3_N")
	(net 116 "/DDR5 RDIMM/B.DQ12")
	(net 117 "/DDR5 RDIMM/B.DQ13")
	(net 118 "/DDR5 RDIMM/B.DQ16")
	(net 119 "/DDR5 RDIMM/B.DQ17")
	(net 120 "/DDR5 RDIMM/A.DQS4_P")
	(net 121 "/DDR5 RDIMM/A.DQS4_N")
	(net 122 "/DDR5 RDIMM/B.DQ20")
	(net 123 "/DDR5 RDIMM/B.DQ21")
	(net 124 "/DDR5 RDIMM/B.DQ24")
	(net 125 "/DDR5 RDIMM/B.DQ25")
	(net 126 "/DDR5 RDIMM/B.DQS9_P")
	(net 127 "/DDR5 RDIMM/B.DQS9_N")
	(net 128 "/DDR5 RDIMM/B.DQ28")
	(net 129 "/DDR5 RDIMM/B.DQ29")
	(net 130 "/DDR5 RDIMM/A.DQ2")
	(net 131 "/DDR5 RDIMM/A.DQ3")
	(net 132 "/DDR5 RDIMM/B.DQS0_P")
	(net 133 "/DDR5 RDIMM/B.DQS0_N")
	(net 134 "/DDR5 RDIMM/A.DQ6")
	(net 135 "/DDR5 RDIMM/A.DQ7")
	(net 136 "/DDR5 RDIMM/A.DQ10")
	(net 137 "/Supply/~{PB_CTRL_CLR}")
	(net 138 "/Supply/PB_CTRL_OUT")
	(net 139 "/Debug FTDI + VNA/FTDI_SDA_IN")
	(net 140 "/DDR5 RDIMM/A.DQ11")
	(net 141 "/DDR5 RDIMM/B.DQS1_P")
	(net 142 "/DDR5 RDIMM/B.DQS1_N")
	(net 143 "/DDR5 RDIMM/A.DQ14")
	(net 144 "/DDR5 RDIMM/A.DQ15")
	(net 145 "/DDR5 RDIMM/A.DQ18")
	(net 146 "/DDR5 RDIMM/A.DQ19")
	(net 147 "/DDR5 RDIMM/B.DQS2_P")
	(net 148 "/DDR5 RDIMM/B.DQS2_N")
	(net 149 "/DDR5 RDIMM/A.DQ22")
	(net 150 "+1V2")
	(net 151 "+3V3")
	(net 152 "+5V")
	(net 153 "/DDR5 RDIMM/A.DQ23")
	(net 154 "/DDR5 RDIMM/A.DQ26")
	(net 155 "/DDR5 RDIMM/A.DQ27")
	(net 156 "/DDR5 RDIMM/B.DQS3_P")
	(net 157 "/Supply/~{PB_CTRL_INT}")
	(net 158 "/Supply/DC-DC IO/VDDQ_local")
	(net 159 "/Supply/DC-DC IO/1V2_local")
	(net 160 "Net-(U30-OUT)")
	(net 161 "/DDR5 RDIMM/B.DQS3_N")
	(net 162 "/DDR5 RDIMM/A.DQ30")
	(net 163 "/Supply/DC-DC VCCINT/V_{CC}")
	(net 164 "Net-(U4-BST)")
	(net 165 "Net-(C215-Pad2)")
	(net 166 "/DDR5 RDIMM/A.DQ31")
	(net 167 "Net-(U36-BST)")
	(net 168 "/Supply/EN1")
	(net 169 "/Supply/EN2")
	(net 170 "/Supply/EN3")
	(net 171 "/DDR5 RDIMM/A.CB2")
	(net 172 "+1V2_MGTAVTT")
	(net 173 "/DDR5 RDIMM/A.CB3")
	(net 174 "/PCIe connector/PRSNT#1")
	(net 175 "/PCIe connector/x1")
	(net 176 "/PCIe connector/x4")
	(net 177 "/DDR5 RDIMM/A.DQS5_N")
	(net 178 "/DDR5 RDIMM/A.DQS5_P")
	(net 179 "HOT_SWAP_YELLOW")
	(net 180 "HOT_SWAP_GREEN")
	(net 181 "/DDR5 RDIMM/A.DQS6_N")
	(net 182 "/DDR5 RDIMM/A.DQS6_P")
	(net 183 "POWER")
	(net 184 "FPGA_POWER_CYCLE")
	(net 185 "FPGA_POWER_OFF")
	(net 186 "/DDR5 RDIMM/A.CB6")
	(net 187 "/DDR5 RDIMM/A.CB7")
	(net 188 "Net-(C132-Pad1)")
	(net 189 "/Supply/~{PB_CTRL_IN}")
	(net 190 "/DDR5 RDIMM/CTRL.~{RESET}")
	(net 191 "/DDR5 RDIMM/A.CS1_c")
	(net 192 "/DDR5 RDIMM/A.CA1")
	(net 193 "/DDR5 RDIMM/A.CA3")
	(net 194 "/DDR5 RDIMM/A.CA5")
	(net 195 "unconnected-(J2B-RFU-Pad231)")
	(net 196 "unconnected-(J2B-RFU-Pad232)")
	(net 197 "FTDI_DIS")
	(net 198 "/DDR5 RDIMM/B.CA2")
	(net 199 "/DDR5 RDIMM/B.CA3")
	(net 200 "/DDR5 RDIMM/B.CA5")
	(net 201 "VDDSPD")
	(net 202 "/DDR5 RDIMM/B.PAR")
	(net 203 "/DDR5 RDIMM/B.CS1_c")
	(net 204 "/DDR5 RDIMM/B.CB6")
	(net 205 "/DDR5 RDIMM/B.CB7")
	(net 206 "FAN_PWM")
	(net 207 "Net-(C216-Pad2)")
	(net 208 "/DDR5 RDIMM/A.DQS7_N")
	(net 209 "/DDR5 RDIMM/A.DQS7_P")
	(net 210 "/DDR5 RDIMM/B.CB2")
	(net 211 "/DDR5 RDIMM/B.CB3")
	(net 212 "/DDR5 RDIMM/B.DQ2")
	(net 213 "/DDR5 RDIMM/B.DQ3")
	(net 214 "/DDR5 RDIMM/A.DQS8_N")
	(net 215 "/Supply/QDCDC2_SCL")
	(net 216 "/DDR5 RDIMM/A.DQS8_P")
	(net 217 "/DDR5 RDIMM/B.DQ6")
	(net 218 "/DDR5 RDIMM/B.DQ7")
	(net 219 "/DDR5 RDIMM/B.DQ10")
	(net 220 "Net-(D17-C)")
	(net 221 "Net-(D20-C_{R})")
	(net 222 "Net-(U4-V_{DRV})")
	(net 223 "/Supply/DC-DC VCCINT/0V85_REG0")
	(net 224 "/Supply/DC-DC VCCINT/0V85_REG1")
	(net 225 "/Supply/DC-DC AUX, MGT/MGTAVCCAUX_local")
	(net 226 "/Supply/DC-DC VCCINT/V_{0SNS+}")
	(net 227 "Net-(U15-XI)")
	(net 228 "Net-(U15-XO)")
	(net 229 "/DDR5 RDIMM/B.DQ11")
	(net 230 "Net-(D5-A)")
	(net 231 "Net-(D6-A)")
	(net 232 "Net-(D7-A)")
	(net 233 "Net-(D8-A)")
	(net 234 "/DDR5 RDIMM/A.DQS9_N")
	(net 235 "/DDR5 RDIMM/A.DQS9_P")
	(net 236 "Net-(D20-C_{G})")
	(net 237 "Net-(D20-C_{Y})")
	(net 238 "/Debug FTDI + VNA/JTAG.TMS")
	(net 239 "/Debug FTDI + VNA/JTAG.TCK")
	(net 240 "unconnected-(J1-Pad12)")
	(net 241 "unconnected-(J1-Pad14)")
	(net 242 "/Debug FTDI + VNA/JTAG.TDO")
	(net 243 "unconnected-(J3-SBU_{1}-PadA8)")
	(net 244 "/Debug FTDI + VNA/JTAG.TDI")
	(net 245 "unconnected-(J3-SBU_{2}-PadB8)")
	(net 246 "/FPGA MGT Interface/HDMI_OUT.D0_P")
	(net 247 "unconnected-(J4-UTILITY{slash}HEAC+-Pad14)")
	(net 248 "/FPGA MGT Interface/HDMI_OUT.D0_N")
	(net 249 "Net-(J5-CD_SW1)")
	(net 250 "Net-(Q15-D)")
	(net 251 "unconnected-(J8-Pad3)")
	(net 252 "/FPGA MGT Interface/PCIE.TXD5_N")
	(net 253 "/FPGA MGT Interface/PCIE.TXD7_P")
	(net 254 "/FPGA MGT Interface/PCIE.TXD7_N")
	(net 255 "/FPGA MGT Interface/PCIE.TXD6_P")
	(net 256 "/FPGA MGT Interface/PCIE.TXD6_N")
	(net 257 "/FPGA MGT Interface/PCIE.TXD5_P")
	(net 258 "/FPGA MGT Interface/PCIE.TXD4_P")
	(net 259 "/FPGA MGT Interface/PCIE.TXD4_N")
	(net 260 "unconnected-(J10-TCK-PadA5)")
	(net 261 "unconnected-(J10-TDI-PadA6)")
	(net 262 "unconnected-(J10-TDO-PadA7)")
	(net 263 "unconnected-(J10-TMS-PadA8)")
	(net 264 "unconnected-(J10-3V3-PadA10)")
	(net 265 "unconnected-(J10-NC-PadA19)")
	(net 266 "Net-(Q1-D)")
	(net 267 "/FPGA MGT Interface/HDMI_OUT.D1_P")
	(net 268 "/FPGA MGT Interface/HDMI_IN_CLK_C_P")
	(net 269 "/FPGA MGT Interface/HDMI_IN.CLK_P")
	(net 270 "Net-(Q2-D)")
	(net 271 "Net-(Q3-D)")
	(net 272 "Net-(Q4-D)")
	(net 273 "Net-(Q5-D)")
	(net 274 "Net-(Q6-D)")
	(net 275 "Net-(Q7-D)")
	(net 276 "Net-(Q8-D)")
	(net 277 "Net-(Q9-D)")
	(net 278 "Net-(Q10-D)")
	(net 279 "/HyperRAM + QSPI Flash/IO3")
	(net 280 "/HyperRAM + QSPI Flash/IO2")
	(net 281 "/HyperRAM + QSPI Flash/IO0")
	(net 282 "/HyperRAM + QSPI Flash/IO1")
	(net 283 "Net-(Q11-D)")
	(net 284 "Net-(Q12-G)")
	(net 285 "Net-(Q13-G)")
	(net 286 "Net-(Q16-D)")
	(net 287 "Net-(Q17-G)")
	(net 288 "Net-(U34L-MGTRREF_R)")
	(net 289 "Net-(U6-~{RESET})")
	(net 290 "/FPGA MGT Interface/HDMI_OUT.D1_N")
	(net 291 "/FPGA MGT Interface/HDMI_IN_CLK_C_N")
	(net 292 "/FPGA MGT Interface/HDMI_IN.CLK_N")
	(net 293 "Net-(U6-REF)")
	(net 294 "/FPGA MGT Interface/HDMI_OUT.D2_P")
	(net 295 "/FPGA MGT Interface/HDMI_OUT.D2_N")
	(net 296 "Net-(U7-B1Y)")
	(net 297 "/HDMI + SD Card/HDMI_IN_5V")
	(net 298 "Net-(U7-B2Y)")
	(net 299 "Net-(U7-B3Y)")
	(net 300 "Net-(U7-B4)")
	(net 301 "Net-(U13-OE)")
	(net 302 "Net-(U15-ISET)")
	(net 303 "unconnected-(U1-NC-PadA2)")
	(net 304 "unconnected-(U1-NC-PadA5)")
	(net 305 "unconnected-(U1-NC-PadB5)")
	(net 306 "unconnected-(U1-NC-PadC2)")
	(net 307 "unconnected-(U1-NC-PadC5)")
	(net 308 "unconnected-(J2B-RFU-Pad2)")
	(net 309 "unconnected-(J2B-RFU-Pad144)")
	(net 310 "unconnected-(J2B-RFU-Pad149)")
	(net 311 "unconnected-(U5-NC-Pad4)")
	(net 312 "unconnected-(U6-ADBUS4-Pad17)")
	(net 313 "unconnected-(U6-ADBUS6-Pad19)")
	(net 314 "unconnected-(U6-ADBUS7-Pad20)")
	(net 315 "unconnected-(U6-BDBUS4-Pad26)")
	(net 316 "unconnected-(U6-BDBUS6-Pad28)")
	(net 317 "unconnected-(U6-BDBUS7-Pad29)")
	(net 318 "unconnected-(U6-~{SUSPEND}-Pad30)")
	(net 319 "unconnected-(U6-CDBUS2-Pad34)")
	(net 320 "unconnected-(U6-CDBUS3-Pad35)")
	(net 321 "Net-(C133-Pad1)")
	(net 322 "Net-(C300-Pad2)")
	(net 323 "/Supply/12V_aux_fused")
	(net 324 "/Supply/12V_PCIE_fused")
	(net 325 "/Supply/12V_aux")
	(net 326 "unconnected-(U6-CDBUS4-Pad37)")
	(net 327 "unconnected-(U6-CDBUS5-Pad38)")
	(net 328 "unconnected-(U6-CDBUS6-Pad39)")
	(net 329 "unconnected-(U6-CDBUS7-Pad40)")
	(net 330 "/Ethernet/LED_SPD")
	(net 331 "/Ethernet/LED_LINK")
	(net 332 "/FPGA MGT Interface/PCIE.RXD0_P")
	(net 333 "/FPGA MGT Interface/PCIE.RXD0_N")
	(net 334 "/FPGA MGT Interface/PCIE.RXD1_P")
	(net 335 "/FPGA MGT Interface/PCIE.RXD1_N")
	(net 336 "/FPGA MGT Interface/PCIE.RXD2_P")
	(net 337 "/FPGA MGT Interface/PCIE.RXD2_N")
	(net 338 "/FPGA MGT Interface/PCIE.RXD3_P")
	(net 339 "/FPGA MGT Interface/PCIE.RXD3_N")
	(net 340 "/FPGA Config/DONE")
	(net 341 "/FPGA Config/INIT_B")
	(net 342 "/FPGA MGT Interface/HDMI_IN.D2_N")
	(net 343 "unconnected-(U6-DDBUS2-Pad47)")
	(net 344 "/FPGA MGT Interface/HDMI_IN.D2_P")
	(net 345 "unconnected-(U6-DDBUS3-Pad48)")
	(net 346 "/FPGA MGT Interface/HDMI_IN.D1_N")
	(net 347 "unconnected-(U6-DDBUS4-Pad49)")
	(net 348 "/FPGA MGT Interface/HDMI_IN.D1_P")
	(net 349 "/FPGA MGT Interface/HDMI_IN.D0_N")
	(net 350 "/FPGA Config/FLASH.~{CS}")
	(net 351 "/FPGA Config/FLASH.IO0")
	(net 352 "/FPGA Config/FLASH.IO1")
	(net 353 "/FPGA Config/FLASH.IO2")
	(net 354 "/FPGA Config/FLASH.IO3")
	(net 355 "/FPGA Config/FLASH.SCK")
	(net 356 "/FPGA Config/MODE0")
	(net 357 "/FPGA Config/PROGRAM_B")
	(net 358 "/DDR5 RDIMM/B.DQ14")
	(net 359 "/DDR5 RDIMM/B.DQ15")
	(net 360 "/DDR5 RDIMM/B.DQ18")
	(net 361 "unconnected-(J2B-RFU-Pad150)")
	(net 362 "unconnected-(J2B-RFU-Pad220)")
	(net 363 "/Debug FTDI + VNA/CC1")
	(net 364 "/Debug FTDI + VNA/DBG_USB_P")
	(net 365 "/Debug FTDI + VNA/DBG_USB_N")
	(net 366 "/Debug FTDI + VNA/CC2")
	(net 367 "unconnected-(J9-Pad1)")
	(net 368 "/I^{2}C + I3C/I3C_EXT.SDA")
	(net 369 "/I^{2}C + I3C/I3C_EXT.SCL")
	(net 370 "Net-(J14-Pad1)")
	(net 371 "Net-(J15-Pad1)")
	(net 372 "/Debug FTDI + VNA/FTDI_PWREN")
	(net 373 "Net-(U16-B1)")
	(net 374 "/Debug FTDI + VNA/UART0.TX")
	(net 375 "Net-(U16-B2)")
	(net 376 "/Debug FTDI + VNA/UART0.RX")
	(net 377 "/Debug FTDI + VNA/UART1.TX")
	(net 378 "/Debug FTDI + VNA/UART1.RX")
	(net 379 "/Debug FTDI + VNA/BDBUS0")
	(net 380 "/FPGA MGT Interface/HDMI_IN.D0_P")
	(net 381 "/FPGA MGT Interface/HDMI_OUT.CLK_P")
	(net 382 "/FPGA MGT Interface/HDMI_FPGA.TX_CLK_P")
	(net 383 "/FPGA MGT Interface/HDMI_OUT.CLK_N")
	(net 384 "/FPGA MGT Interface/HDMI_FPGA.TX_CLK_N")
	(net 385 "HDMI_OE")
	(net 386 "/FPGA MGT Interface/HDMI_SI5319_C_CLK_N")
	(net 387 "/FPGA MGT Interface/HDMI_SI5319_CLK_N")
	(net 388 "/Debug FTDI + VNA/AUX.TCK")
	(net 389 "/FPGA MGT Interface/HDMI_SI5319_C_CLK_P")
	(net 390 "/Debug FTDI + VNA/BDBUS1")
	(net 391 "/Debug FTDI + VNA/AUX.TDI")
	(net 392 "/Debug FTDI + VNA/BDBUS2")
	(net 393 "/Ethernet/ETH.RXD0")
	(net 394 "/Ethernet/ETH.RXD1")
	(net 395 "/Ethernet/ETH.RXD2")
	(net 396 "/Ethernet/ETH.RXD3")
	(net 397 "/Ethernet/ETH.RX_CTL")
	(net 398 "/Ethernet/ETH.RXC")
	(net 399 "/Ethernet/ETH.REF_CLK")
	(net 400 "/Ethernet/ETH.MDIO")
	(net 401 "/Ethernet/ETH.~{RESET}")
	(net 402 "/FPGA MGT Interface/HDMI_SI5319_CLK_P")
	(net 403 "HDMI_REC_CLK_P")
	(net 404 "IN1")
	(net 405 "IN2")
	(net 406 "/Debug FTDI + VNA/AUX.TDO")
	(net 407 "/Debug FTDI + VNA/BDBUS3")
	(net 408 "/Debug FTDI + VNA/AUX.TMS")
	(net 409 "/Ethernet/ETH.TXC")
	(net 410 "/Ethernet/ETH.MDC")
	(net 411 "unconnected-(U6-DDBUS5-Pad51)")
	(net 412 "unconnected-(U6-DDBUS6-Pad52)")
	(net 413 "unconnected-(U6-DDBUS7-Pad53)")
	(net 414 "unconnected-(U7-NC-Pad6)")
	(net 415 "unconnected-(U7-NC-Pad9)")
	(net 416 "unconnected-(U9-QB-Pad1)")
	(net 417 "unconnected-(U9-QC-Pad2)")
	(net 418 "unconnected-(U9-QD-Pad3)")
	(net 419 "unconnected-(U9-QH'-Pad9)")
	(net 420 "unconnected-(U9-QA-Pad15)")
	(net 421 "unconnected-(U9-EP-Pad17)")
	(net 422 "unconnected-(U13-NC-Pad6)")
	(net 423 "unconnected-(U13-NC-Pad9)")
	(net 424 "unconnected-(U13-B2Y-Pad12)")
	(net 425 "unconnected-(U15-NC-Pad13)")
	(net 426 "unconnected-(U15-LDO_O-Pad43)")
	(net 427 "unconnected-(U15-NC-Pad47)")
	(net 428 "unconnected-(U17-STAT-Pad4)")
	(net 429 "unconnected-(U18-STAT-Pad4)")
	(net 430 "unconnected-(U19-SW2-Pad11)")
	(net 431 "unconnected-(U19-SW1-Pad12)")
	(net 432 "unconnected-(U20-SW2-Pad11)")
	(net 433 "unconnected-(U20-SW1-Pad12)")
	(net 434 "unconnected-(U21-NC-Pad4)")
	(net 435 "/Ethernet/ETH.TX_CTL")
	(net 436 "/Ethernet/ETH.TXD0")
	(net 437 "/Ethernet/ETH.~{INT}")
	(net 438 "/Ethernet/ETH.TXD3")
	(net 439 "/Ethernet/ETH.TXD2")
	(net 440 "/Ethernet/ETH.TXD1")
	(net 441 "/Debug FTDI + VNA/I2C_EN")
	(net 442 "/Debug FTDI + VNA/AUX.RST")
	(net 443 "/Debug FTDI + VNA/LED_TX0")
	(net 444 "/Debug FTDI + VNA/LED_RX0")
	(net 445 "/Debug FTDI + VNA/LED_TX1")
	(net 446 "/Debug FTDI + VNA/LED_RX1")
	(net 447 "/Debug FTDI + VNA/FTDI_SCL")
	(net 448 "Net-(U32-B1)")
	(net 449 "Net-(U32-B2)")
	(net 450 "/DDR5 RDIMM/B.DQ19")
	(net 451 "/DDR5 RDIMM/B.DQS4_N")
	(net 452 "/DDR5 RDIMM/B.DQS4_P")
	(net 453 "/DDR5 RDIMM/B.DQ22")
	(net 454 "/DDR5 RDIMM/B.DQ23")
	(net 455 "/DDR5 RDIMM/B.DQ26")
	(net 456 "/DDR5 RDIMM/B.DQ27")
	(net 457 "/DDR5 RDIMM/B.DQS5_N")
	(net 458 "HDMI_REC_CLK_N")
	(net 459 "/DDR5 RDIMM/DDR.SDA")
	(net 460 "/DDR5 RDIMM/DDR.SCL")
	(net 461 "/DDR5 RDIMM/HSA")
	(net 462 "/FPGA Config/POR_OVERRIDE")
	(net 463 "unconnected-(U34L-NC-PadA3)")
	(net 464 "unconnected-(U34L-NC-PadA4)")
	(net 465 "/FPGA banks HD/FPGA_DDR.SCL")
	(net 466 "unconnected-(U34F-IO_L5N_HDGC_AD7N_84-PadAC14)")
	(net 467 "/HDMI + SD Card/HDMI_OUT_C.SCL")
	(net 468 "/HDMI + SD Card/HDMI_OUT_C.SDA")
	(net 469 "unconnected-(U34E-IO_L19N_T3L_N1_DBC_AD9N_67-PadA23)")
	(net 470 "/FPGA MGT Interface/GTY_224_TX2_N")
	(net 471 "unconnected-(U34F-IO_L11N_AD1N_84-PadAA13)")
	(net 472 "/FPGA banks HD/FPGA_DDR.SDA")
	(net 473 "Net-(R126-Pad1)")
	(net 474 "/DDR5 RDIMM/B.DQS5_P")
	(net 475 "/DDR5 RDIMM/B.DQ30")
	(net 476 "/DDR5 RDIMM/B.DQ31")
	(net 477 "/FPGA Config/~{ALARM}")
	(net 478 "unconnected-(U34F-IO_L8N_HDGC_AD4N_84-PadAB14)")
	(net 479 "unconnected-(U34F-IO_L6P_HDGC_AD6P_84-PadAB15)")
	(net 480 "/HDMI + SD Card/HDMI_IN_5V.SDA")
	(net 481 "unconnected-(U34F-IO_L5P_HDGC_AD7P_84-PadAC13)")
	(net 482 "PG1")
	(net 483 "unconnected-(U34B-IO_T3U_N12_64-PadAC16)")
	(net 484 "PG2")
	(net 485 "PG3")
	(net 486 "Net-(R87-Pad1)")
	(net 487 "unconnected-(U34B-IO_T2U_N12_64-PadAE18)")
	(net 488 "/FPGA MGT Interface/HDMI_REC_CLK_C_P")
	(net 489 "/FPGA MGT Interface/HDMI_REC_CLK_C_N")
	(net 490 "unconnected-(J11-Pad1)")
	(net 491 "unconnected-(U34B-IO_T1U_N12_64-PadAF20)")
	(net 492 "unconnected-(U34L-NC-PadB1)")
	(net 493 "unconnected-(U34L-NC-PadB2)")
	(net 494 "unconnected-(U34L-NC-PadB6)")
	(net 495 "unconnected-(U34L-NC-PadB7)")
	(net 496 "unconnected-(J11-Pad7)")
	(net 497 "unconnected-(U34G-IO_L11P_AD1P_86-PadB10)")
	(net 498 "unconnected-(U34G-IO_L12N_AD0N_86-PadB11)")
	(net 499 "/HDMI + SD Card/HDMI_IN_5V.SCL")
	(net 500 "HDMI_IN_HPD")
	(net 501 "unconnected-(U34E-IO_L24N_T3U_N11_67-PadB22)")
	(net 502 "unconnected-(U34L-NC-PadC3)")
	(net 503 "unconnected-(U34L-NC-PadC4)")
	(net 504 "unconnected-(J11-Pad8)")
	(net 505 "unconnected-(U34G-IO_L12P_AD0P_86-PadC11)")
	(net 506 "Net-(Q18-G)")
	(net 507 "HDMI_IN_CD")
	(net 508 "unconnected-(U34E-IO_L13P_T2L_N0_GC_QBC_67-PadC18)")
	(net 509 "unconnected-(U34E-IO_L13N_T2L_N1_GC_QBC_67-PadC19)")
	(net 510 "unconnected-(U34L-NC-PadD1)")
	(net 511 "unconnected-(U34L-NC-PadD2)")
	(net 512 "unconnected-(U34L-NC-PadD6)")
	(net 513 "unconnected-(U34L-NC-PadD7)")
	(net 514 "unconnected-(U34G-IO_L8P_HDGC_AD4P_86-PadD11)")
	(net 515 "unconnected-(U34H-IO_L8N_HDGC_87-PadD13)")
	(net 516 "unconnected-(U34L-NC-PadE4)")
	(net 517 "unconnected-(U34L-NC-PadE5)")
	(net 518 "unconnected-(U34G-IO_L7N_HDGC_AD5N_86-PadE10)")
	(net 519 "unconnected-(U34G-IO_L7P_HDGC_AD5P_86-PadE11)")
	(net 520 "unconnected-(U34H-IO_L7N_HDGC_87-PadE12)")
	(net 521 "unconnected-(U34E-IO_T3U_N12_67-PadE22)")
	(net 522 "unconnected-(U34K-MGTYRXN3_226-PadF1)")
	(net 523 "unconnected-(U34K-MGTYRXP3_226-PadF2)")
	(net 524 "unconnected-(U34L-NC-PadF6)")
	(net 525 "unconnected-(U34L-NC-PadF7)")
	(net 526 "/Debug FTDI + VNA/FTDI.SCL")
	(net 527 "/Debug FTDI + VNA/FTDI.SDA")
	(net 528 "/FPGA banks HD/FPGA_I3C.SDA")
	(net 529 "unconnected-(U34D-IO_T3U_N12_66-PadF22)")
	(net 530 "Net-(U38-HPD_SNK)")
	(net 531 "~{SI_5319_RST}")
	(net 532 "unconnected-(U34G-IO_L4N_AD8N_86-PadG11)")
	(net 533 "/I^{2}C + I3C/PWR.SDA")
	(net 534 "Net-(U39-RATE0)")
	(net 535 "/FPGA banks HP/VREF_64")
	(net 536 "/FPGA banks HP/VREF_65")
	(net 537 "unconnected-(U34D-IO_T2U_N12_66-PadG22)")
	(net 538 "unconnected-(U34L-NC-PadH6)")
	(net 539 "unconnected-(U34L-NC-PadH7)")
	(net 540 "unconnected-(U34G-IO_L3N_AD9N_86-PadH9)")
	(net 541 "unconnected-(U34G-IO_L4P_AD8P_86-PadH11)")
	(net 542 "Net-(U39-RATE1)")
	(net 543 "/FPGA banks HP/GCLK_100_LVDS+")
	(net 544 "/FPGA banks HP/GCLK_100_LVDS-")
	(net 545 "/FPGA banks HP/VREF_66")
	(net 546 "/FPGA banks HP/VREF_67")
	(net 547 "/FPGA banks HP/VRP_64")
	(net 548 "/FPGA banks HP/VRP_65")
	(net 549 "HDMI_OUT_HPD")
	(net 550 "/FPGA banks HD/HDMI_IN_I2C.SCL")
	(net 551 "unconnected-(U34L-NC-PadK6)")
	(net 552 "unconnected-(U34L-NC-PadK7)")
	(net 553 "+0V85")
	(net 554 "/FPGA banks HD/HDMI_OUT_I2C.SCL")
	(net 555 "/FPGA banks HD/HDMI_IN_I2C.SDA")
	(net 556 "unconnected-(U34D-IO_T1U_N12_66-PadM24)")
	(net 557 "/FPGA MGT Interface/GTY_224_TX0_P")
	(net 558 "/FPGA MGT Interface/GTY_224_TX0_N")
	(net 559 "/FPGA MGT Interface/GTY_224_TX1_P")
	(net 560 "unconnected-(U34J-MGTREFCLK1N_225-PadT6)")
	(net 561 "unconnected-(U34J-MGTREFCLK1P_225-PadT7)")
	(net 562 "/FPGA MGT Interface/GTY_224_TX1_N")
	(net 563 "/FPGA MGT Interface/GTY_224_TX2_P")
	(net 564 "unconnected-(U34J-MGTREFCLK0N_225-PadV6)")
	(net 565 "unconnected-(U34J-MGTREFCLK0P_225-PadV7)")
	(net 566 "/FPGA MGT Interface/GTY_224_TX3_P")
	(net 567 "unconnected-(U34F-IO_L9P_AD3P_84-PadW16)")
	(net 568 "/FPGA MGT Interface/GTY_224_TX3_N")
	(net 569 "unconnected-(U34I-MGTREFCLK1N_224-PadY6)")
	(net 570 "unconnected-(U34I-MGTREFCLK1P_224-PadY7)")
	(net 571 "unconnected-(U34F-IO_L11P_AD1P_84-PadY13)")
	(net 572 "unconnected-(U34F-IO_L9N_AD3N_84-PadY16)")
	(net 573 "+1V8_MGTVCCAUX")
	(net 574 "unconnected-(J10-NC-PadA32)")
	(net 575 "unconnected-(J10-NC-PadA33)")
	(net 576 "unconnected-(J10-SMCLK-PadB5)")
	(net 577 "unconnected-(J10-SMDAT-PadB6)")
	(net 578 "unconnected-(J10-~{TRST}-PadB9)")
	(net 579 "unconnected-(J10-3V3AUX-PadB10)")
	(net 580 "unconnected-(J10-~{WAKE}-PadB11)")
	(net 581 "unconnected-(J10-~{CLKREQ}-PadB12)")
	(net 582 "unconnected-(J10-~{PWRBRK}-PadB30)")
	(net 583 "/FPGA MGT Interface/PCIE.RXD4_P")
	(net 584 "/FPGA MGT Interface/PCIE.RXD4_N")
	(net 585 "/FPGA MGT Interface/PCIE.RXD5_P")
	(net 586 "/FPGA MGT Interface/PCIE.RXD5_N")
	(net 587 "/FPGA MGT Interface/PCIE.RXD6_P")
	(net 588 "/FPGA MGT Interface/PCIE.RXD6_N")
	(net 589 "/FPGA MGT Interface/PCIE.RXD7_P")
	(net 590 "/FPGA MGT Interface/PCIE.RXD7_N")
	(net 591 "/PCIe connector/x8")
	(net 592 "/DDR5 RDIMM/B.DQS6_N")
	(net 593 "/DDR5 RDIMM/B.DQS6_P")
	(net 594 "/DDR5 RDIMM/B.DQS7_N")
	(net 595 "/DDR5 RDIMM/B.DQS7_P")
	(net 596 "/DDR5 RDIMM/B.DQS8_N")
	(net 597 "/DDR5 RDIMM/B.DQS8_P")
	(net 598 "/FPGA Config/VREFN")
	(net 599 "/FPGA Config/VREFP")
	(net 600 "/FPGA banks HP/VRP_66")
	(net 601 "/FPGA banks HP/VRP_67")
	(net 602 "/DDR5 RDIMM/CTRL.PWR_GOOD")
	(net 603 "unconnected-(J4-CEC-Pad13)")
	(net 604 "/HDMI + SD Card/HDMI_IN_HPD_CONN")
	(net 605 "/HDMI + SD Card/HDMI0.HPD")
	(net 606 "/HDMI + SD Card/SD_DAT2")
	(net 607 "/HDMI + SD Card/SD_DAT3")
	(net 608 "/HDMI + SD Card/SD_CMD")
	(net 609 "/HDMI + SD Card/SD_CLK")
	(net 610 "/FPGA banks HP/HyperRAM.DQ7")
	(net 611 "/HDMI + SD Card/SD_DAT0")
	(net 612 "/HDMI + SD Card/SD_DAT1")
	(net 613 "/FPGA banks HP/HyperRAM.DQ3")
	(net 614 "/FPGA banks HP/HyperRAM.DQ6")
	(net 615 "/FPGA banks HP/HyperRAM.DQ2")
	(net 616 "/FPGA banks HP/HyperRAM.CK_P")
	(net 617 "/FPGA banks HP/HyperRAM.CK_N")
	(net 618 "/FPGA banks HP/HyperRAM.~{CS}")
	(net 619 "/FPGA banks HP/HyperRAM.DQ5")
	(net 620 "/FPGA banks HP/HyperRAM.DQ1")
	(net 621 "/FPGA banks HP/HyperRAM.DQ4")
	(net 622 "/FPGA banks HP/HyperRAM.DQ0")
	(net 623 "/FPGA banks HP/HyperRAM.~{RESET}")
	(net 624 "/FPGA banks HP/HyperRAM.RWDS")
	(net 625 "Net-(Q17-D)")
	(net 626 "USER_IN")
	(net 627 "/FPGA MGT Interface/HDMI_FPGA.TX2_N")
	(net 628 "/FPGA MGT Interface/HDMI_FPGA.TX2_P")
	(net 629 "/FPGA MGT Interface/HDMI_FPGA.TX1_N")
	(net 630 "/FPGA MGT Interface/HDMI_FPGA.TX1_P")
	(net 631 "/FPGA MGT Interface/HDMI_FPGA.TX0_N")
	(net 632 "/FPGA MGT Interface/HDMI_FPGA.TX0_P")
	(net 633 "/DDR5 RDIMM/CTRL.CK_N")
	(net 634 "/DDR5 RDIMM/CTRL.CK_P")
	(net 635 "/FPGA banks HP/SD.CD")
	(net 636 "/FPGA banks HP/SD.CLK")
	(net 637 "/FPGA banks HP/SD.CMD")
	(net 638 "/FPGA banks HP/SD.DAT0")
	(net 639 "/FPGA banks HP/SD.DAT1")
	(net 640 "/FPGA banks HP/SD.DAT2")
	(net 641 "/FPGA banks HP/SD.DAT3")
	(net 642 "unconnected-(U27-EP-Pad9)")
	(net 643 "unconnected-(U34E-IO_L11N_T1U_N9_GC_67-PadD18)")
	(net 644 "/FPGA banks HD/HDMI_OUT_I2C.SDA")
	(net 645 "unconnected-(Y3-NC-Pad2)")
	(net 646 "unconnected-(U34E-IO_L11P_T1U_N8_GC_67-PadE18)")
	(net 647 "/HDMI + SD Card/VCCB")
	(net 648 "/FPGA MGT Interface/HDMI_FPGA.RX2_N")
	(net 649 "/FPGA MGT Interface/HDMI_FPGA.RX2_P")
	(net 650 "/FPGA MGT Interface/HDMI_FPGA.RX1_N")
	(net 651 "/FPGA MGT Interface/HDMI_FPGA.RX1_P")
	(net 652 "/FPGA MGT Interface/HDMI_FPGA.RX0_N")
	(net 653 "/FPGA MGT Interface/HDMI_FPGA.RX0_P")
	(net 654 "/HDMI + SD Card/HDMI_OUT_CONN_D2_P")
	(net 655 "/HDMI + SD Card/HDMI_OUT_CONN_D2_N")
	(net 656 "/HDMI + SD Card/HDMI_OUT_CONN_D1_P")
	(net 657 "/HDMI + SD Card/HDMI_OUT_CONN_D1_N")
	(net 658 "/HDMI + SD Card/HDMI_OUT_CONN_D0_P")
	(net 659 "/HDMI + SD Card/HDMI_OUT_CONN_D0_N")
	(net 660 "/HDMI + SD Card/HDMI_OUT_CONN_CLK_P")
	(net 661 "/HDMI + SD Card/HDMI_OUT_CONN_CLK_N")
	(net 662 "Net-(Q22-D)")
	(net 663 "Net-(U43-ST)")
	(net 664 "Net-(C325-Pad2)")
	(net 665 "unconnected-(U34E-IO_L19P_T3L_N0_DBC_AD9P_67-PadA22)")
	(net 666 "unconnected-(U34E-IO_T2U_N12_67-PadB16)")
	(net 667 "/FPGA Config/DX_N")
	(net 668 "/FPGA Config/DX_P")
	(net 669 "unconnected-(U39-NC-Pad12)")
	(net 670 "unconnected-(U39-NC-Pad13)")
	(net 671 "unconnected-(U40-CLK_{FB}-Pad6)")
	(net 672 "unconnected-(U34E-IO_T1U_N12_67-PadG19)")
	(net 673 "Net-(L3-Pad2)")
	(net 674 "Net-(L4-Pad2)")
	(net 675 "Net-(L5-Pad2)")
	(net 676 "Net-(L6-Pad2)")
	(net 677 "Net-(L7-Pad2)")
	(net 678 "Net-(L8-Pad2)")
	(net 679 "Net-(L9-Pad2)")
	(net 680 "Net-(L10-Pad2)")
	(net 681 "/Supply/DC-DC AUX, MGT/1V8_SEN_+")
	(net 682 "/Supply/DC-DC AUX, MGT/MGTAVTT_SEN_+")
	(net 683 "/Supply/DC-DC AUX, MGT/MGTAVCC_SEN_+")
	(net 684 "/Supply/DC-DC AUX, MGT/MGTAVCCAUX_SEN_+")
	(net 685 "/Supply/DC-DC IO/3V3_SEN_+")
	(net 686 "/Supply/DC-DC IO/5V_SEN_+")
	(net 687 "VDDQ")
	(net 688 "/Supply/DC-DC IO/1V2_SEN_+")
	(net 689 "/Supply/DC-DC AUX, MGT/1V8_SEN_-")
	(net 690 "/Supply/DC-DC AUX, MGT/MGTAVTT_SEN_-")
	(net 691 "/Supply/DC-DC AUX, MGT/MGTAVCC_SEN_-")
	(net 692 "/Supply/DC-DC AUX, MGT/MGTAVCCAUX_SEN_-")
	(net 693 "/Supply/DC-DC IO/3V3_SEN_-")
	(net 694 "/Supply/DC-DC IO/5V_SEN_-")
	(net 695 "/Supply/DC-DC IO/VDDQ_SEN_+")
	(net 696 "/Supply/DC-DC IO/1V2_SEN_-")
	(net 697 "/FPGA banks HD/USR_LED1")
	(net 698 "/FPGA banks HD/USR_LED2")
	(net 699 "/FPGA banks HD/USR_LED3")
	(net 700 "/FPGA banks HD/USR_LED4")
	(net 701 "/FPGA banks HD/USR_LED5")
	(net 702 "HOT_SWAP_RED")
	(net 703 "/DDR5 RDIMM/VSS_DET1")
	(net 704 "~{DDR_PRESENCE}")
	(net 705 "/FPGA Config/~{THERM}")
	(net 706 "unconnected-(U39-NC-Pad14)")
	(net 707 "/HDMI + SD Card/SWAP{slash}POL")
	(net 708 "Net-(U39-CS)")
	(net 709 "Net-(U38-VSADJ)")
	(net 710 "/HDMI + SD Card/I2C_EN{slash}PIN")
	(net 711 "Net-(U3-~{ALERT})")
	(net 712 "/Supply/DC-DC AUX, MGT/FB1")
	(net 713 "/Supply/DC-DC AUX, MGT/FB2")
	(net 714 "/Supply/DC-DC IO/FB5")
	(net 715 "/Supply/DC-DC IO/FB6")
	(net 716 "/Supply/DC-DC AUX, MGT/FB3")
	(net 717 "/Supply/DC-DC AUX, MGT/FB4")
	(net 718 "/Supply/DC-DC IO/FB7")
	(net 719 "/Supply/DC-DC IO/FB8")
	(net 720 "Net-(U28-~{PWRDN})")
	(net 721 "/Supply/DC-DC VCCINT/PASS0")
	(net 722 "/Supply/DC-DC VCCINT/TAKE1")
	(net 723 "/Supply/DC-DC VCCINT/PASS1")
	(net 724 "/Supply/DC-DC VCCINT/TAKE0")
	(net 725 "Net-(U4-I_{REF})")
	(net 726 "Net-(U36-I_{REF})")
	(net 727 "Net-(U4-ADDR)")
	(net 728 "Net-(U36-ADDR)")
	(net 729 "Net-(U3-ADDRSEL)")
	(net 730 "Net-(U28-IN1+)")
	(net 731 "Net-(U25-~{ALERT})")
	(net 732 "Net-(U28-IN2+)")
	(net 733 "Net-(U28-IN3+)")
	(net 734 "Net-(U28-IN4+)")
	(net 735 "Net-(U25-ADDRSEL)")
	(net 736 "/HDMI + SD Card/PRE_SEL")
	(net 737 "/HDMI + SD Card/EQ_SEL")
	(net 738 "/HDMI + SD Card/~{HDMI_SEL}")
	(net 739 "/HDMI + SD Card/TX_TERM_CTL")
	(net 740 "/HDMI + SD Card/SLEW_CTL")
	(net 741 "/Supply/DC-DC VCCINT/PWR.~{ALT}1")
	(net 742 "/Supply/DC-DC VCCINT/SET")
	(net 743 "/Supply/DC-DC VCCINT/I_{SUM}")
	(net 744 "unconnected-(U28-SLOW{slash}~{ALERT1}-Pad1)")
	(net 745 "unconnected-(U28-GPIO{slash}~{ALERT2}-Pad15)")
	(net 746 "/FPGA Config/FPGA_PWR.SDA")
	(net 747 "/FPGA Config/FPGA_PWR.SCL")
	(net 748 "/Supply/DC-DC VCCINT/PWR.~{ALT}2")
	(net 749 "/I^{2}C + I3C/PWR.SCL")
	(net 750 "unconnected-(U39-NC-Pad30)")
	(net 751 "unconnected-(U39-NC-Pad33)")
	(net 752 "unconnected-(U39-NC-Pad34)")
	(net 753 "unconnected-(U39-NC-Pad35)")
	(net 754 "/Supply/DC-DC VCCINT/VREF+")
	(net 755 "/Supply/DC-DC VCCINT/VREF-")
	(net 756 "Net-(C264-Pad2)")
	(net 757 "unconnected-(U38-NC-Pad17)")
	(net 758 "unconnected-(U38-CEC_EN-Pad18)")
	(net 759 "unconnected-(U38-AUX_SRC_N-Pad44)")
	(net 760 "unconnected-(U38-AUX_SRC_P-Pad45)")
	(net 761 "unconnected-(U39-NC-Pad2)")
	(net 762 "INT_CB")
	(net 763 "unconnected-(U39-NC-Pad4)")
	(net 764 "/FPGA MGT Interface/XA")
	(net 765 "/FPGA MGT Interface/XB")
	(net 766 "unconnected-(U39-NC-Pad9)")
	(net 767 "LOL")
	(net 768 "/FPGA MGT Interface/HDMI_CTL.SCL")
	(net 769 "/FPGA MGT Interface/HDMI_CTL.SDA")
	(net 770 "unconnected-(U39-SDI-Pad27)")
	(net 771 "/FPGA banks HD/FPGA_I3C.SCL")
	(net 772 "SD_SEL")
	(net 773 "MODE2")
	(net 774 "Net-(U49-EN)")
	(net 775 "Net-(Q24-S)")
	(net 776 "/Debug FTDI + VNA/FTDI_JTAG_RST")
	(net 777 "/Supply/DC-DC VCCINT/~{PS}")
	(net 778 "~{FPGA_I3C_EXT_PU}")
	(net 779 "~{I3C_EXT_PU}")
	(net 780 "/Debug FTDI + VNA/FTDI_EECS")
	(net 781 "/Debug FTDI + VNA/FTDI_JTAG_TCK")
	(net 782 "Net-(Q24-D)")
	(net 783 "Net-(D1-C)")
	(net 784 "Net-(D2-C)")
	(net 785 "Net-(D3-C)")
	(net 786 "/Debug FTDI + VNA/FTDI_JTAG_TDI")
	(net 787 "/Debug FTDI + VNA/FTDI_JTAG_TDO")
	(net 788 "/Debug FTDI + VNA/FTDI_JTAG_TMS")
	(net 789 "/Debug FTDI + VNA/FTDI_UART0_TX")
	(net 790 "/Debug FTDI + VNA/FTDI_UART0_RX")
	(net 791 "/Debug FTDI + VNA/FTDI_UART1_TX")
	(net 792 "/Debug FTDI + VNA/FTDI_UART1_RX")
	(net 793 "/Debug FTDI + VNA/FTDI_EEDAT")
	(net 794 "/Debug FTDI + VNA/FTDI_EECLK")
	(net 795 "unconnected-(U33-Pad5)")
	(net 796 "Net-(U45-EN)")
	(net 797 "+1V8")
	(net 798 "unconnected-(U34H-IO_L3N_AD13N_87-PadG14)")
	(net 799 "unconnected-(U34H-IO_L3P_AD13P_87-PadH14)")
	(net 800 "unconnected-(U34H-IO_L4N_AD12N_87-PadJ14)")
	(net 801 "unconnected-(U34H-IO_L4P_AD12P_87-PadJ15)")
	(net 802 "/DDR5 RDIMM/VIN_BULK")
	(net 803 "/DDR5 RDIMM/VIN_MGMT")
	(net 804 "Net-(D21-C)")
	(net 805 "Net-(D22-C)")
	(net 806 "Net-(Q23-G)")
	(net 807 "Net-(Q26-D)")
	(net 808 "VIN_BULK_EN")
	(net 809 "VIN_MGMT_EN")
	(net 810 "/HDMI + SD Card/HDMI_VDD")
	(net 811 "/Supply/heater")
	(net 812 "Heater_PWM")
	(net 813 "Net-(Q28-D)")
	(net 814 "Net-(Q29-D)")
	(net 815 "unconnected-(J10-3V3-PadA10)_1")
	(net 816 "unconnected-(J10-3V3-PadA10)_2")
	(net 817 "unconnected-(U33-Pad5)_1")
	(net 818 "Net-(D17-A)")
	(net 819 "/Supply/DC-DC IO/VDDQ_SEN_-")
	(net 820 "+0V9_MGTAVCC")
	(net 821 "Net-(C135-Pad2)")
	(net 822 "Net-(C137-Pad2)")
	(net 823 "Net-(J6-LED_G+)")
	(net 824 "Net-(J6-LED_Y+)")
	(net 825 "DAC_VREF")
	(net 826 "/FPGA banks HP/VREF")
	(net 827 "Net-(R253-Pad1)")
	(footprint "antmicro-footprints:C_0402_1005Metric"
		(layer "F.Cu")
		(at 133.815 159.985 90)
		(descr "Capacitor SMD 0402")
		(tags "capacitor SMD 0402")
		(property "Reference" "C116"
			(at -1.065 2.385 90)
			(layer "F.SilkS")
			(effects
				(font
					(size 0.7 0.7)
					(thickness 0.15)
				)
				(justify left bottom)
			)
		)
		(property "Value" "C_4u7_0402"
			(at -1.022927 2.155213 90)
			(layer "F.Fab")
			(effects
				(font
					(size 0.7 0.7)
					(thickness 0.15)
				)
				(justify left bottom)
			)
		)
		(property "Datasheet" "https://www.murata.com/products/productdetail?partno=GRM155R61A475MEAA%23"
			(at 0 0 90)
			(layer "F.Fab")
			(hide yes)
			(effects
				(font
					(size 1.27 1.27)
					(thickness 0.15)
				)
			)
		)
		(property "Manufacturer" "Murata"
			(at 0 0 90)
			(unlocked yes)
			(layer "F.Fab")
			(hide yes)
			(effects
				(font
					(size 1 1)
					(thickness 0.15)
				)
			)
		)
		(property "MPN" "GRM155R61A475MEAAD"
			(at 0 0 90)
			(unlocked yes)
			(layer "F.Fab")
			(hide yes)
			(effects
				(font
					(size 1 1)
					(thickness 0.15)
				)
			)
		)
		(property "Val" "4u7"
			(at 0 0 90)
			(unlocked yes)
			(layer "F.Fab")
			(hide yes)
			(effects
				(font
					(size 1 1)
					(thickness 0.15)
				)
			)
		)
		(property "License" "Apache-2.0"
			(at 0 0 90)
			(unlocked yes)
			(layer "F.Fab")
			(hide yes)
			(effects
				(font
					(size 1 1)
					(thickness 0.15)
				)
			)
		)
		(property "Author" "Antmicro"
			(at 0 0 90)
			(unlocked yes)
			(layer "F.Fab")
			(hide yes)
			(effects
				(font
					(size 1 1)
					(thickness 0.15)
				)
			)
		)
		(property "Voltage" ""
			(at 0 0 90)
			(unlocked yes)
			(layer "F.Fab")
			(hide yes)
			(effects
				(font
					(size 1 1)
					(thickness 0.15)
				)
			)
		)
		(property "Dielectric" ""
			(at 0 0 90)
			(unlocked yes)
			(layer "F.Fab")
			(hide yes)
			(effects
				(font
					(size 1 1)
					(thickness 0.15)
				)
			)
		)
		(sheetname "/Debug FTDI + VNA/")
		(sheetfile "debug-ftdi.kicad_sch")
		(attr smd)
		(fp_rect
			(start -0.925 -0.47)
			(end 0.925 0.47)
			(stroke
				(width 0.05)
				(type default)
			)
			(fill no)
			(layer "F.CrtYd")
		)
		(fp_line
			(start 0.504 -0.25)
			(end 0.504 0.248)
			(stroke
				(width 0.15)
				(type solid)
			)
			(layer "F.Fab")
		)
		(fp_line
			(start -0.494 -0.25)
			(end 0.504 -0.25)
			(stroke
				(width 0.15)
				(type solid)
			)
			(layer "F.Fab")
		)
		(fp_line
			(start 0.504 0.248)
			(end -0.494 0.248)
			(stroke
				(width 0.15)
				(type solid)
			)
			(layer "F.Fab")
		)
		(fp_line
			(start -0.494 0.248)
			(end -0.494 -0.25)
			(stroke
				(width 0.15)
				(type solid)
			)
			(layer "F.Fab")
		)
		(fp_text user "License: Apache-2.0"
			(at -0.939 5.799 90)
			(layer "F.Fab")
			(effects
				(font
					(size 0.7 0.7)
					(thickness 0.15)
				)
				(justify left bottom)
			)
		)
		(fp_text user "${REFERENCE}"
			(at -0.939 4.599 90)
			(layer "F.Fab")
			(effects
				(font
					(size 0.7 0.7)
					(thickness 0.15)
				)
				(justify left bottom)
			)
		)
		(fp_text user "Author: Antmicro"
			(at -0.939 3.399 90)
			(layer "F.Fab")
			(effects
				(font
					(size 0.7 0.7)
					(thickness 0.15)
				)
				(justify left bottom)
			)
		)
		(pad "1" smd roundrect
			(at -0.48 0 90)
			(size 0.59 0.64)
			(layers "F.Cu" "F.Mask" "F.Paste")
			(roundrect_rratio 0.25)
			(net 5 "/Debug FTDI + VNA/FTDI_VPHY")
			(pintype "passive")
		)
		(pad "2" smd roundrect
			(at 0.48 0 90)
			(size 0.59 0.64)
			(layers "F.Cu" "F.Mask" "F.Paste")
			(roundrect_rratio 0.25)
			(net 1 "GND")
			(pintype "passive")
		)
	)
	(footprint "antmicro-footprints:C_0402_1005Metric"
		(layer "F.Cu")
		(at 138.396843 156.001328 90)
		(descr "Capacitor SMD 0402")
		(tags "capacitor SMD 0402")
		(property "Reference" "C123"
			(at 1.251328 0.503157 90)
			(layer "F.SilkS")
			(effects
				(font
					(size 0.7 0.7)
					(thickness 0.15)
				)
				(justify left bottom)
			)
		)
		(property "Value" "C_100n_0402"
			(at -1.022927 2.155213 90)
			(layer "F.Fab")
			(effects
				(font
					(size 0.7 0.7)
					(thickness 0.15)
				)
				(justify left bottom)
			)
		)
		(property "Datasheet" "https://www.murata.com/products/productdetail?partno=GRM155R61H104KE14%23"
			(at 0 0 90)
			(layer "F.Fab")
			(hide yes)
			(effects
				(font
					(size 1.27 1.27)
					(thickness 0.15)
				)
			)
		)
		(property "Manufacturer" "Murata"
			(at 0 0 90)
			(unlocked yes)
			(layer "F.Fab")
			(hide yes)
			(effects
				(font
					(size 1 1)
					(thickness 0.15)
				)
			)
		)
		(property "MPN" "GRM155R61H104KE14D"
			(at 0 0 90)
			(unlocked yes)
			(layer "F.Fab")
			(hide yes)
			(effects
				(font
					(size 1 1)
					(thickness 0.15)
				)
			)
		)
		(property "Val" "100n"
			(at 0 0 90)
			(unlocked yes)
			(layer "F.Fab")
			(hide yes)
			(effects
				(font
					(size 1 1)
					(thickness 0.15)
				)
			)
		)
		(property "License" "Apache-2.0"
			(at 0 0 90)
			(unlocked yes)
			(layer "F.Fab")
			(hide yes)
			(effects
				(font
					(size 1 1)
					(thickness 0.15)
				)
			)
		)
		(property "Author" "Antmicro"
			(at 0 0 90)
			(unlocked yes)
			(layer "F.Fab")
			(hide yes)
			(effects
				(font
					(size 1 1)
					(thickness 0.15)
				)
			)
		)
		(property "Voltage" "50V"
			(at 0 0 90)
			(unlocked yes)
			(layer "F.Fab")
			(hide yes)
			(effects
				(font
					(size 1 1)
					(thickness 0.15)
				)
			)
		)
		(property "Dielectric" "X5R"
			(at 0 0 90)
			(unlocked yes)
			(layer "F.Fab")
			(hide yes)
			(effects
				(font
					(size 1 1)
					(thickness 0.15)
				)
			)
		)
		(sheetname "/Debug FTDI + VNA/")
		(sheetfile "debug-ftdi.kicad_sch")
		(attr smd)
		(fp_rect
			(start -0.925 -0.47)
			(end 0.925 0.47)
			(stroke
				(width 0.05)
				(type default)
			)
			(fill no)
			(layer "F.CrtYd")
		)
		(fp_line
			(start 0.504 -0.25)
			(end 0.504 0.248)
			(stroke
				(width 0.15)
				(type solid)
			)
			(layer "F.Fab")
		)
		(fp_line
			(start -0.494 -0.25)
			(end 0.504 -0.25)
			(stroke
				(width 0.15)
				(type solid)
			)
			(layer "F.Fab")
		)
		(fp_line
			(start 0.504 0.248)
			(end -0.494 0.248)
			(stroke
				(width 0.15)
				(type solid)
			)
			(layer "F.Fab")
		)
		(fp_line
			(start -0.494 0.248)
			(end -0.494 -0.25)
			(stroke
				(width 0.15)
				(type solid)
			)
			(layer "F.Fab")
		)
		(fp_text user "${REFERENCE}"
			(at -0.939 4.599 90)
			(layer "F.Fab")
			(effects
				(font
					(size 0.7 0.7)
					(thickness 0.15)
				)
				(justify left bottom)
			)
		)
		(fp_text user "Author: Antmicro"
			(at -0.939 3.399 90)
			(layer "F.Fab")
			(effects
				(font
					(size 0.7 0.7)
					(thickness 0.15)
				)
				(justify left bottom)
			)
		)
		(fp_text user "License: Apache-2.0"
			(at -0.939 5.799 90)
			(layer "F.Fab")
			(effects
				(font
					(size 0.7 0.7)
					(thickness 0.15)
				)
				(justify left bottom)
			)
		)
		(pad "1" smd roundrect
			(at -0.48 0 90)
			(size 0.59 0.64)
			(layers "F.Cu" "F.Mask" "F.Paste")
			(roundrect_rratio 0.25)
			(net 34 "/Debug FTDI + VNA/FTDI_VCORE")
			(pintype "passive")
		)
		(pad "2" smd roundrect
			(at 0.48 0 90)
			(size 0.59 0.64)
			(layers "F.Cu" "F.Mask" "F.Paste")
			(roundrect_rratio 0.25)
			(net 1 "GND")
			(pintype "passive")
		)
	)
	(footprint "antmicro-footprints:Resonator_SMD_Abracon_ABM8G_3.2x2.5mm"
		(layer "F.Cu")
		(at 135.023 155.374 90)
		(property "Reference" "Y1"
			(at 3.424 -0.723 90)
			(layer "F.SilkS")
			(effects
				(font
					(size 0.7 0.7)
					(thickness 0.15)
				)
				(justify right bottom)
			)
		)
		(property "Value" "Resonator_12MHz_ABM8G"
			(at -1.75 2.548 90)
			(layer "F.Fab")
			(effects
				(font
					(size 0.7 0.7)
					(thickness 0.15)
				)
				(justify left bottom)
			)
		)
		(property "Datasheet" "https://abracon.com/Resonators/ABM8G.pdf"
			(at 0 0 90)
			(layer "F.Fab")
			(hide yes)
			(effects
				(font
					(size 1.27 1.27)
					(thickness 0.15)
				)
			)
		)
		(property "MPN" "ABM8G-12.000MHZ-18-D2Y-T"
			(at 0 0 90)
			(unlocked yes)
			(layer "F.Fab")
			(hide yes)
			(effects
				(font
					(size 1 1)
					(thickness 0.15)
				)
			)
		)
		(property "Manufacturer" "Abracon"
			(at 0 0 90)
			(unlocked yes)
			(layer "F.Fab")
			(hide yes)
			(effects
				(font
					(size 1 1)
					(thickness 0.15)
				)
			)
		)
		(property "Author" "Antmicro"
			(at 0 0 90)
			(unlocked yes)
			(layer "F.Fab")
			(hide yes)
			(effects
				(font
					(size 1 1)
					(thickness 0.15)
				)
			)
		)
		(property "License" "Apache-2.0"
			(at 0 0 90)
			(unlocked yes)
			(layer "F.Fab")
			(hide yes)
			(effects
				(font
					(size 1 1)
					(thickness 0.15)
				)
			)
		)
		(property "Val" "12 MHz"
			(at 0 0 90)
			(unlocked yes)
			(layer "F.Fab")
			(hide yes)
			(effects
				(font
					(size 1 1)
					(thickness 0.15)
				)
			)
		)
		(sheetname "/Debug FTDI + VNA/")
		(sheetfile "debug-ftdi.kicad_sch")
		(attr smd)
		(fp_line
			(start -0.35 -1.25)
			(end 0.45 -1.25)
			(stroke
				(width 0.15)
				(type solid)
			)
			(layer "F.SilkS")
		)
		(fp_line
			(start 1.6 0.3)
			(end 1.6 -0.2)
			(stroke
				(width 0.15)
				(type solid)
			)
			(layer "F.SilkS")
		)
		(fp_line
			(start -1.6 0.3)
			(end -1.6 -0.2)
			(stroke
				(width 0.15)
				(type solid)
			)
			(layer "F.SilkS")
		)
		(fp_line
			(start -0.35 1.25)
			(end 0.45 1.25)
			(stroke
				(width 0.15)
				(type solid)
			)
			(layer "F.SilkS")
		)
		(fp_circle
			(center -1.75 1.5)
			(end -1.7 1.5)
			(stroke
				(width 0.15)
				(type solid)
			)
			(fill no)
			(layer "F.SilkS")
		)
		(fp_rect
			(start -1.907 -1.55)
			(end 2.006 1.649)
			(stroke
				(width 0.05)
				(type solid)
			)
			(fill no)
			(layer "F.CrtYd")
		)
		(fp_text user "${REFERENCE}"
			(at -1.75 3.75 90)
			(layer "F.Fab")
			(effects
				(font
					(size 0.7 0.7)
					(thickness 0.15)
				)
				(justify left bottom)
			)
		)
		(fp_text user "License: Apache-2.0"
			(at -1.75 6.5 90)
			(layer "F.Fab")
			(effects
				(font
					(size 0.7 0.7)
					(thickness 0.15)
				)
				(justify left bottom)
			)
		)
		(fp_text user "Author: Antmicro"
			(at -1.75 5 90)
			(layer "F.Fab")
			(effects
				(font
					(size 0.7 0.7)
					(thickness 0.15)
				)
				(justify left bottom)
			)
		)
		(pad "1" smd roundrect
			(at -1.101 0.949 90)
			(size 1.3 1.1)
			(layers "F.Cu" "F.Mask" "F.Paste")
			(roundrect_rratio 0)
			(chamfer_ratio 0.2)
			(chamfer bottom_left)
			(net 4 "/Debug FTDI + VNA/FTDI_XI")
			(pintype "passive")
		)
		(pad "2" smd rect
			(at 1.199 0.949 90)
			(size 1.3 1.1)
			(layers "F.Cu" "F.Mask" "F.Paste")
			(net 1 "GND")
			(pinfunction "SH")
			(pintype "passive")
		)
		(pad "3" smd rect
			(at 1.199 -0.85 90)
			(size 1.3 1.1)
			(layers "F.Cu" "F.Mask" "F.Paste")
			(net 7 "/Debug FTDI + VNA/FTDI_XO")
			(pintype "passive")
		)
		(pad "4" smd rect
			(at -1.101 -0.85 90)
			(size 1.3 1.1)
			(layers "F.Cu" "F.Mask" "F.Paste")
			(net 1 "GND")
			(pinfunction "SH")
			(pintype "passive")
		)
	)
	(footprint "antmicro-footprints:R_0402_1005Metric"
		(layer "F.Cu")
		(at 149.899499 163.469)
		(descr "Resistor SMD 0402")
		(tags "resistor SMD 0402")
		(property "Reference" "R52"
			(at 0.990501 0.536 0)
			(layer "F.SilkS")
			(effects
				(font
					(size 0.7 0.7)
					(thickness 0.15)
				)
				(justify left bottom)
			)
		)
		(property "Value" "R_22R_0402"
			(at -1.011843 1.772047 0)
			(layer "F.Fab")
			(effects
				(font
					(size 0.7 0.7)
					(thickness 0.15)
				)
				(justify left bottom)
			)
		)
		(property "Datasheet" "https://www.bourns.com/docs/product-datasheets/cr.pdf"
			(at 0 0 0)
			(layer "F.Fab")
			(hide yes)
			(effects
				(font
					(size 1.27 1.27)
					(thickness 0.15)
				)
			)
		)
		(property "Manufacturer" "Bourns"
			(at 0 0 0)
			(unlocked yes)
			(layer "F.Fab")
			(hide yes)
			(effects
				(font
					(size 1 1)
					(thickness 0.15)
				)
			)
		)
		(property "MPN" "CR0402-FX-22R0GLF"
			(at 0 0 0)
			(unlocked yes)
			(layer "F.Fab")
			(hide yes)
			(effects
				(font
					(size 1 1)
					(thickness 0.15)
				)
			)
		)
		(property "Val" "22R"
			(at 0 0 0)
			(unlocked yes)
			(layer "F.Fab")
			(hide yes)
			(effects
				(font
					(size 1 1)
					(thickness 0.15)
				)
			)
		)
		(property "License" "Apache-2.0"
			(at 0 0 0)
			(unlocked yes)
			(layer "F.Fab")
			(hide yes)
			(effects
				(font
					(size 1 1)
					(thickness 0.15)
				)
			)
		)
		(property "Author" "Antmicro"
			(at 0 0 0)
			(unlocked yes)
			(layer "F.Fab")
			(hide yes)
			(effects
				(font
					(size 1 1)
					(thickness 0.15)
				)
			)
		)
		(property "Tolerance" "1%"
			(at 0 0 0)
			(unlocked yes)
			(layer "F.Fab")
			(hide yes)
			(effects
				(font
					(size 1 1)
					(thickness 0.15)
				)
			)
		)
		(sheetname "/Debug FTDI + VNA/")
		(sheetfile "debug-ftdi.kicad_sch")
		(attr smd)
		(fp_rect
			(start -0.925 -0.47)
			(end 0.925 0.47)
			(stroke
				(width 0.05)
				(type default)
			)
			(fill no)
			(layer "F.CrtYd")
		)
		(fp_rect
			(start -0.5 -0.25)
			(end 0.5 0.25)
			(stroke
				(width 0.15)
				(type solid)
			)
			(fill no)
			(layer "F.Fab")
		)
		(fp_text user "${REFERENCE}"
			(at -0.95 3.168 0)
			(layer "F.Fab")
			(effects
				(font
					(size 0.7 0.7)
					(thickness 0.15)
				)
				(justify left bottom)
			)
		)
		(fp_text user "Author: Antmicro"
			(at -0.95 4.169 0)
			(layer "F.Fab")
			(effects
				(font
					(size 0.7 0.7)
					(thickness 0.15)
				)
				(justify left bottom)
			)
		)
		(fp_text user "License: Apache-2.0"
			(at -0.95 5.169 0)
			(layer "F.Fab")
			(effects
				(font
					(size 0.7 0.7)
					(thickness 0.15)
				)
				(justify left bottom)
			)
		)
		(pad "1" smd roundrect
			(at -0.48 0)
			(size 0.59 0.64)
			(layers "F.Cu" "F.Mask" "F.Paste")
			(roundrect_rratio 0.25)
			(net 373 "Net-(U16-B1)")
			(pintype "passive")
		)
		(pad "2" smd roundrect
			(at 0.48 0)
			(size 0.59 0.64)
			(layers "F.Cu" "F.Mask" "F.Paste")
			(roundrect_rratio 0.25)
			(net 374 "/Debug FTDI + VNA/UART0.TX")
			(pintype "passive")
		)
	)
	(footprint "antmicro-footprints:R_0402_1005Metric"
		(layer "F.Cu")
		(at 149.899499 164.494)
		(descr "Resistor SMD 0402")
		(tags "resistor SMD 0402")
		(property "Reference" "R53"
			(at 0.990501 0.536 0)
			(layer "F.SilkS")
			(effects
				(font
					(size 0.7 0.7)
					(thickness 0.15)
				)
				(justify left bottom)
			)
		)
		(property "Value" "R_22R_0402"
			(at -1.011843 1.772047 0)
			(layer "F.Fab")
			(effects
				(font
					(size 0.7 0.7)
					(thickness 0.15)
				)
				(justify left bottom)
			)
		)
		(property "Datasheet" "https://www.bourns.com/docs/product-datasheets/cr.pdf"
			(at 0 0 0)
			(layer "F.Fab")
			(hide yes)
			(effects
				(font
					(size 1.27 1.27)
					(thickness 0.15)
				)
			)
		)
		(property "Manufacturer" "Bourns"
			(at 0 0 0)
			(unlocked yes)
			(layer "F.Fab")
			(hide yes)
			(effects
				(font
					(size 1 1)
					(thickness 0.15)
				)
			)
		)
		(property "MPN" "CR0402-FX-22R0GLF"
			(at 0 0 0)
			(unlocked yes)
			(layer "F.Fab")
			(hide yes)
			(effects
				(font
					(size 1 1)
					(thickness 0.15)
				)
			)
		)
		(property "Val" "22R"
			(at 0 0 0)
			(unlocked yes)
			(layer "F.Fab")
			(hide yes)
			(effects
				(font
					(size 1 1)
					(thickness 0.15)
				)
			)
		)
		(property "License" "Apache-2.0"
			(at 0 0 0)
			(unlocked yes)
			(layer "F.Fab")
			(hide yes)
			(effects
				(font
					(size 1 1)
					(thickness 0.15)
				)
			)
		)
		(property "Author" "Antmicro"
			(at 0 0 0)
			(unlocked yes)
			(layer "F.Fab")
			(hide yes)
			(effects
				(font
					(size 1 1)
					(thickness 0.15)
				)
			)
		)
		(property "Tolerance" "1%"
			(at 0 0 0)
			(unlocked yes)
			(layer "F.Fab")
			(hide yes)
			(effects
				(font
					(size 1 1)
					(thickness 0.15)
				)
			)
		)
		(sheetname "/Debug FTDI + VNA/")
		(sheetfile "debug-ftdi.kicad_sch")
		(attr smd)
		(fp_rect
			(start -0.925 -0.47)
			(end 0.925 0.47)
			(stroke
				(width 0.05)
				(type default)
			)
			(fill no)
			(layer "F.CrtYd")
		)
		(fp_rect
			(start -0.5 -0.25)
			(end 0.5 0.25)
			(stroke
				(width 0.15)
				(type solid)
			)
			(fill no)
			(layer "F.Fab")
		)
		(fp_text user "${REFERENCE}"
			(at -0.95 3.168 0)
			(layer "F.Fab")
			(effects
				(font
					(size 0.7 0.7)
					(thickness 0.15)
				)
				(justify left bottom)
			)
		)
		(fp_text user "License: Apache-2.0"
			(at -0.95 5.169 0)
			(layer "F.Fab")
			(effects
				(font
					(size 0.7 0.7)
					(thickness 0.15)
				)
				(justify left bottom)
			)
		)
		(fp_text user "Author: Antmicro"
			(at -0.95 4.169 0)
			(layer "F.Fab")
			(effects
				(font
					(size 0.7 0.7)
					(thickness 0.15)
				)
				(justify left bottom)
			)
		)
		(pad "1" smd roundrect
			(at -0.48 0)
			(size 0.59 0.64)
			(layers "F.Cu" "F.Mask" "F.Paste")
			(roundrect_rratio 0.25)
			(net 375 "Net-(U16-B2)")
			(pintype "passive")
		)
		(pad "2" smd roundrect
			(at 0.48 0)
			(size 0.59 0.64)
			(layers "F.Cu" "F.Mask" "F.Paste")
			(roundrect_rratio 0.25)
			(net 376 "/Debug FTDI + VNA/UART0.RX")
			(pintype "passive")
		)
	)
	(footprint "antmicro-footprints:R_0402_1005Metric"
		(layer "F.Cu")
		(at 149.904499 159.709)
		(descr "Resistor SMD 0402")
		(tags "resistor SMD 0402")
		(property "Reference" "R54"
			(at -0.834499 -1.569 0)
			(layer "F.SilkS")
			(effects
				(font
					(size 0.7 0.7)
					(thickness 0.15)
				)
				(justify left bottom)
			)
		)
		(property "Value" "R_22R_0402"
			(at -1.011843 1.772047 0)
			(layer "F.Fab")
			(effects
				(font
					(size 0.7 0.7)
					(thickness 0.15)
				)
				(justify left bottom)
			)
		)
		(property "Datasheet" "https://www.bourns.com/docs/product-datasheets/cr.pdf"
			(at 0 0 0)
			(layer "F.Fab")
			(hide yes)
			(effects
				(font
					(size 1.27 1.27)
					(thickness 0.15)
				)
			)
		)
		(property "Manufacturer" "Bourns"
			(at 0 0 0)
			(unlocked yes)
			(layer "F.Fab")
			(hide yes)
			(effects
				(font
					(size 1 1)
					(thickness 0.15)
				)
			)
		)
		(property "MPN" "CR0402-FX-22R0GLF"
			(at 0 0 0)
			(unlocked yes)
			(layer "F.Fab")
			(hide yes)
			(effects
				(font
					(size 1 1)
					(thickness 0.15)
				)
			)
		)
		(property "Val" "22R"
			(at 0 0 0)
			(unlocked yes)
			(layer "F.Fab")
			(hide yes)
			(effects
				(font
					(size 1 1)
					(thickness 0.15)
				)
			)
		)
		(property "License" "Apache-2.0"
			(at 0 0 0)
			(unlocked yes)
			(layer "F.Fab")
			(hide yes)
			(effects
				(font
					(size 1 1)
					(thickness 0.15)
				)
			)
		)
		(property "Author" "Antmicro"
			(at 0 0 0)
			(unlocked yes)
			(layer "F.Fab")
			(hide yes)
			(effects
				(font
					(size 1 1)
					(thickness 0.15)
				)
			)
		)
		(property "Tolerance" "1%"
			(at 0 0 0)
			(unlocked yes)
			(layer "F.Fab")
			(hide yes)
			(effects
				(font
					(size 1 1)
					(thickness 0.15)
				)
			)
		)
		(sheetname "/Debug FTDI + VNA/")
		(sheetfile "debug-ftdi.kicad_sch")
		(attr smd)
		(fp_rect
			(start -0.925 -0.47)
			(end 0.925 0.47)
			(stroke
				(width 0.05)
				(type default)
			)
			(fill no)
			(layer "F.CrtYd")
		)
		(fp_rect
			(start -0.5 -0.25)
			(end 0.5 0.25)
			(stroke
				(width 0.15)
				(type solid)
			)
			(fill no)
			(layer "F.Fab")
		)
		(fp_text user "Author: Antmicro"
			(at -0.95 4.169 0)
			(layer "F.Fab")
			(effects
				(font
					(size 0.7 0.7)
					(thickness 0.15)
				)
				(justify left bottom)
			)
		)
		(fp_text user "License: Apache-2.0"
			(at -0.95 5.169 0)
			(layer "F.Fab")
			(effects
				(font
					(size 0.7 0.7)
					(thickness 0.15)
				)
				(justify left bottom)
			)
		)
		(fp_text user "${REFERENCE}"
			(at -0.95 3.168 0)
			(layer "F.Fab")
			(effects
				(font
					(size 0.7 0.7)
					(thickness 0.15)
				)
				(justify left bottom)
			)
		)
		(pad "1" smd roundrect
			(at -0.48 0)
			(size 0.59 0.64)
			(layers "F.Cu" "F.Mask" "F.Paste")
			(roundrect_rratio 0.25)
			(net 448 "Net-(U32-B1)")
			(pintype "passive")
		)
		(pad "2" smd roundrect
			(at 0.48 0)
			(size 0.59 0.64)
			(layers "F.Cu" "F.Mask" "F.Paste")
			(roundrect_rratio 0.25)
			(net 377 "/Debug FTDI + VNA/UART1.TX")
			(pintype "passive")
		)
	)
	(footprint "antmicro-footprints:R_0402_1005Metric"
		(layer "F.Cu")
		(at 149.904499 160.709)
		(descr "Resistor SMD 0402")
		(tags "resistor SMD 0402")
		(property "Reference" "R55"
			(at -0.834499 -1.569 0)
			(layer "F.SilkS")
			(effects
				(font
					(size 0.7 0.7)
					(thickness 0.15)
				)
				(justify left bottom)
			)
		)
		(property "Value" "R_22R_0402"
			(at -1.011843 1.772047 0)
			(layer "F.Fab")
			(effects
				(font
					(size 0.7 0.7)
					(thickness 0.15)
				)
				(justify left bottom)
			)
		)
		(property "Datasheet" "https://www.bourns.com/docs/product-datasheets/cr.pdf"
			(at 0 0 0)
			(layer "F.Fab")
			(hide yes)
			(effects
				(font
					(size 1.27 1.27)
					(thickness 0.15)
				)
			)
		)
		(property "Manufacturer" "Bourns"
			(at 0 0 0)
			(unlocked yes)
			(layer "F.Fab")
			(hide yes)
			(effects
				(font
					(size 1 1)
					(thickness 0.15)
				)
			)
		)
		(property "MPN" "CR0402-FX-22R0GLF"
			(at 0 0 0)
			(unlocked yes)
			(layer "F.Fab")
			(hide yes)
			(effects
				(font
					(size 1 1)
					(thickness 0.15)
				)
			)
		)
		(property "Val" "22R"
			(at 0 0 0)
			(unlocked yes)
			(layer "F.Fab")
			(hide yes)
			(effects
				(font
					(size 1 1)
					(thickness 0.15)
				)
			)
		)
		(property "License" "Apache-2.0"
			(at 0 0 0)
			(unlocked yes)
			(layer "F.Fab")
			(hide yes)
			(effects
				(font
					(size 1 1)
					(thickness 0.15)
				)
			)
		)
		(property "Author" "Antmicro"
			(at 0 0 0)
			(unlocked yes)
			(layer "F.Fab")
			(hide yes)
			(effects
				(font
					(size 1 1)
					(thickness 0.15)
				)
			)
		)
		(property "Tolerance" "1%"
			(at 0 0 0)
			(unlocked yes)
			(layer "F.Fab")
			(hide yes)
			(effects
				(font
					(size 1 1)
					(thickness 0.15)
				)
			)
		)
		(sheetname "/Debug FTDI + VNA/")
		(sheetfile "debug-ftdi.kicad_sch")
		(attr smd)
		(fp_rect
			(start -0.925 -0.47)
			(end 0.925 0.47)
			(stroke
				(width 0.05)
				(type default)
			)
			(fill no)
			(layer "F.CrtYd")
		)
		(fp_rect
			(start -0.5 -0.25)
			(end 0.5 0.25)
			(stroke
				(width 0.15)
				(type solid)
			)
			(fill no)
			(layer "F.Fab")
		)
		(fp_text user "${REFERENCE}"
			(at -0.95 3.168 0)
			(layer "F.Fab")
			(effects
				(font
					(size 0.7 0.7)
					(thickness 0.15)
				)
				(justify left bottom)
			)
		)
		(fp_text user "License: Apache-2.0"
			(at -0.95 5.169 0)
			(layer "F.Fab")
			(effects
				(font
					(size 0.7 0.7)
					(thickness 0.15)
				)
				(justify left bottom)
			)
		)
		(fp_text user "Author: Antmicro"
			(at -0.95 4.169 0)
			(layer "F.Fab")
			(effects
				(font
					(size 0.7 0.7)
					(thickness 0.15)
				)
				(justify left bottom)
			)
		)
		(pad "1" smd roundrect
			(at -0.48 0)
			(size 0.59 0.64)
			(layers "F.Cu" "F.Mask" "F.Paste")
			(roundrect_rratio 0.25)
			(net 449 "Net-(U32-B2)")
			(pintype "passive")
		)
		(pad "2" smd roundrect
			(at 0.48 0)
			(size 0.59 0.64)
			(layers "F.Cu" "F.Mask" "F.Paste")
			(roundrect_rratio 0.25)
			(net 378 "/Debug FTDI + VNA/UART1.RX")
			(pintype "passive")
		)
	)
	(footprint "antmicro-footprints:R_0402_1005Metric"
		(layer "F.Cu")
		(at 137.624499 173.049 -90)
		(descr "Resistor SMD 0402")
		(tags "resistor SMD 0402")
		(property "Reference" "R48"
			(at 1.127672 -0.427658 90)
			(layer "F.SilkS")
			(effects
				(font
					(size 0.7 0.7)
					(thickness 0.15)
				)
				(justify right bottom)
			)
		)
		(property "Value" "R_22R_0402"
			(at -1.011843 1.772047 90)
			(layer "F.Fab")
			(effects
				(font
					(size 0.7 0.7)
					(thickness 0.15)
				)
				(justify right bottom)
			)
		)
		(property "Datasheet" "https://www.bourns.com/docs/product-datasheets/cr.pdf"
			(at 0 0 270)
			(layer "F.Fab")
			(hide yes)
			(effects
				(font
					(size 1.27 1.27)
					(thickness 0.15)
				)
			)
		)
		(property "Manufacturer" "Bourns"
			(at 0 0 270)
			(unlocked yes)
			(layer "F.Fab")
			(hide yes)
			(effects
				(font
					(size 1 1)
					(thickness 0.15)
				)
			)
		)
		(property "MPN" "CR0402-FX-22R0GLF"
			(at 0 0 270)
			(unlocked yes)
			(layer "F.Fab")
			(hide yes)
			(effects
				(font
					(size 1 1)
					(thickness 0.15)
				)
			)
		)
		(property "Val" "22R"
			(at 0 0 270)
			(unlocked yes)
			(layer "F.Fab")
			(hide yes)
			(effects
				(font
					(size 1 1)
					(thickness 0.15)
				)
			)
		)
		(property "License" "Apache-2.0"
			(at 0 0 270)
			(unlocked yes)
			(layer "F.Fab")
			(hide yes)
			(effects
				(font
					(size 1 1)
					(thickness 0.15)
				)
			)
		)
		(property "Author" "Antmicro"
			(at 0 0 270)
			(unlocked yes)
			(layer "F.Fab")
			(hide yes)
			(effects
				(font
					(size 1 1)
					(thickness 0.15)
				)
			)
		)
		(property "Tolerance" "1%"
			(at 0 0 270)
			(unlocked yes)
			(layer "F.Fab")
			(hide yes)
			(effects
				(font
					(size 1 1)
					(thickness 0.15)
				)
			)
		)
		(sheetname "/Debug FTDI + VNA/")
		(sheetfile "debug-ftdi.kicad_sch")
		(attr smd)
		(fp_rect
			(start -0.925 -0.47)
			(end 0.925 0.47)
			(stroke
				(width 0.05)
				(type default)
			)
			(fill no)
			(layer "F.CrtYd")
		)
		(fp_rect
			(start -0.5 -0.25)
			(end 0.5 0.25)
			(stroke
				(width 0.15)
				(type solid)
			)
			(fill no)
			(layer "F.Fab")
		)
		(fp_text user "Author: Antmicro"
			(at -0.95 4.169 270)
			(layer "F.Fab")
			(effects
				(font
					(size 0.7 0.7)
					(thickness 0.15)
				)
				(justify left bottom)
			)
		)
		(fp_text user "License: Apache-2.0"
			(at -0.95 5.169 270)
			(layer "F.Fab")
			(effects
				(font
					(size 0.7 0.7)
					(thickness 0.15)
				)
				(justify left bottom)
			)
		)
		(fp_text user "${REFERENCE}"
			(at -0.95 3.168 270)
			(layer "F.Fab")
			(effects
				(font
					(size 0.7 0.7)
					(thickness 0.15)
				)
				(justify left bottom)
			)
		)
		(pad "1" smd roundrect
			(at -0.48 0 270)
			(size 0.59 0.64)
			(layers "F.Cu" "F.Mask" "F.Paste")
			(roundrect_rratio 0.25)
			(net 298 "Net-(U7-B2Y)")
			(pintype "passive")
		)
		(pad "2" smd roundrect
			(at 0.48 0 270)
			(size 0.59 0.64)
			(layers "F.Cu" "F.Mask" "F.Paste")
			(roundrect_rratio 0.25)
			(net 239 "/Debug FTDI + VNA/JTAG.TCK")
			(pintype "passive")
		)
	)
	(footprint "antmicro-footprints:R_0402_1005Metric"
		(layer "F.Cu")
		(at 135.424499 173.049 -90)
		(descr "Resistor SMD 0402")
		(tags "resistor SMD 0402")
		(property "Reference" "R50"
			(at 1.127672 -0.427658 90)
			(layer "F.SilkS")
			(effects
				(font
					(size 0.7 0.7)
					(thickness 0.15)
				)
				(justify right bottom)
			)
		)
		(property "Value" "R_22R_0402"
			(at -1.011843 1.772047 90)
			(layer "F.Fab")
			(effects
				(font
					(size 0.7 0.7)
					(thickness 0.15)
				)
				(justify right bottom)
			)
		)
		(property "Datasheet" "https://www.bourns.com/docs/product-datasheets/cr.pdf"
			(at 0 0 270)
			(layer "F.Fab")
			(hide yes)
			(effects
				(font
					(size 1.27 1.27)
					(thickness 0.15)
				)
			)
		)
		(property "Manufacturer" "Bourns"
			(at 0 0 270)
			(unlocked yes)
			(layer "F.Fab")
			(hide yes)
			(effects
				(font
					(size 1 1)
					(thickness 0.15)
				)
			)
		)
		(property "MPN" "CR0402-FX-22R0GLF"
			(at 0 0 270)
			(unlocked yes)
			(layer "F.Fab")
			(hide yes)
			(effects
				(font
					(size 1 1)
					(thickness 0.15)
				)
			)
		)
		(property "Val" "22R"
			(at 0 0 270)
			(unlocked yes)
			(layer "F.Fab")
			(hide yes)
			(effects
				(font
					(size 1 1)
					(thickness 0.15)
				)
			)
		)
		(property "License" "Apache-2.0"
			(at 0 0 270)
			(unlocked yes)
			(layer "F.Fab")
			(hide yes)
			(effects
				(font
					(size 1 1)
					(thickness 0.15)
				)
			)
		)
		(property "Author" "Antmicro"
			(at 0 0 270)
			(unlocked yes)
			(layer "F.Fab")
			(hide yes)
			(effects
				(font
					(size 1 1)
					(thickness 0.15)
				)
			)
		)
		(property "Tolerance" "1%"
			(at 0 0 270)
			(unlocked yes)
			(layer "F.Fab")
			(hide yes)
			(effects
				(font
					(size 1 1)
					(thickness 0.15)
				)
			)
		)
		(sheetname "/Debug FTDI + VNA/")
		(sheetfile "debug-ftdi.kicad_sch")
		(attr smd)
		(fp_rect
			(start -0.925 -0.47)
			(end 0.925 0.47)
			(stroke
				(width 0.05)
				(type default)
			)
			(fill no)
			(layer "F.CrtYd")
		)
		(fp_rect
			(start -0.5 -0.25)
			(end 0.5 0.25)
			(stroke
				(width 0.15)
				(type solid)
			)
			(fill no)
			(layer "F.Fab")
		)
		(fp_text user "Author: Antmicro"
			(at -0.95 4.169 270)
			(layer "F.Fab")
			(effects
				(font
					(size 0.7 0.7)
					(thickness 0.15)
				)
				(justify left bottom)
			)
		)
		(fp_text user "License: Apache-2.0"
			(at -0.95 5.169 270)
			(layer "F.Fab")
			(effects
				(font
					(size 0.7 0.7)
					(thickness 0.15)
				)
				(justify left bottom)
			)
		)
		(fp_text user "${REFERENCE}"
			(at -0.95 3.168 270)
			(layer "F.Fab")
			(effects
				(font
					(size 0.7 0.7)
					(thickness 0.15)
				)
				(justify left bottom)
			)
		)
		(pad "1" smd roundrect
			(at -0.48 0 270)
			(size 0.59 0.64)
			(layers "F.Cu" "F.Mask" "F.Paste")
			(roundrect_rratio 0.25)
			(net 300 "Net-(U7-B4)")
			(pintype "passive")
		)
		(pad "2" smd roundrect
			(at 0.48 0 270)
			(size 0.59 0.64)
			(layers "F.Cu" "F.Mask" "F.Paste")
			(roundrect_rratio 0.25)
			(net 242 "/Debug FTDI + VNA/JTAG.TDO")
			(pintype "passive")
		)
	)
	(footprint "antmicro-footprints:R_0402_1005Metric"
		(layer "F.Cu")
		(at 136.547342 173.047328 -90)
		(descr "Resistor SMD 0402")
		(tags "resistor SMD 0402")
		(property "Reference" "R49"
			(at 1.127672 -0.427658 90)
			(layer "F.SilkS")
			(effects
				(font
					(size 0.7 0.7)
					(thickness 0.15)
				)
				(justify right bottom)
			)
		)
		(property "Value" "R_22R_0402"
			(at -1.011843 1.772047 90)
			(layer "F.Fab")
			(effects
				(font
					(size 0.7 0.7)
					(thickness 0.15)
				)
				(justify right bottom)
			)
		)
		(property "Datasheet" "https://www.bourns.com/docs/product-datasheets/cr.pdf"
			(at 0 0 270)
			(layer "F.Fab")
			(hide yes)
			(effects
				(font
					(size 1.27 1.27)
					(thickness 0.15)
				)
			)
		)
		(property "Manufacturer" "Bourns"
			(at 0 0 270)
			(unlocked yes)
			(layer "F.Fab")
			(hide yes)
			(effects
				(font
					(size 1 1)
					(thickness 0.15)
				)
			)
		)
		(property "MPN" "CR0402-FX-22R0GLF"
			(at 0 0 270)
			(unlocked yes)
			(layer "F.Fab")
			(hide yes)
			(effects
				(font
					(size 1 1)
					(thickness 0.15)
				)
			)
		)
		(property "Val" "22R"
			(at 0 0 270)
			(unlocked yes)
			(layer "F.Fab")
			(hide yes)
			(effects
				(font
					(size 1 1)
					(thickness 0.15)
				)
			)
		)
		(property "License" "Apache-2.0"
			(at 0 0 270)
			(unlocked yes)
			(layer "F.Fab")
			(hide yes)
			(effects
				(font
					(size 1 1)
					(thickness 0.15)
				)
			)
		)
		(property "Author" "Antmicro"
			(at 0 0 270)
			(unlocked yes)
			(layer "F.Fab")
			(hide yes)
			(effects
				(font
					(size 1 1)
					(thickness 0.15)
				)
			)
		)
		(property "Tolerance" "1%"
			(at 0 0 270)
			(unlocked yes)
			(layer "F.Fab")
			(hide yes)
			(effects
				(font
					(size 1 1)
					(thickness 0.15)
				)
			)
		)
		(sheetname "/Debug FTDI + VNA/")
		(sheetfile "debug-ftdi.kicad_sch")
		(attr smd)
		(fp_rect
			(start -0.925 -0.47)
			(end 0.925 0.47)
			(stroke
				(width 0.05)
				(type default)
			)
			(fill no)
			(layer "F.CrtYd")
		)
		(fp_rect
			(start -0.5 -0.25)
			(end 0.5 0.25)
			(stroke
				(width 0.15)
				(type solid)
			)
			(fill no)
			(layer "F.Fab")
		)
		(fp_text user "License: Apache-2.0"
			(at -0.95 5.169 270)
			(layer "F.Fab")
			(effects
				(font
					(size 0.7 0.7)
					(thickness 0.15)
				)
				(justify left bottom)
			)
		)
		(fp_text user "Author: Antmicro"
			(at -0.95 4.169 270)
			(layer "F.Fab")
			(effects
				(font
					(size 0.7 0.7)
					(thickness 0.15)
				)
				(justify left bottom)
			)
		)
		(fp_text user "${REFERENCE}"
			(at -0.95 3.168 270)
			(layer "F.Fab")
			(effects
				(font
					(size 0.7 0.7)
					(thickness 0.15)
				)
				(justify left bottom)
			)
		)
		(pad "1" smd roundrect
			(at -0.48 0 270)
			(size 0.59 0.64)
			(layers "F.Cu" "F.Mask" "F.Paste")
			(roundrect_rratio 0.25)
			(net 299 "Net-(U7-B3Y)")
			(pintype "passive")
		)
		(pad "2" smd roundrect
			(at 0.48 0 270)
			(size 0.59 0.64)
			(layers "F.Cu" "F.Mask" "F.Paste")
			(roundrect_rratio 0.25)
			(net 244 "/Debug FTDI + VNA/JTAG.TDI")
			(pintype "passive")
		)
	)
	(footprint "antmicro-footprints:R_0402_1005Metric"
		(layer "F.Cu")
		(at 138.724499 173.049 -90)
		(descr "Resistor SMD 0402")
		(tags "resistor SMD 0402")
		(property "Reference" "R47"
			(at 1.127672 -0.427658 90)
			(layer "F.SilkS")
			(effects
				(font
					(size 0.7 0.7)
					(thickness 0.15)
				)
				(justify right bottom)
			)
		)
		(property "Value" "R_22R_0402"
			(at -1.011843 1.772047 90)
			(layer "F.Fab")
			(effects
				(font
					(size 0.7 0.7)
					(thickness 0.15)
				)
				(justify right bottom)
			)
		)
		(property "Datasheet" "https://www.bourns.com/docs/product-datasheets/cr.pdf"
			(at 0 0 270)
			(layer "F.Fab")
			(hide yes)
			(effects
				(font
					(size 1.27 1.27)
					(thickness 0.15)
				)
			)
		)
		(property "Manufacturer" "Bourns"
			(at 0 0 270)
			(unlocked yes)
			(layer "F.Fab")
			(hide yes)
			(effects
				(font
					(size 1 1)
					(thickness 0.15)
				)
			)
		)
		(property "MPN" "CR0402-FX-22R0GLF"
			(at 0 0 270)
			(unlocked yes)
			(layer "F.Fab")
			(hide yes)
			(effects
				(font
					(size 1 1)
					(thickness 0.15)
				)
			)
		)
		(property "Val" "22R"
			(at 0 0 270)
			(unlocked yes)
			(layer "F.Fab")
			(hide yes)
			(effects
				(font
					(size 1 1)
					(thickness 0.15)
				)
			)
		)
		(property "License" "Apache-2.0"
			(at 0 0 270)
			(unlocked yes)
			(layer "F.Fab")
			(hide yes)
			(effects
				(font
					(size 1 1)
					(thickness 0.15)
				)
			)
		)
		(property "Author" "Antmicro"
			(at 0 0 270)
			(unlocked yes)
			(layer "F.Fab")
			(hide yes)
			(effects
				(font
					(size 1 1)
					(thickness 0.15)
				)
			)
		)
		(property "Tolerance" "1%"
			(at 0 0 270)
			(unlocked yes)
			(layer "F.Fab")
			(hide yes)
			(effects
				(font
					(size 1 1)
					(thickness 0.15)
				)
			)
		)
		(sheetname "/Debug FTDI + VNA/")
		(sheetfile "debug-ftdi.kicad_sch")
		(attr smd)
		(fp_rect
			(start -0.925 -0.47)
			(end 0.925 0.47)
			(stroke
				(width 0.05)
				(type default)
			)
			(fill no)
			(layer "F.CrtYd")
		)
		(fp_rect
			(start -0.5 -0.25)
			(end 0.5 0.25)
			(stroke
				(width 0.15)
				(type solid)
			)
			(fill no)
			(layer "F.Fab")
		)
		(fp_text user "License: Apache-2.0"
			(at -0.95 5.169 270)
			(layer "F.Fab")
			(effects
				(font
					(size 0.7 0.7)
					(thickness 0.15)
				)
				(justify left bottom)
			)
		)
		(fp_text user "${REFERENCE}"
			(at -0.95 3.168 270)
			(layer "F.Fab")
			(effects
				(font
					(size 0.7 0.7)
					(thickness 0.15)
				)
				(justify left bottom)
			)
		)
		(fp_text user "Author: Antmicro"
			(at -0.95 4.169 270)
			(layer "F.Fab")
			(effects
				(font
					(size 0.7 0.7)
					(thickness 0.15)
				)
				(justify left bottom)
			)
		)
		(pad "1" smd roundrect
			(at -0.48 0 270)
			(size 0.59 0.64)
			(layers "F.Cu" "F.Mask" "F.Paste")
			(roundrect_rratio 0.25)
			(net 296 "Net-(U7-B1Y)")
			(pintype "passive")
		)
		(pad "2" smd roundrect
			(at 0.48 0 270)
			(size 0.59 0.64)
			(layers "F.Cu" "F.Mask" "F.Paste")
			(roundrect_rratio 0.25)
			(net 238 "/Debug FTDI + VNA/JTAG.TMS")
			(pintype "passive")
		)
	)
	(footprint "antmicro-footprints:C_0402_1005Metric"
		(layer "F.Cu")
		(at 140.396843 156.001328 90)
		(descr "Capacitor SMD 0402")
		(tags "capacitor SMD 0402")
		(property "Reference" "C115"
			(at 1.001328 0.403157 90)
			(layer "F.SilkS")
			(effects
				(font
					(size 0.7 0.7)
					(thickness 0.15)
				)
				(justify left bottom)
			)
		)
		(property "Value" "C_100n_0402"
			(at -1.022927 2.155213 90)
			(layer "F.Fab")
			(effects
				(font
					(size 0.7 0.7)
					(thickness 0.15)
				)
				(justify left bottom)
			)
		)
		(property "Datasheet" "https://www.murata.com/products/productdetail?partno=GRM155R61H104KE14%23"
			(at 0 0 90)
			(layer "F.Fab")
			(hide yes)
			(effects
				(font
					(size 1.27 1.27)
					(thickness 0.15)
				)
			)
		)
		(property "Manufacturer" "Murata"
			(at 0 0 90)
			(unlocked yes)
			(layer "F.Fab")
			(hide yes)
			(effects
				(font
					(size 1 1)
					(thickness 0.15)
				)
			)
		)
		(property "MPN" "GRM155R61H104KE14D"
			(at 0 0 90)
			(unlocked yes)
			(layer "F.Fab")
			(hide yes)
			(effects
				(font
					(size 1 1)
					(thickness 0.15)
				)
			)
		)
		(property "Val" "100n"
			(at 0 0 90)
			(unlocked yes)
			(layer "F.Fab")
			(hide yes)
			(effects
				(font
					(size 1 1)
					(thickness 0.15)
				)
			)
		)
		(property "License" "Apache-2.0"
			(at 0 0 90)
			(unlocked yes)
			(layer "F.Fab")
			(hide yes)
			(effects
				(font
					(size 1 1)
					(thickness 0.15)
				)
			)
		)
		(property "Author" "Antmicro"
			(at 0 0 90)
			(unlocked yes)
			(layer "F.Fab")
			(hide yes)
			(effects
				(font
					(size 1 1)
					(thickness 0.15)
				)
			)
		)
		(property "Voltage" "50V"
			(at 0 0 90)
			(unlocked yes)
			(layer "F.Fab")
			(hide yes)
			(effects
				(font
					(size 1 1)
					(thickness 0.15)
				)
			)
		)
		(property "Dielectric" "X5R"
			(at 0 0 90)
			(unlocked yes)
			(layer "F.Fab")
			(hide yes)
			(effects
				(font
					(size 1 1)
					(thickness 0.15)
				)
			)
		)
		(sheetname "/Debug FTDI + VNA/")
		(sheetfile "debug-ftdi.kicad_sch")
		(attr smd)
		(fp_rect
			(start -0.925 -0.47)
			(end 0.925 0.47)
			(stroke
				(width 0.05)
				(type default)
			)
			(fill no)
			(layer "F.CrtYd")
		)
		(fp_line
			(start 0.504 -0.25)
			(end 0.504 0.248)
			(stroke
				(width 0.15)
				(type solid)
			)
			(layer "F.Fab")
		)
		(fp_line
			(start -0.494 -0.25)
			(end 0.504 -0.25)
			(stroke
				(width 0.15)
				(type solid)
			)
			(layer "F.Fab")
		)
		(fp_line
			(start 0.504 0.248)
			(end -0.494 0.248)
			(stroke
				(width 0.15)
				(type solid)
			)
			(layer "F.Fab")
		)
		(fp_line
			(start -0.494 0.248)
			(end -0.494 -0.25)
			(stroke
				(width 0.15)
				(type solid)
			)
			(layer "F.Fab")
		)
		(fp_text user "Author: Antmicro"
			(at -0.939 3.399 90)
			(layer "F.Fab")
			(effects
				(font
					(size 0.7 0.7)
					(thickness 0.15)
				)
				(justify left bottom)
			)
		)
		(fp_text user "${REFERENCE}"
			(at -0.939 4.599 90)
			(layer "F.Fab")
			(effects
				(font
					(size 0.7 0.7)
					(thickness 0.15)
				)
				(justify left bottom)
			)
		)
		(fp_text user "License: Apache-2.0"
			(at -0.939 5.799 90)
			(layer "F.Fab")
			(effects
				(font
					(size 0.7 0.7)
					(thickness 0.15)
				)
				(justify left bottom)
			)
		)
		(pad "1" smd roundrect
			(at -0.48 0 90)
			(size 0.59 0.64)
			(layers "F.Cu" "F.Mask" "F.Paste")
			(roundrect_rratio 0.25)
			(net 6 "/Debug FTDI + VNA/FTDI_3V3")
			(pintype "passive")
		)
		(pad "2" smd roundrect
			(at 0.48 0 90)
			(size 0.59 0.64)
			(layers "F.Cu" "F.Mask" "F.Paste")
			(roundrect_rratio 0.25)
			(net 1 "GND")
			(pintype "passive")
		)
	)
	(footprint "antmicro-footprints:C_0402_1005Metric"
		(layer "F.Cu")
		(at 137.184328 155.996157 90)
		(descr "Capacitor SMD 0402")
		(tags "capacitor SMD 0402")
		(property "Reference" "C111"
			(at 1.296157 0.765672 90)
			(layer "F.SilkS")
			(effects
				(font
					(size 0.7 0.7)
					(thickness 0.15)
				)
				(justify left bottom)
			)
		)
		(property "Value" "C_18p_0402"
			(at -1.022927 2.155213 90)
			(layer "F.Fab")
			(effects
				(font
					(size 0.7 0.7)
					(thickness 0.15)
				)
				(justify left bottom)
			)
		)
		(property "Datasheet" "https://product.samsungsem.com/mlcc/CL05C180JB51PN.do"
			(at 0 0 90)
			(layer "F.Fab")
			(hide yes)
			(effects
				(font
					(size 1.27 1.27)
					(thickness 0.15)
				)
			)
		)
		(property "Manufacturer" "Samsung Electro-Mechanics"
			(at 0 0 90)
			(unlocked yes)
			(layer "F.Fab")
			(hide yes)
			(effects
				(font
					(size 1 1)
					(thickness 0.15)
				)
			)
		)
		(property "MPN" "CL05C180JB51PNC"
			(at 0 0 90)
			(unlocked yes)
			(layer "F.Fab")
			(hide yes)
			(effects
				(font
					(size 1 1)
					(thickness 0.15)
				)
			)
		)
		(property "Val" "18p"
			(at 0 0 90)
			(unlocked yes)
			(layer "F.Fab")
			(hide yes)
			(effects
				(font
					(size 1 1)
					(thickness 0.15)
				)
			)
		)
		(property "License" "Apache-2.0"
			(at 0 0 90)
			(unlocked yes)
			(layer "F.Fab")
			(hide yes)
			(effects
				(font
					(size 1 1)
					(thickness 0.15)
				)
			)
		)
		(property "Author" "Antmicro"
			(at 0 0 90)
			(unlocked yes)
			(layer "F.Fab")
			(hide yes)
			(effects
				(font
					(size 1 1)
					(thickness 0.15)
				)
			)
		)
		(property "Voltage" ""
			(at 0 0 90)
			(unlocked yes)
			(layer "F.Fab")
			(hide yes)
			(effects
				(font
					(size 1 1)
					(thickness 0.15)
				)
			)
		)
		(property "Dielectric" ""
			(at 0 0 90)
			(unlocked yes)
			(layer "F.Fab")
			(hide yes)
			(effects
				(font
					(size 1 1)
					(thickness 0.15)
				)
			)
		)
		(sheetname "/Debug FTDI + VNA/")
		(sheetfile "debug-ftdi.kicad_sch")
		(attr smd)
		(fp_rect
			(start -0.925 -0.47)
			(end 0.925 0.47)
			(stroke
				(width 0.05)
				(type default)
			)
			(fill no)
			(layer "F.CrtYd")
		)
		(fp_line
			(start 0.504 -0.25)
			(end 0.504 0.248)
			(stroke
				(width 0.15)
				(type solid)
			)
			(layer "F.Fab")
		)
		(fp_line
			(start -0.494 -0.25)
			(end 0.504 -0.25)
			(stroke
				(width 0.15)
				(type solid)
			)
			(layer "F.Fab")
		)
		(fp_line
			(start 0.504 0.248)
			(end -0.494 0.248)
			(stroke
				(width 0.15)
				(type solid)
			)
			(layer "F.Fab")
		)
		(fp_line
			(start -0.494 0.248)
			(end -0.494 -0.25)
			(stroke
				(width 0.15)
				(type solid)
			)
			(layer "F.Fab")
		)
		(fp_text user "Author: Antmicro"
			(at -0.939 3.399 90)
			(layer "F.Fab")
			(effects
				(font
					(size 0.7 0.7)
					(thickness 0.15)
				)
				(justify left bottom)
			)
		)
		(fp_text user "License: Apache-2.0"
			(at -0.939 5.799 90)
			(layer "F.Fab")
			(effects
				(font
					(size 0.7 0.7)
					(thickness 0.15)
				)
				(justify left bottom)
			)
		)
		(fp_text user "${REFERENCE}"
			(at -0.939 4.599 90)
			(layer "F.Fab")
			(effects
				(font
					(size 0.7 0.7)
					(thickness 0.15)
				)
				(justify left bottom)
			)
		)
		(pad "1" smd roundrect
			(at -0.48 0 90)
			(size 0.59 0.64)
			(layers "F.Cu" "F.Mask" "F.Paste")
			(roundrect_rratio 0.25)
			(net 4 "/Debug FTDI + VNA/FTDI_XI")
			(pintype "passive")
		)
		(pad "2" smd roundrect
			(at 0.48 0 90)
			(size 0.59 0.64)
			(layers "F.Cu" "F.Mask" "F.Paste")
			(roundrect_rratio 0.25)
			(net 1 "GND")
			(pintype "passive")
		)
	)
	(footprint "antmicro-footprints:C_0402_1005Metric"
		(layer "F.Cu")
		(at 141.024499 169.049 -90)
		(descr "Capacitor SMD 0402")
		(tags "capacitor SMD 0402")
		(property "Reference" "C119"
			(at -1.099 -2.225501 90)
			(layer "F.SilkS")
			(effects
				(font
					(size 0.7 0.7)
					(thickness 0.15)
				)
				(justify right bottom)
			)
		)
		(property "Value" "C_100n_0402"
			(at -1.022927 2.155213 90)
			(layer "F.Fab")
			(effects
				(font
					(size 0.7 0.7)
					(thickness 0.15)
				)
				(justify right bottom)
			)
		)
		(property "Datasheet" "https://www.murata.com/products/productdetail?partno=GRM155R61H104KE14%23"
			(at 0 0 270)
			(layer "F.Fab")
			(hide yes)
			(effects
				(font
					(size 1.27 1.27)
					(thickness 0.15)
				)
			)
		)
		(property "Manufacturer" "Murata"
			(at 0 0 270)
			(unlocked yes)
			(layer "F.Fab")
			(hide yes)
			(effects
				(font
					(size 1 1)
					(thickness 0.15)
				)
			)
		)
		(property "MPN" "GRM155R61H104KE14D"
			(at 0 0 270)
			(unlocked yes)
			(layer "F.Fab")
			(hide yes)
			(effects
				(font
					(size 1 1)
					(thickness 0.15)
				)
			)
		)
		(property "Val" "100n"
			(at 0 0 270)
			(unlocked yes)
			(layer "F.Fab")
			(hide yes)
			(effects
				(font
					(size 1 1)
					(thickness 0.15)
				)
			)
		)
		(property "License" "Apache-2.0"
			(at 0 0 270)
			(unlocked yes)
			(layer "F.Fab")
			(hide yes)
			(effects
				(font
					(size 1 1)
					(thickness 0.15)
				)
			)
		)
		(property "Author" "Antmicro"
			(at 0 0 270)
			(unlocked yes)
			(layer "F.Fab")
			(hide yes)
			(effects
				(font
					(size 1 1)
					(thickness 0.15)
				)
			)
		)
		(property "Voltage" "50V"
			(at 0 0 270)
			(unlocked yes)
			(layer "F.Fab")
			(hide yes)
			(effects
				(font
					(size 1 1)
					(thickness 0.15)
				)
			)
		)
		(property "Dielectric" "X5R"
			(at 0 0 270)
			(unlocked yes)
			(layer "F.Fab")
			(hide yes)
			(effects
				(font
					(size 1 1)
					(thickness 0.15)
				)
			)
		)
		(sheetname "/Debug FTDI + VNA/")
		(sheetfile "debug-ftdi.kicad_sch")
		(attr smd)
		(fp_rect
			(start -0.925 -0.47)
			(end 0.925 0.47)
			(stroke
				(width 0.05)
				(type default)
			)
			(fill no)
			(layer "F.CrtYd")
		)
		(fp_line
			(start -0.494 0.248)
			(end -0.494 -0.25)
			(stroke
				(width 0.15)
				(type solid)
			)
			(layer "F.Fab")
		)
		(fp_line
			(start 0.504 0.248)
			(end -0.494 0.248)
			(stroke
				(width 0.15)
				(type solid)
			)
			(layer "F.Fab")
		)
		(fp_line
			(start -0.494 -0.25)
			(end 0.504 -0.25)
			(stroke
				(width 0.15)
				(type solid)
			)
			(layer "F.Fab")
		)
		(fp_line
			(start 0.504 -0.25)
			(end 0.504 0.248)
			(stroke
				(width 0.15)
				(type solid)
			)
			(layer "F.Fab")
		)
		(fp_text user "Author: Antmicro"
			(at -0.939 3.399 270)
			(layer "F.Fab")
			(effects
				(font
					(size 0.7 0.7)
					(thickness 0.15)
				)
				(justify left bottom)
			)
		)
		(fp_text user "License: Apache-2.0"
			(at -0.939 5.799 270)
			(layer "F.Fab")
			(effects
				(font
					(size 0.7 0.7)
					(thickness 0.15)
				)
				(justify left bottom)
			)
		)
		(fp_text user "${REFERENCE}"
			(at -0.939 4.599 270)
			(layer "F.Fab")
			(effects
				(font
					(size 0.7 0.7)
					(thickness 0.15)
				)
				(justify left bottom)
			)
		)
		(pad "1" smd roundrect
			(at -0.48 0 270)
			(size 0.59 0.64)
			(layers "F.Cu" "F.Mask" "F.Paste")
			(roundrect_rratio 0.25)
			(net 6 "/Debug FTDI + VNA/FTDI_3V3")
			(pintype "passive")
		)
		(pad "2" smd roundrect
			(at 0.48 0 270)
			(size 0.59 0.64)
			(layers "F.Cu" "F.Mask" "F.Paste")
			(roundrect_rratio 0.25)
			(net 1 "GND")
			(pintype "passive")
		)
	)
	(footprint "antmicro-footprints:C_0402_1005Metric"
		(layer "F.Cu")
		(at 148.591843 165.716328)
		(descr "Capacitor SMD 0402")
		(tags "capacitor SMD 0402")
		(property "Reference" "C122"
			(at 0.928157 0.413672 0)
			(layer "F.SilkS")
			(effects
				(font
					(size 0.7 0.7)
					(thickness 0.15)
				)
				(justify left bottom)
			)
		)
		(property "Value" "C_4u7_0402"
			(at -1.022927 2.155213 0)
			(layer "F.Fab")
			(effects
				(font
					(size 0.7 0.7)
					(thickness 0.15)
				)
				(justify left bottom)
			)
		)
		(property "Datasheet" "https://www.murata.com/products/productdetail?partno=GRM155R61A475MEAA%23"
			(at 0 0 0)
			(layer "F.Fab")
			(hide yes)
			(effects
				(font
					(size 1.27 1.27)
					(thickness 0.15)
				)
			)
		)
		(property "Manufacturer" "Murata"
			(at 0 0 0)
			(unlocked yes)
			(layer "F.Fab")
			(hide yes)
			(effects
				(font
					(size 1 1)
					(thickness 0.15)
				)
			)
		)
		(property "MPN" "GRM155R61A475MEAAD"
			(at 0 0 0)
			(unlocked yes)
			(layer "F.Fab")
			(hide yes)
			(effects
				(font
					(size 1 1)
					(thickness 0.15)
				)
			)
		)
		(property "Val" "4u7"
			(at 0 0 0)
			(unlocked yes)
			(layer "F.Fab")
			(hide yes)
			(effects
				(font
					(size 1 1)
					(thickness 0.15)
				)
			)
		)
		(property "License" "Apache-2.0"
			(at 0 0 0)
			(unlocked yes)
			(layer "F.Fab")
			(hide yes)
			(effects
				(font
					(size 1 1)
					(thickness 0.15)
				)
			)
		)
		(property "Author" "Antmicro"
			(at 0 0 0)
			(unlocked yes)
			(layer "F.Fab")
			(hide yes)
			(effects
				(font
					(size 1 1)
					(thickness 0.15)
				)
			)
		)
		(property "Voltage" ""
			(at 0 0 0)
			(unlocked yes)
			(layer "F.Fab")
			(hide yes)
			(effects
				(font
					(size 1 1)
					(thickness 0.15)
				)
			)
		)
		(property "Dielectric" ""
			(at 0 0 0)
			(unlocked yes)
			(layer "F.Fab")
			(hide yes)
			(effects
				(font
					(size 1 1)
					(thickness 0.15)
				)
			)
		)
		(sheetname "/Debug FTDI + VNA/")
		(sheetfile "debug-ftdi.kicad_sch")
		(attr smd)
		(fp_rect
			(start -0.925 -0.47)
			(end 0.925 0.47)
			(stroke
				(width 0.05)
				(type default)
			)
			(fill no)
			(layer "F.CrtYd")
		)
		(fp_line
			(start -0.494 -0.25)
			(end 0.504 -0.25)
			(stroke
				(width 0.15)
				(type solid)
			)
			(layer "F.Fab")
		)
		(fp_line
			(start -0.494 0.248)
			(end -0.494 -0.25)
			(stroke
				(width 0.15)
				(type solid)
			)
			(layer "F.Fab")
		)
		(fp_line
			(start 0.504 -0.25)
			(end 0.504 0.248)
			(stroke
				(width 0.15)
				(type solid)
			)
			(layer "F.Fab")
		)
		(fp_line
			(start 0.504 0.248)
			(end -0.494 0.248)
			(stroke
				(width 0.15)
				(type solid)
			)
			(layer "F.Fab")
		)
		(fp_text user "${REFERENCE}"
			(at -0.939 4.599 0)
			(layer "F.Fab")
			(effects
				(font
					(size 0.7 0.7)
					(thickness 0.15)
				)
				(justify left bottom)
			)
		)
		(fp_text user "License: Apache-2.0"
			(at -0.939 5.799 0)
			(layer "F.Fab")
			(effects
				(font
					(size 0.7 0.7)
					(thickness 0.15)
				)
				(justify left bottom)
			)
		)
		(fp_text user "Author: Antmicro"
			(at -0.939 3.399 0)
			(layer "F.Fab")
			(effects
				(font
					(size 0.7 0.7)
					(thickness 0.15)
				)
				(justify left bottom)
			)
		)
		(pad "1" smd roundrect
			(at -0.48 0)
			(size 0.59 0.64)
			(layers "F.Cu" "F.Mask" "F.Paste")
			(roundrect_rratio 0.25)
			(net 34 "/Debug FTDI + VNA/FTDI_VCORE")
			(pintype "passive")
		)
		(pad "2" smd roundrect
			(at 0.48 0)
			(size 0.59 0.64)
			(layers "F.Cu" "F.Mask" "F.Paste")
			(roundrect_rratio 0.25)
			(net 1 "GND")
			(pintype "passive")
		)
	)
	(footprint "antmicro-footprints:FB_0603_1608Metric"
		(layer "F.Cu")
		(at 132.435 159.484 -90)
		(property "Reference" "FB2"
			(at -0.584 0.935 90)
			(layer "F.SilkS")
			(effects
				(font
					(size 0.7 0.7)
					(thickness 0.15)
				)
				(justify right bottom)
			)
		)
		(property "Value" "FB_600Z_0.5A_Murata-BLM18AG_0603"
			(at 0 1.5 90)
			(layer "F.Fab")
			(effects
				(font
					(size 0.7 0.7)
					(thickness 0.15)
				)
				(justify right bottom)
			)
		)
		(property "Datasheet" "https://www.murata.com/en-us/products/productdata/8796738650142/ENFA0003.pdf"
			(at 0 0 270)
			(layer "F.Fab")
			(hide yes)
			(effects
				(font
					(size 1.27 1.27)
					(thickness 0.15)
				)
			)
		)
		(property "Val" "600Z/0.5A"
			(at 0 0 270)
			(unlocked yes)
			(layer "F.Fab")
			(hide yes)
			(effects
				(font
					(size 1 1)
					(thickness 0.15)
				)
			)
		)
		(property "MPN" "BLM18AG601SN1D"
			(at 0 0 270)
			(unlocked yes)
			(layer "F.Fab")
			(hide yes)
			(effects
				(font
					(size 1 1)
					(thickness 0.15)
				)
			)
		)
		(property "Manufacturer" "Murata"
			(at 0 0 270)
			(unlocked yes)
			(layer "F.Fab")
			(hide yes)
			(effects
				(font
					(size 1 1)
					(thickness 0.15)
				)
			)
		)
		(property "Author" "Antmicro"
			(at 0 0 270)
			(unlocked yes)
			(layer "F.Fab")
			(hide yes)
			(effects
				(font
					(size 1 1)
					(thickness 0.15)
				)
			)
		)
		(property "License" "Apache-2.0"
			(at 0 0 270)
			(unlocked yes)
			(layer "F.Fab")
			(hide yes)
			(effects
				(font
					(size 1 1)
					(thickness 0.15)
				)
			)
		)
		(sheetname "/Debug FTDI + VNA/")
		(sheetfile "debug-ftdi.kicad_sch")
		(attr smd)
		(fp_line
			(start -0.15 0.4)
			(end 0.15 0.4)
			(stroke
				(width 0.15)
				(type solid)
			)
			(layer "F.SilkS")
		)
		(fp_line
			(start -0.15 -0.4)
			(end 0.15 -0.4)
			(stroke
				(width 0.15)
				(type solid)
			)
			(layer "F.SilkS")
		)
		(fp_rect
			(start -1.25 -0.65)
			(end 1.25 0.65)
			(stroke
				(width 0.05)
				(type solid)
			)
			(fill no)
			(layer "F.CrtYd")
		)
		(fp_line
			(start -0.803 0.406)
			(end -0.803 -0.408)
			(stroke
				(width 0.15)
				(type solid)
			)
			(layer "F.Fab")
		)
		(fp_line
			(start 0.8 0.406)
			(end -0.803 0.406)
			(stroke
				(width 0.15)
				(type solid)
			)
			(layer "F.Fab")
		)
		(fp_line
			(start 0.8 -0.408)
			(end 0.8 0.406)
			(stroke
				(width 0.15)
				(type solid)
			)
			(layer "F.Fab")
		)
		(fp_line
			(start 0.8 -0.408)
			(end -0.803 -0.408)
			(stroke
				(width 0.15)
				(type solid)
			)
			(layer "F.Fab")
		)
		(fp_text user "Author: Antmicro"
			(at -1.653 3.162 270)
			(layer "F.Fab")
			(effects
				(font
					(size 0.7 0.7)
					(thickness 0.15)
				)
				(justify left bottom)
			)
		)
		(fp_text user "${REFERENCE}"
			(at -1.653 4.6 270)
			(layer "F.Fab")
			(effects
				(font
					(size 0.7 0.7)
					(thickness 0.15)
				)
				(justify left bottom)
			)
		)
		(fp_text user "License: Apache-2.0"
			(at -1.653 5.9 270)
			(layer "F.Fab")
			(effects
				(font
					(size 0.7 0.7)
					(thickness 0.15)
				)
				(justify left bottom)
			)
		)
		(pad "1" smd roundrect
			(at -0.7 0 270)
			(size 0.8 1)
			(layers "F.Cu" "F.Mask" "F.Paste")
			(roundrect_rratio 0.2)
			(net 6 "/Debug FTDI + VNA/FTDI_3V3")
			(pintype "passive")
		)
		(pad "2" smd roundrect
			(at 0.7 0 270)
			(size 0.8 1)
			(layers "F.Cu" "F.Mask" "F.Paste")
			(roundrect_rratio 0.2)
			(net 5 "/Debug FTDI + VNA/FTDI_VPHY")
			(pintype "passive")
		)
	)
	(footprint "antmicro-footprints:R_0402_1005Metric"
		(layer "F.Cu")
		(at 134.176843 161.831328)
		(descr "Resistor SMD 0402")
		(tags "resistor SMD 0402")
		(property "Reference" "R44"
			(at 0.823157 0.468672 0)
			(layer "F.SilkS")
			(effects
				(font
					(size 0.7 0.7)
					(thickness 0.15)
				)
				(justify left bottom)
			)
		)
		(property "Value" "R_12k_0402"
			(at -1.011843 1.772047 0)
			(layer "F.Fab")
			(effects
				(font
					(size 0.7 0.7)
					(thickness 0.15)
				)
				(justify left bottom)
			)
		)
		(property "Datasheet" "https://www.bourns.com/docs/product-datasheets/cr.pdf"
			(at 0 0 0)
			(layer "F.Fab")
			(hide yes)
			(effects
				(font
					(size 1.27 1.27)
					(thickness 0.15)
				)
			)
		)
		(property "Manufacturer" "Bourns"
			(at 0 0 0)
			(unlocked yes)
			(layer "F.Fab")
			(hide yes)
			(effects
				(font
					(size 1 1)
					(thickness 0.15)
				)
			)
		)
		(property "MPN" "CR0402-FX-1202GLF"
			(at 0 0 0)
			(unlocked yes)
			(layer "F.Fab")
			(hide yes)
			(effects
				(font
					(size 1 1)
					(thickness 0.15)
				)
			)
		)
		(property "Val" "12k"
			(at 0 0 0)
			(unlocked yes)
			(layer "F.Fab")
			(hide yes)
			(effects
				(font
					(size 1 1)
					(thickness 0.15)
				)
			)
		)
		(property "License" "Apache-2.0"
			(at 0 0 0)
			(unlocked yes)
			(layer "F.Fab")
			(hide yes)
			(effects
				(font
					(size 1 1)
					(thickness 0.15)
				)
			)
		)
		(property "Author" "Antmicro"
			(at 0 0 0)
			(unlocked yes)
			(layer "F.Fab")
			(hide yes)
			(effects
				(font
					(size 1 1)
					(thickness 0.15)
				)
			)
		)
		(property "Tolerance" "1%"
			(at 0 0 0)
			(unlocked yes)
			(layer "F.Fab")
			(hide yes)
			(effects
				(font
					(size 1 1)
					(thickness 0.15)
				)
			)
		)
		(sheetname "/Debug FTDI + VNA/")
		(sheetfile "debug-ftdi.kicad_sch")
		(attr smd)
		(fp_rect
			(start -0.925 -0.47)
			(end 0.925 0.47)
			(stroke
				(width 0.05)
				(type default)
			)
			(fill no)
			(layer "F.CrtYd")
		)
		(fp_rect
			(start -0.5 -0.25)
			(end 0.5 0.25)
			(stroke
				(width 0.15)
				(type solid)
			)
			(fill no)
			(layer "F.Fab")
		)
		(fp_text user "License: Apache-2.0"
			(at -0.95 5.169 0)
			(layer "F.Fab")
			(effects
				(font
					(size 0.7 0.7)
					(thickness 0.15)
				)
				(justify left bottom)
			)
		)
		(fp_text user "Author: Antmicro"
			(at -0.95 4.169 0)
			(layer "F.Fab")
			(effects
				(font
					(size 0.7 0.7)
					(thickness 0.15)
				)
				(justify left bottom)
			)
		)
		(fp_text user "${REFERENCE}"
			(at -0.95 3.168 0)
			(layer "F.Fab")
			(effects
				(font
					(size 0.7 0.7)
					(thickness 0.15)
				)
				(justify left bottom)
			)
		)
		(pad "1" smd roundrect
			(at -0.48 0)
			(size 0.59 0.64)
			(layers "F.Cu" "F.Mask" "F.Paste")
			(roundrect_rratio 0.25)
			(net 1 "GND")
			(pintype "passive")
		)
		(pad "2" smd roundrect
			(at 0.48 0)
			(size 0.59 0.64)
			(layers "F.Cu" "F.Mask" "F.Paste")
			(roundrect_rratio 0.25)
			(net 293 "Net-(U6-REF)")
			(pintype "passive")
		)
	)
	(footprint "antmicro-footprints:C_0402_1005Metric"
		(layer "F.Cu")
		(at 133.815 164.485 -90)
		(descr "Capacitor SMD 0402")
		(tags "capacitor SMD 0402")
		(property "Reference" "C110"
			(at -0.335 -2.285 90)
			(layer "F.SilkS")
			(effects
				(font
					(size 0.7 0.7)
					(thickness 0.15)
				)
				(justify right bottom)
			)
		)
		(property "Value" "C_100n_0402"
			(at -1.022927 2.155213 90)
			(layer "F.Fab")
			(effects
				(font
					(size 0.7 0.7)
					(thickness 0.15)
				)
				(justify right bottom)
			)
		)
		(property "Datasheet" "https://www.murata.com/products/productdetail?partno=GRM155R61H104KE14%23"
			(at 0 0 270)
			(layer "F.Fab")
			(hide yes)
			(effects
				(font
					(size 1.27 1.27)
					(thickness 0.15)
				)
			)
		)
		(property "Manufacturer" "Murata"
			(at 0 0 270)
			(unlocked yes)
			(layer "F.Fab")
			(hide yes)
			(effects
				(font
					(size 1 1)
					(thickness 0.15)
				)
			)
		)
		(property "MPN" "GRM155R61H104KE14D"
			(at 0 0 270)
			(unlocked yes)
			(layer "F.Fab")
			(hide yes)
			(effects
				(font
					(size 1 1)
					(thickness 0.15)
				)
			)
		)
		(property "Val" "100n"
			(at 0 0 270)
			(unlocked yes)
			(layer "F.Fab")
			(hide yes)
			(effects
				(font
					(size 1 1)
					(thickness 0.15)
				)
			)
		)
		(property "License" "Apache-2.0"
			(at 0 0 270)
			(unlocked yes)
			(layer "F.Fab")
			(hide yes)
			(effects
				(font
					(size 1 1)
					(thickness 0.15)
				)
			)
		)
		(property "Author" "Antmicro"
			(at 0 0 270)
			(unlocked yes)
			(layer "F.Fab")
			(hide yes)
			(effects
				(font
					(size 1 1)
					(thickness 0.15)
				)
			)
		)
		(property "Voltage" "50V"
			(at 0 0 270)
			(unlocked yes)
			(layer "F.Fab")
			(hide yes)
			(effects
				(font
					(size 1 1)
					(thickness 0.15)
				)
			)
		)
		(property "Dielectric" "X5R"
			(at 0 0 270)
			(unlocked yes)
			(layer "F.Fab")
			(hide yes)
			(effects
				(font
					(size 1 1)
					(thickness 0.15)
				)
			)
		)
		(sheetname "/Debug FTDI + VNA/")
		(sheetfile "debug-ftdi.kicad_sch")
		(attr smd)
		(fp_rect
			(start -0.925 -0.47)
			(end 0.925 0.47)
			(stroke
				(width 0.05)
				(type default)
			)
			(fill no)
			(layer "F.CrtYd")
		)
		(fp_line
			(start -0.494 0.248)
			(end -0.494 -0.25)
			(stroke
				(width 0.15)
				(type solid)
			)
			(layer "F.Fab")
		)
		(fp_line
			(start 0.504 0.248)
			(end -0.494 0.248)
			(stroke
				(width 0.15)
				(type solid)
			)
			(layer "F.Fab")
		)
		(fp_line
			(start -0.494 -0.25)
			(end 0.504 -0.25)
			(stroke
				(width 0.15)
				(type solid)
			)
			(layer "F.Fab")
		)
		(fp_line
			(start 0.504 -0.25)
			(end 0.504 0.248)
			(stroke
				(width 0.15)
				(type solid)
			)
			(layer "F.Fab")
		)
		(fp_text user "Author: Antmicro"
			(at -0.939 3.399 270)
			(layer "F.Fab")
			(effects
				(font
					(size 0.7 0.7)
					(thickness 0.15)
				)
				(justify left bottom)
			)
		)
		(fp_text user "License: Apache-2.0"
			(at -0.939 5.799 270)
			(layer "F.Fab")
			(effects
				(font
					(size 0.7 0.7)
					(thickness 0.15)
				)
				(justify left bottom)
			)
		)
		(fp_text user "${REFERENCE}"
			(at -0.939 4.599 270)
			(layer "F.Fab")
			(effects
				(font
					(size 0.7 0.7)
					(thickness 0.15)
				)
				(justify left bottom)
			)
		)
		(pad "1" smd roundrect
			(at -0.48 0 270)
			(size 0.59 0.64)
			(layers "F.Cu" "F.Mask" "F.Paste")
			(roundrect_rratio 0.25)
			(net 3 "/Debug FTDI + VNA/FTDI_VPLL")
			(pintype "passive")
		)
		(pad "2" smd roundrect
			(at 0.48 0 270)
			(size 0.59 0.64)
			(layers "F.Cu" "F.Mask" "F.Paste")
			(roundrect_rratio 0.25)
			(net 1 "GND")
			(pintype "passive")
		)
	)
	(footprint "antmicro-footprints:C_0402_1005Metric"
		(layer "F.Cu")
		(at 134.8135 164.484 -90)
		(descr "Capacitor SMD 0402")
		(tags "capacitor SMD 0402")
		(property "Reference" "C114"
			(at -0.335 -2.285 90)
			(layer "F.SilkS")
			(effects
				(font
					(size 0.7 0.7)
					(thickness 0.15)
				)
				(justify right bottom)
			)
		)
		(property "Value" "C_4u7_0402"
			(at -1.022927 2.155213 90)
			(layer "F.Fab")
			(effects
				(font
					(size 0.7 0.7)
					(thickness 0.15)
				)
				(justify right bottom)
			)
		)
		(property "Datasheet" "https://www.murata.com/products/productdetail?partno=GRM155R61A475MEAA%23"
			(at 0 0 270)
			(layer "F.Fab")
			(hide yes)
			(effects
				(font
					(size 1.27 1.27)
					(thickness 0.15)
				)
			)
		)
		(property "Manufacturer" "Murata"
			(at 0 0 270)
			(unlocked yes)
			(layer "F.Fab")
			(hide yes)
			(effects
				(font
					(size 1 1)
					(thickness 0.15)
				)
			)
		)
		(property "MPN" "GRM155R61A475MEAAD"
			(at 0 0 270)
			(unlocked yes)
			(layer "F.Fab")
			(hide yes)
			(effects
				(font
					(size 1 1)
					(thickness 0.15)
				)
			)
		)
		(property "Val" "4u7"
			(at 0 0 270)
			(unlocked yes)
			(layer "F.Fab")
			(hide yes)
			(effects
				(font
					(size 1 1)
					(thickness 0.15)
				)
			)
		)
		(property "License" "Apache-2.0"
			(at 0 0 270)
			(unlocked yes)
			(layer "F.Fab")
			(hide yes)
			(effects
				(font
					(size 1 1)
					(thickness 0.15)
				)
			)
		)
		(property "Author" "Antmicro"
			(at 0 0 270)
			(unlocked yes)
			(layer "F.Fab")
			(hide yes)
			(effects
				(font
					(size 1 1)
					(thickness 0.15)
				)
			)
		)
		(property "Voltage" ""
			(at 0 0 270)
			(unlocked yes)
			(layer "F.Fab")
			(hide yes)
			(effects
				(font
					(size 1 1)
					(thickness 0.15)
				)
			)
		)
		(property "Dielectric" ""
			(at 0 0 270)
			(unlocked yes)
			(layer "F.Fab")
			(hide yes)
			(effects
				(font
					(size 1 1)
					(thickness 0.15)
				)
			)
		)
		(sheetname "/Debug FTDI + VNA/")
		(sheetfile "debug-ftdi.kicad_sch")
		(attr smd)
		(fp_rect
			(start -0.925 -0.47)
			(end 0.925 0.47)
			(stroke
				(width 0.05)
				(type default)
			)
			(fill no)
			(layer "F.CrtYd")
		)
		(fp_line
			(start -0.494 0.248)
			(end -0.494 -0.25)
			(stroke
				(width 0.15)
				(type solid)
			)
			(layer "F.Fab")
		)
		(fp_line
			(start 0.504 0.248)
			(end -0.494 0.248)
			(stroke
				(width 0.15)
				(type solid)
			)
			(layer "F.Fab")
		)
		(fp_line
			(start -0.494 -0.25)
			(end 0.504 -0.25)
			(stroke
				(width 0.15)
				(type solid)
			)
			(layer "F.Fab")
		)
		(fp_line
			(start 0.504 -0.25)
			(end 0.504 0.248)
			(stroke
				(width 0.15)
				(type solid)
			)
			(layer "F.Fab")
		)
		(fp_text user "Author: Antmicro"
			(at -0.939 3.399 270)
			(layer "F.Fab")
			(effects
				(font
					(size 0.7 0.7)
					(thickness 0.15)
				)
				(justify left bottom)
			)
		)
		(fp_text user "License: Apache-2.0"
			(at -0.939 5.799 270)
			(layer "F.Fab")
			(effects
				(font
					(size 0.7 0.7)
					(thickness 0.15)
				)
				(justify left bottom)
			)
		)
		(fp_text user "${REFERENCE}"
			(at -0.939 4.599 270)
			(layer "F.Fab")
			(effects
				(font
					(size 0.7 0.7)
					(thickness 0.15)
				)
				(justify left bottom)
			)
		)
		(pad "1" smd roundrect
			(at -0.48 0 270)
			(size 0.59 0.64)
			(layers "F.Cu" "F.Mask" "F.Paste")
			(roundrect_rratio 0.25)
			(net 3 "/Debug FTDI + VNA/FTDI_VPLL")
			(pintype "passive")
		)
		(pad "2" smd roundrect
			(at 0.48 0 270)
			(size 0.59 0.64)
			(layers "F.Cu" "F.Mask" "F.Paste")
			(roundrect_rratio 0.25)
			(net 1 "GND")
			(pintype "passive")
		)
	)
	(footprint "antmicro-footprints:FB_0603_1608Metric"
		(layer "F.Cu")
		(at 132.435 164.984 90)
		(property "Reference" "FB1"
			(at -3.616 0.365 90)
			(layer "F.SilkS")
			(effects
				(font
					(size 0.7 0.7)
					(thickness 0.15)
				)
				(justify left bottom)
			)
		)
		(property "Value" "FB_600Z_0.5A_Murata-BLM18AG_0603"
			(at 0 1.5 90)
			(layer "F.Fab")
			(effects
				(font
					(size 0.7 0.7)
					(thickness 0.15)
				)
				(justify left bottom)
			)
		)
		(property "Datasheet" "https://www.murata.com/en-us/products/productdata/8796738650142/ENFA0003.pdf"
			(at 0 0 90)
			(layer "F.Fab")
			(hide yes)
			(effects
				(font
					(size 1.27 1.27)
					(thickness 0.15)
				)
			)
		)
		(property "Val" "600Z/0.5A"
			(at 0 0 90)
			(unlocked yes)
			(layer "F.Fab")
			(hide yes)
			(effects
				(font
					(size 1 1)
					(thickness 0.15)
				)
			)
		)
		(property "MPN" "BLM18AG601SN1D"
			(at 0 0 90)
			(unlocked yes)
			(layer "F.Fab")
			(hide yes)
			(effects
				(font
					(size 1 1)
					(thickness 0.15)
				)
			)
		)
		(property "Manufacturer" "Murata"
			(at 0 0 90)
			(unlocked yes)
			(layer "F.Fab")
			(hide yes)
			(effects
				(font
					(size 1 1)
					(thickness 0.15)
				)
			)
		)
		(property "Author" "Antmicro"
			(at 0 0 90)
			(unlocked yes)
			(layer "F.Fab")
			(hide yes)
			(effects
				(font
					(size 1 1)
					(thickness 0.15)
				)
			)
		)
		(property "License" "Apache-2.0"
			(at 0 0 90)
			(unlocked yes)
			(layer "F.Fab")
			(hide yes)
			(effects
				(font
					(size 1 1)
					(thickness 0.15)
				)
			)
		)
		(sheetname "/Debug FTDI + VNA/")
		(sheetfile "debug-ftdi.kicad_sch")
		(attr smd)
		(fp_line
			(start -0.15 -0.4)
			(end 0.15 -0.4)
			(stroke
				(width 0.15)
				(type solid)
			)
			(layer "F.SilkS")
		)
		(fp_line
			(start -0.15 0.4)
			(end 0.15 0.4)
			(stroke
				(width 0.15)
				(type solid)
			)
			(layer "F.SilkS")
		)
		(fp_rect
			(start -1.25 -0.65)
			(end 1.25 0.65)
			(stroke
				(width 0.05)
				(type solid)
			)
			(fill no)
			(layer "F.CrtYd")
		)
		(fp_line
			(start 0.8 -0.408)
			(end -0.803 -0.408)
			(stroke
				(width 0.15)
				(type solid)
			)
			(layer "F.Fab")
		)
		(fp_line
			(start 0.8 -0.408)
			(end 0.8 0.406)
			(stroke
				(width 0.15)
				(type solid)
			)
			(layer "F.Fab")
		)
		(fp_line
			(start 0.8 0.406)
			(end -0.803 0.406)
			(stroke
				(width 0.15)
				(type solid)
			)
			(layer "F.Fab")
		)
		(fp_line
			(start -0.803 0.406)
			(end -0.803 -0.408)
			(stroke
				(width 0.15)
				(type solid)
			)
			(layer "F.Fab")
		)
		(fp_text user "${REFERENCE}"
			(at -1.653 4.6 90)
			(layer "F.Fab")
			(effects
				(font
					(size 0.7 0.7)
					(thickness 0.15)
				)
				(justify left bottom)
			)
		)
		(fp_text user "Author: Antmicro"
			(at -1.653 3.162 90)
			(layer "F.Fab")
			(effects
				(font
					(size 0.7 0.7)
					(thickness 0.15)
				)
				(justify left bottom)
			)
		)
		(fp_text user "License: Apache-2.0"
			(at -1.653 5.9 90)
			(layer "F.Fab")
			(effects
				(font
					(size 0.7 0.7)
					(thickness 0.15)
				)
				(justify left bottom)
			)
		)
		(pad "1" smd roundrect
			(at -0.7 0 90)
			(size 0.8 1)
			(layers "F.Cu" "F.Mask" "F.Paste")
			(roundrect_rratio 0.2)
			(net 6 "/Debug FTDI + VNA/FTDI_3V3")
			(pintype "passive")
		)
		(pad "2" smd roundrect
			(at 0.7 0 90)
			(size 0.8 1)
			(layers "F.Cu" "F.Mask" "F.Paste")
			(roundrect_rratio 0.2)
			(net 3 "/Debug FTDI + VNA/FTDI_VPLL")
			(pintype "passive")
		)
	)
	(footprint "antmicro-footprints:C_0402_1005Metric"
		(layer "F.Cu")
		(at 132.648 154.624 -90)
		(descr "Capacitor SMD 0402")
		(tags "capacitor SMD 0402")
		(property "Reference" "C117"
			(at -3.724 -0.452 90)
			(layer "F.SilkS")
			(effects
				(font
					(size 0.7 0.7)
					(thickness 0.15)
				)
				(justify right bottom)
			)
		)
		(property "Value" "C_18p_0402"
			(at -1.022927 2.155213 90)
			(layer "F.Fab")
			(effects
				(font
					(size 0.7 0.7)
					(thickness 0.15)
				)
				(justify right bottom)
			)
		)
		(property "Datasheet" "https://product.samsungsem.com/mlcc/CL05C180JB51PN.do"
			(at 0 0 270)
			(layer "F.Fab")
			(hide yes)
			(effects
				(font
					(size 1.27 1.27)
					(thickness 0.15)
				)
			)
		)
		(property "Manufacturer" "Samsung Electro-Mechanics"
			(at 0 0 270)
			(unlocked yes)
			(layer "F.Fab")
			(hide yes)
			(effects
				(font
					(size 1 1)
					(thickness 0.15)
				)
			)
		)
		(property "MPN" "CL05C180JB51PNC"
			(at 0 0 270)
			(unlocked yes)
			(layer "F.Fab")
			(hide yes)
			(effects
				(font
					(size 1 1)
					(thickness 0.15)
				)
			)
		)
		(property "Val" "18p"
			(at 0 0 270)
			(unlocked yes)
			(layer "F.Fab")
			(hide yes)
			(effects
				(font
					(size 1 1)
					(thickness 0.15)
				)
			)
		)
		(property "License" "Apache-2.0"
			(at 0 0 270)
			(unlocked yes)
			(layer "F.Fab")
			(hide yes)
			(effects
				(font
					(size 1 1)
					(thickness 0.15)
				)
			)
		)
		(property "Author" "Antmicro"
			(at 0 0 270)
			(unlocked yes)
			(layer "F.Fab")
			(hide yes)
			(effects
				(font
					(size 1 1)
					(thickness 0.15)
				)
			)
		)
		(property "Voltage" ""
			(at 0 0 270)
			(unlocked yes)
			(layer "F.Fab")
			(hide yes)
			(effects
				(font
					(size 1 1)
					(thickness 0.15)
				)
			)
		)
		(property "Dielectric" ""
			(at 0 0 270)
			(unlocked yes)
			(layer "F.Fab")
			(hide yes)
			(effects
				(font
					(size 1 1)
					(thickness 0.15)
				)
			)
		)
		(sheetname "/Debug FTDI + VNA/")
		(sheetfile "debug-ftdi.kicad_sch")
		(attr smd)
		(fp_rect
			(start -0.925 -0.47)
			(end 0.925 0.47)
			(stroke
				(width 0.05)
				(type default)
			)
			(fill no)
			(layer "F.CrtYd")
		)
		(fp_line
			(start -0.494 0.248)
			(end -0.494 -0.25)
			(stroke
				(width 0.15)
				(type solid)
			)
			(layer "F.Fab")
		)
		(fp_line
			(start 0.504 0.248)
			(end -0.494 0.248)
			(stroke
				(width 0.15)
				(type solid)
			)
			(layer "F.Fab")
		)
		(fp_line
			(start -0.494 -0.25)
			(end 0.504 -0.25)
			(stroke
				(width 0.15)
				(type solid)
			)
			(layer "F.Fab")
		)
		(fp_line
			(start 0.504 -0.25)
			(end 0.504 0.248)
			(stroke
				(width 0.15)
				(type solid)
			)
			(layer "F.Fab")
		)
		(fp_text user "License: Apache-2.0"
			(at -0.939 5.799 270)
			(layer "F.Fab")
			(effects
				(font
					(size 0.7 0.7)
					(thickness 0.15)
				)
				(justify left bottom)
			)
		)
		(fp_text user "Author: Antmicro"
			(at -0.939 3.399 270)
			(layer "F.Fab")
			(effects
				(font
					(size 0.7 0.7)
					(thickness 0.15)
				)
				(justify left bottom)
			)
		)
		(fp_text user "${REFERENCE}"
			(at -0.939 4.599 270)
			(layer "F.Fab")
			(effects
				(font
					(size 0.7 0.7)
					(thickness 0.15)
				)
				(justify left bottom)
			)
		)
		(pad "1" smd roundrect
			(at -0.48 0 270)
			(size 0.59 0.64)
			(layers "F.Cu" "F.Mask" "F.Paste")
			(roundrect_rratio 0.25)
			(net 7 "/Debug FTDI + VNA/FTDI_XO")
			(pintype "passive")
		)
		(pad "2" smd roundrect
			(at 0.48 0 270)
			(size 0.59 0.64)
			(layers "F.Cu" "F.Mask" "F.Paste")
			(roundrect_rratio 0.25)
			(net 1 "GND")
			(pintype "passive")
		)
	)
	(footprint "antmicro-footprints:R_0402_1005Metric"
		(layer "F.Cu")
		(at 115.75 153.65 180)
		(descr "Resistor SMD 0402")
		(tags "resistor SMD 0402")
		(property "Reference" "R84"
			(at -1.025 1.8 0)
			(layer "F.SilkS")
			(effects
				(font
					(size 0.7 0.7)
					(thickness 0.15)
				)
				(justify right bottom)
			)
		)
		(property "Value" "R_330R_0402"
			(at -1.011843 1.772047 0)
			(layer "F.Fab")
			(effects
				(font
					(size 0.7 0.7)
					(thickness 0.15)
				)
				(justify right bottom)
			)
		)
		(property "Datasheet" "https://www.bourns.com/docs/product-datasheets/cr.pdf"
			(at 0 0 180)
			(layer "F.Fab")
			(hide yes)
			(effects
				(font
					(size 1.27 1.27)
					(thickness 0.15)
				)
			)
		)
		(property "Manufacturer" "Bourns"
			(at 0 0 180)
			(unlocked yes)
			(layer "F.Fab")
			(hide yes)
			(effects
				(font
					(size 1 1)
					(thickness 0.15)
				)
			)
		)
		(property "MPN" "CR0402-FX-3300GLF"
			(at 0 0 180)
			(unlocked yes)
			(layer "F.Fab")
			(hide yes)
			(effects
				(font
					(size 1 1)
					(thickness 0.15)
				)
			)
		)
		(property "Val" "330R"
			(at 0 0 180)
			(unlocked yes)
			(layer "F.Fab")
			(hide yes)
			(effects
				(font
					(size 1 1)
					(thickness 0.15)
				)
			)
		)
		(property "License" "Apache-2.0"
			(at 0 0 180)
			(unlocked yes)
			(layer "F.Fab")
			(hide yes)
			(effects
				(font
					(size 1 1)
					(thickness 0.15)
				)
			)
		)
		(property "Author" "Antmicro"
			(at 0 0 180)
			(unlocked yes)
			(layer "F.Fab")
			(hide yes)
			(effects
				(font
					(size 1 1)
					(thickness 0.15)
				)
			)
		)
		(property "Tolerance" "1%"
			(at 0 0 180)
			(unlocked yes)
			(layer "F.Fab")
			(hide yes)
			(effects
				(font
					(size 1 1)
					(thickness 0.15)
				)
			)
		)
		(sheetname "/HDMI + SD Card/")
		(sheetfile "hdmi-sd-card.kicad_sch")
		(attr smd)
		(fp_rect
			(start -0.925 -0.47)
			(end 0.925 0.47)
			(stroke
				(width 0.05)
				(type default)
			)
			(fill no)
			(layer "F.CrtYd")
		)
		(fp_rect
			(start -0.5 -0.25)
			(end 0.5 0.25)
			(stroke
				(width 0.15)
				(type solid)
			)
			(fill no)
			(layer "F.Fab")
		)
		(fp_text user "License: Apache-2.0"
			(at -0.95 5.169 180)
			(layer "F.Fab")
			(effects
				(font
					(size 0.7 0.7)
					(thickness 0.15)
				)
				(justify left bottom)
			)
		)
		(fp_text user "${REFERENCE}"
			(at -0.95 3.168 180)
			(layer "F.Fab")
			(effects
				(font
					(size 0.7 0.7)
					(thickness 0.15)
				)
				(justify left bottom)
			)
		)
		(fp_text user "Author: Antmicro"
			(at -0.95 4.169 180)
			(layer "F.Fab")
			(effects
				(font
					(size 0.7 0.7)
					(thickness 0.15)
				)
				(justify left bottom)
			)
		)
		(pad "1" smd roundrect
			(at -0.48 0 180)
			(size 0.59 0.64)
			(layers "F.Cu" "F.Mask" "F.Paste")
			(roundrect_rratio 0.25)
			(net 635 "/FPGA banks HP/SD.CD")
			(pintype "passive")
		)
		(pad "2" smd roundrect
			(at 0.48 0 180)
			(size 0.59 0.64)
			(layers "F.Cu" "F.Mask" "F.Paste")
			(roundrect_rratio 0.25)
			(net 249 "Net-(J5-CD_SW1)")
			(pintype "passive")
		)
	)
	(footprint "antmicro-footprints:C_0402_1005Metric"
		(layer "F.Cu")
		(at 134.8135 159.984 90)
		(descr "Capacitor SMD 0402")
		(tags "capacitor SMD 0402")
		(property "Reference" "C112"
			(at -1.066 2.2865 90)
			(layer "F.SilkS")
			(effects
				(font
					(size 0.7 0.7)
					(thickness 0.15)
				)
				(justify left bottom)
			)
		)
		(property "Value" "C_100n_0402"
			(at -1.022927 2.155213 90)
			(layer "F.Fab")
			(effects
				(font
					(size 0.7 0.7)
					(thickness 0.15)
				)
				(justify left bottom)
			)
		)
		(property "Datasheet" "https://www.murata.com/products/productdetail?partno=GRM155R61H104KE14%23"
			(at 0 0 90)
			(layer "F.Fab")
			(hide yes)
			(effects
				(font
					(size 1.27 1.27)
					(thickness 0.15)
				)
			)
		)
		(property "Manufacturer" "Murata"
			(at 0 0 90)
			(unlocked yes)
			(layer "F.Fab")
			(hide yes)
			(effects
				(font
					(size 1 1)
					(thickness 0.15)
				)
			)
		)
		(property "MPN" "GRM155R61H104KE14D"
			(at 0 0 90)
			(unlocked yes)
			(layer "F.Fab")
			(hide yes)
			(effects
				(font
					(size 1 1)
					(thickness 0.15)
				)
			)
		)
		(property "Val" "100n"
			(at 0 0 90)
			(unlocked yes)
			(layer "F.Fab")
			(hide yes)
			(effects
				(font
					(size 1 1)
					(thickness 0.15)
				)
			)
		)
		(property "License" "Apache-2.0"
			(at 0 0 90)
			(unlocked yes)
			(layer "F.Fab")
			(hide yes)
			(effects
				(font
					(size 1 1)
					(thickness 0.15)
				)
			)
		)
		(property "Author" "Antmicro"
			(at 0 0 90)
			(unlocked yes)
			(layer "F.Fab")
			(hide yes)
			(effects
				(font
					(size 1 1)
					(thickness 0.15)
				)
			)
		)
		(property "Voltage" "50V"
			(at 0 0 90)
			(unlocked yes)
			(layer "F.Fab")
			(hide yes)
			(effects
				(font
					(size 1 1)
					(thickness 0.15)
				)
			)
		)
		(property "Dielectric" "X5R"
			(at 0 0 90)
			(unlocked yes)
			(layer "F.Fab")
			(hide yes)
			(effects
				(font
					(size 1 1)
					(thickness 0.15)
				)
			)
		)
		(sheetname "/Debug FTDI + VNA/")
		(sheetfile "debug-ftdi.kicad_sch")
		(attr smd)
		(fp_rect
			(start -0.925 -0.47)
			(end 0.925 0.47)
			(stroke
				(width 0.05)
				(type default)
			)
			(fill no)
			(layer "F.CrtYd")
		)
		(fp_line
			(start 0.504 -0.25)
			(end 0.504 0.248)
			(stroke
				(width 0.15)
				(type solid)
			)
			(layer "F.Fab")
		)
		(fp_line
			(start -0.494 -0.25)
			(end 0.504 -0.25)
			(stroke
				(width 0.15)
				(type solid)
			)
			(layer "F.Fab")
		)
		(fp_line
			(start 0.504 0.248)
			(end -0.494 0.248)
			(stroke
				(width 0.15)
				(type solid)
			)
			(layer "F.Fab")
		)
		(fp_line
			(start -0.494 0.248)
			(end -0.494 -0.25)
			(stroke
				(width 0.15)
				(type solid)
			)
			(layer "F.Fab")
		)
		(fp_text user "${REFERENCE}"
			(at -0.939 4.599 90)
			(layer "F.Fab")
			(effects
				(font
					(size 0.7 0.7)
					(thickness 0.15)
				)
				(justify left bottom)
			)
		)
		(fp_text user "Author: Antmicro"
			(at -0.939 3.399 90)
			(layer "F.Fab")
			(effects
				(font
					(size 0.7 0.7)
					(thickness 0.15)
				)
				(justify left bottom)
			)
		)
		(fp_text user "License: Apache-2.0"
			(at -0.939 5.799 90)
			(layer "F.Fab")
			(effects
				(font
					(size 0.7 0.7)
					(thickness 0.15)
				)
				(justify left bottom)
			)
		)
		(pad "1" smd roundrect
			(at -0.48 0 90)
			(size 0.59 0.64)
			(layers "F.Cu" "F.Mask" "F.Paste")
			(roundrect_rratio 0.25)
			(net 5 "/Debug FTDI + VNA/FTDI_VPHY")
			(pintype "passive")
		)
		(pad "2" smd roundrect
			(at 0.48 0 90)
			(size 0.59 0.64)
			(layers "F.Cu" "F.Mask" "F.Paste")
			(roundrect_rratio 0.25)
			(net 1 "GND")
			(pintype "passive")
		)
	)
	(footprint "antmicro-footprints:C_0402_1005Metric"
		(layer "F.Cu")
		(at 142.971843 155.991328 90)
		(descr "Capacitor SMD 0402")
		(tags "capacitor SMD 0402")
		(property "Reference" "C118"
			(at 0.991328 0.348157 90)
			(layer "F.SilkS")
			(effects
				(font
					(size 0.7 0.7)
					(thickness 0.15)
				)
				(justify left bottom)
			)
		)
		(property "Value" "C_100n_0402"
			(at -1.022927 2.155213 90)
			(layer "F.Fab")
			(effects
				(font
					(size 0.7 0.7)
					(thickness 0.15)
				)
				(justify left bottom)
			)
		)
		(property "Datasheet" "https://www.murata.com/products/productdetail?partno=GRM155R61H104KE14%23"
			(at 0 0 90)
			(layer "F.Fab")
			(hide yes)
			(effects
				(font
					(size 1.27 1.27)
					(thickness 0.15)
				)
			)
		)
		(property "Manufacturer" "Murata"
			(at 0 0 90)
			(unlocked yes)
			(layer "F.Fab")
			(hide yes)
			(effects
				(font
					(size 1 1)
					(thickness 0.15)
				)
			)
		)
		(property "MPN" "GRM155R61H104KE14D"
			(at 0 0 90)
			(unlocked yes)
			(layer "F.Fab")
			(hide yes)
			(effects
				(font
					(size 1 1)
					(thickness 0.15)
				)
			)
		)
		(property "Val" "100n"
			(at 0 0 90)
			(unlocked yes)
			(layer "F.Fab")
			(hide yes)
			(effects
				(font
					(size 1 1)
					(thickness 0.15)
				)
			)
		)
		(property "License" "Apache-2.0"
			(at 0 0 90)
			(unlocked yes)
			(layer "F.Fab")
			(hide yes)
			(effects
				(font
					(size 1 1)
					(thickness 0.15)
				)
			)
		)
		(property "Author" "Antmicro"
			(at 0 0 90)
			(unlocked yes)
			(layer "F.Fab")
			(hide yes)
			(effects
				(font
					(size 1 1)
					(thickness 0.15)
				)
			)
		)
		(property "Voltage" "50V"
			(at 0 0 90)
			(unlocked yes)
			(layer "F.Fab")
			(hide yes)
			(effects
				(font
					(size 1 1)
					(thickness 0.15)
				)
			)
		)
		(property "Dielectric" "X5R"
			(at 0 0 90)
			(unlocked yes)
			(layer "F.Fab")
			(hide yes)
			(effects
				(font
					(size 1 1)
					(thickness 0.15)
				)
			)
		)
		(sheetname "/Debug FTDI + VNA/")
		(sheetfile "debug-ftdi.kicad_sch")
		(attr smd)
		(fp_rect
			(start -0.925 -0.47)
			(end 0.925 0.47)
			(stroke
				(width 0.05)
				(type default)
			)
			(fill no)
			(layer "F.CrtYd")
		)
		(fp_line
			(start 0.504 -0.25)
			(end 0.504 0.248)
			(stroke
				(width 0.15)
				(type solid)
			)
			(layer "F.Fab")
		)
		(fp_line
			(start -0.494 -0.25)
			(end 0.504 -0.25)
			(stroke
				(width 0.15)
				(type solid)
			)
			(layer "F.Fab")
		)
		(fp_line
			(start 0.504 0.248)
			(end -0.494 0.248)
			(stroke
				(width 0.15)
				(type solid)
			)
			(layer "F.Fab")
		)
		(fp_line
			(start -0.494 0.248)
			(end -0.494 -0.25)
			(stroke
				(width 0.15)
				(type solid)
			)
			(layer "F.Fab")
		)
		(fp_text user "Author: Antmicro"
			(at -0.939 3.399 90)
			(layer "F.Fab")
			(effects
				(font
					(size 0.7 0.7)
					(thickness 0.15)
				)
				(justify left bottom)
			)
		)
		(fp_text user "${REFERENCE}"
			(at -0.939 4.599 90)
			(layer "F.Fab")
			(effects
				(font
					(size 0.7 0.7)
					(thickness 0.15)
				)
				(justify left bottom)
			)
		)
		(fp_text user "License: Apache-2.0"
			(at -0.939 5.799 90)
			(layer "F.Fab")
			(effects
				(font
					(size 0.7 0.7)
					(thickness 0.15)
				)
				(justify left bottom)
			)
		)
		(pad "1" smd roundrect
			(at -0.48 0 90)
			(size 0.59 0.64)
			(layers "F.Cu" "F.Mask" "F.Paste")
			(roundrect_rratio 0.25)
			(net 6 "/Debug FTDI + VNA/FTDI_3V3")
			(pintype "passive")
		)
		(pad "2" smd roundrect
			(at 0.48 0 90)
			(size 0.59 0.64)
			(layers "F.Cu" "F.Mask" "F.Paste")
			(roundrect_rratio 0.25)
			(net 1 "GND")
			(pintype "passive")
		)
	)
	(footprint "antmicro-footprints:C_0402_1005Metric"
		(layer "F.Cu")
		(at 144.051843 155.991328 90)
		(descr "Capacitor SMD 0402")
		(tags "capacitor SMD 0402")
		(property "Reference" "C125"
			(at 0.991328 0.348157 90)
			(layer "F.SilkS")
			(effects
				(font
					(size 0.7 0.7)
					(thickness 0.15)
				)
				(justify left bottom)
			)
		)
		(property "Value" "C_100n_0402"
			(at -1.022927 2.155213 90)
			(layer "F.Fab")
			(effects
				(font
					(size 0.7 0.7)
					(thickness 0.15)
				)
				(justify left bottom)
			)
		)
		(property "Datasheet" "https://www.murata.com/products/productdetail?partno=GRM155R61H104KE14%23"
			(at 0 0 90)
			(layer "F.Fab")
			(hide yes)
			(effects
				(font
					(size 1.27 1.27)
					(thickness 0.15)
				)
			)
		)
		(property "Manufacturer" "Murata"
			(at 0 0 90)
			(unlocked yes)
			(layer "F.Fab")
			(hide yes)
			(effects
				(font
					(size 1 1)
					(thickness 0.15)
				)
			)
		)
		(property "MPN" "GRM155R61H104KE14D"
			(at 0 0 90)
			(unlocked yes)
			(layer "F.Fab")
			(hide yes)
			(effects
				(font
					(size 1 1)
					(thickness 0.15)
				)
			)
		)
		(property "Val" "100n"
			(at 0 0 90)
			(unlocked yes)
			(layer "F.Fab")
			(hide yes)
			(effects
				(font
					(size 1 1)
					(thickness 0.15)
				)
			)
		)
		(property "License" "Apache-2.0"
			(at 0 0 90)
			(unlocked yes)
			(layer "F.Fab")
			(hide yes)
			(effects
				(font
					(size 1 1)
					(thickness 0.15)
				)
			)
		)
		(property "Author" "Antmicro"
			(at 0 0 90)
			(unlocked yes)
			(layer "F.Fab")
			(hide yes)
			(effects
				(font
					(size 1 1)
					(thickness 0.15)
				)
			)
		)
		(property "Voltage" "50V"
			(at 0 0 90)
			(unlocked yes)
			(layer "F.Fab")
			(hide yes)
			(effects
				(font
					(size 1 1)
					(thickness 0.15)
				)
			)
		)
		(property "Dielectric" "X5R"
			(at 0 0 90)
			(unlocked yes)
			(layer "F.Fab")
			(hide yes)
			(effects
				(font
					(size 1 1)
					(thickness 0.15)
				)
			)
		)
		(sheetname "/Debug FTDI + VNA/")
		(sheetfile "debug-ftdi.kicad_sch")
		(attr smd)
		(fp_rect
			(start -0.925 -0.47)
			(end 0.925 0.47)
			(stroke
				(width 0.05)
				(type default)
			)
			(fill no)
			(layer "F.CrtYd")
		)
		(fp_line
			(start 0.504 -0.25)
			(end 0.504 0.248)
			(stroke
				(width 0.15)
				(type solid)
			)
			(layer "F.Fab")
		)
		(fp_line
			(start -0.494 -0.25)
			(end 0.504 -0.25)
			(stroke
				(width 0.15)
				(type solid)
			)
			(layer "F.Fab")
		)
		(fp_line
			(start 0.504 0.248)
			(end -0.494 0.248)
			(stroke
				(width 0.15)
				(type solid)
			)
			(layer "F.Fab")
		)
		(fp_line
			(start -0.494 0.248)
			(end -0.494 -0.25)
			(stroke
				(width 0.15)
				(type solid)
			)
			(layer "F.Fab")
		)
		(fp_text user "${REFERENCE}"
			(at -0.939 4.599 90)
			(layer "F.Fab")
			(effects
				(font
					(size 0.7 0.7)
					(thickness 0.15)
				)
				(justify left bottom)
			)
		)
		(fp_text user "License: Apache-2.0"
			(at -0.939 5.799 90)
			(layer "F.Fab")
			(effects
				(font
					(size 0.7 0.7)
					(thickness 0.15)
				)
				(justify left bottom)
			)
		)
		(fp_text user "Author: Antmicro"
			(at -0.939 3.399 90)
			(layer "F.Fab")
			(effects
				(font
					(size 0.7 0.7)
					(thickness 0.15)
				)
				(justify left bottom)
			)
		)
		(pad "1" smd roundrect
			(at -0.48 0 90)
			(size 0.59 0.64)
			(layers "F.Cu" "F.Mask" "F.Paste")
			(roundrect_rratio 0.25)
			(net 34 "/Debug FTDI + VNA/FTDI_VCORE")
			(pintype "passive")
		)
		(pad "2" smd roundrect
			(at 0.48 0 90)
			(size 0.59 0.64)
			(layers "F.Cu" "F.Mask" "F.Paste")
			(roundrect_rratio 0.25)
			(net 1 "GND")
			(pintype "passive")
		)
	)
	(footprint "antmicro-footprints:C_0402_1005Metric"
		(layer "F.Cu")
		(at 148.592843 162.216328)
		(descr "Capacitor SMD 0402")
		(tags "capacitor SMD 0402")
		(property "Reference" "C120"
			(at 0.887157 0.393672 0)
			(layer "F.SilkS")
			(effects
				(font
					(size 0.7 0.7)
					(thickness 0.15)
				)
				(justify left bottom)
			)
		)
		(property "Value" "C_100n_0402"
			(at -1.022927 2.155213 0)
			(layer "F.Fab")
			(effects
				(font
					(size 0.7 0.7)
					(thickness 0.15)
				)
				(justify left bottom)
			)
		)
		(property "Datasheet" "https://www.murata.com/products/productdetail?partno=GRM155R61H104KE14%23"
			(at 0 0 0)
			(layer "F.Fab")
			(hide yes)
			(effects
				(font
					(size 1.27 1.27)
					(thickness 0.15)
				)
			)
		)
		(property "Manufacturer" "Murata"
			(at 0 0 0)
			(unlocked yes)
			(layer "F.Fab")
			(hide yes)
			(effects
				(font
					(size 1 1)
					(thickness 0.15)
				)
			)
		)
		(property "MPN" "GRM155R61H104KE14D"
			(at 0 0 0)
			(unlocked yes)
			(layer "F.Fab")
			(hide yes)
			(effects
				(font
					(size 1 1)
					(thickness 0.15)
				)
			)
		)
		(property "Val" "100n"
			(at 0 0 0)
			(unlocked yes)
			(layer "F.Fab")
			(hide yes)
			(effects
				(font
					(size 1 1)
					(thickness 0.15)
				)
			)
		)
		(property "License" "Apache-2.0"
			(at 0 0 0)
			(unlocked yes)
			(layer "F.Fab")
			(hide yes)
			(effects
				(font
					(size 1 1)
					(thickness 0.15)
				)
			)
		)
		(property "Author" "Antmicro"
			(at 0 0 0)
			(unlocked yes)
			(layer "F.Fab")
			(hide yes)
			(effects
				(font
					(size 1 1)
					(thickness 0.15)
				)
			)
		)
		(property "Voltage" "50V"
			(at 0 0 0)
			(unlocked yes)
			(layer "F.Fab")
			(hide yes)
			(effects
				(font
					(size 1 1)
					(thickness 0.15)
				)
			)
		)
		(property "Dielectric" "X5R"
			(at 0 0 0)
			(unlocked yes)
			(layer "F.Fab")
			(hide yes)
			(effects
				(font
					(size 1 1)
					(thickness 0.15)
				)
			)
		)
		(sheetname "/Debug FTDI + VNA/")
		(sheetfile "debug-ftdi.kicad_sch")
		(attr smd)
		(fp_rect
			(start -0.925 -0.47)
			(end 0.925 0.47)
			(stroke
				(width 0.05)
				(type default)
			)
			(fill no)
			(layer "F.CrtYd")
		)
		(fp_line
			(start -0.494 -0.25)
			(end 0.504 -0.25)
			(stroke
				(width 0.15)
				(type solid)
			)
			(layer "F.Fab")
		)
		(fp_line
			(start -0.494 0.248)
			(end -0.494 -0.25)
			(stroke
				(width 0.15)
				(type solid)
			)
			(layer "F.Fab")
		)
		(fp_line
			(start 0.504 -0.25)
			(end 0.504 0.248)
			(stroke
				(width 0.15)
				(type solid)
			)
			(layer "F.Fab")
		)
		(fp_line
			(start 0.504 0.248)
			(end -0.494 0.248)
			(stroke
				(width 0.15)
				(type solid)
			)
			(layer "F.Fab")
		)
		(fp_text user "License: Apache-2.0"
			(at -0.939 5.799 0)
			(layer "F.Fab")
			(effects
				(font
					(size 0.7 0.7)
					(thickness 0.15)
				)
				(justify left bottom)
			)
		)
		(fp_text user "${REFERENCE}"
			(at -0.939 4.599 0)
			(layer "F.Fab")
			(effects
				(font
					(size 0.7 0.7)
					(thickness 0.15)
				)
				(justify left bottom)
			)
		)
		(fp_text user "Author: Antmicro"
			(at -0.939 3.399 0)
			(layer "F.Fab")
			(effects
				(font
					(size 0.7 0.7)
					(thickness 0.15)
				)
				(justify left bottom)
			)
		)
		(pad "1" smd roundrect
			(at -0.48 0)
			(size 0.59 0.64)
			(layers "F.Cu" "F.Mask" "F.Paste")
			(roundrect_rratio 0.25)
			(net 6 "/Debug FTDI + VNA/FTDI_3V3")
			(pintype "passive")
		)
		(pad "2" smd roundrect
			(at 0.48 0)
			(size 0.59 0.64)
			(layers "F.Cu" "F.Mask" "F.Paste")
			(roundrect_rratio 0.25)
			(net 1 "GND")
			(pintype "passive")
		)
	)
	(footprint "antmicro-footprints:C_0402_1005Metric"
		(layer "F.Cu")
		(at 141.525 144.907851 90)
		(descr "Capacitor SMD 0402")
		(tags "capacitor SMD 0402")
		(property "Reference" "C159"
			(at -5.992149 0.375 90)
			(layer "F.SilkS")
			(effects
				(font
					(size 0.7 0.7)
					(thickness 0.15)
				)
				(justify left bottom)
			)
		)
		(property "Value" "C_4u7_0402"
			(at -1.022927 2.155213 90)
			(layer "F.Fab")
			(effects
				(font
					(size 0.7 0.7)
					(thickness 0.15)
				)
				(justify left bottom)
			)
		)
		(property "Datasheet" "https://www.murata.com/products/productdetail?partno=GRM155R61A475MEAA%23"
			(at 0 0 90)
			(layer "F.Fab")
			(hide yes)
			(effects
				(font
					(size 1.27 1.27)
					(thickness 0.15)
				)
			)
		)
		(property "Manufacturer" "Murata"
			(at 0 0 90)
			(unlocked yes)
			(layer "F.Fab")
			(hide yes)
			(effects
				(font
					(size 1 1)
					(thickness 0.15)
				)
			)
		)
		(property "MPN" "GRM155R61A475MEAAD"
			(at 0 0 90)
			(unlocked yes)
			(layer "F.Fab")
			(hide yes)
			(effects
				(font
					(size 1 1)
					(thickness 0.15)
				)
			)
		)
		(property "Val" "4u7"
			(at 0 0 90)
			(unlocked yes)
			(layer "F.Fab")
			(hide yes)
			(effects
				(font
					(size 1 1)
					(thickness 0.15)
				)
			)
		)
		(property "License" "Apache-2.0"
			(at 0 0 90)
			(unlocked yes)
			(layer "F.Fab")
			(hide yes)
			(effects
				(font
					(size 1 1)
					(thickness 0.15)
				)
			)
		)
		(property "Author" "Antmicro"
			(at 0 0 90)
			(unlocked yes)
			(layer "F.Fab")
			(hide yes)
			(effects
				(font
					(size 1 1)
					(thickness 0.15)
				)
			)
		)
		(property "Voltage" ""
			(at 0 0 90)
			(unlocked yes)
			(layer "F.Fab")
			(hide yes)
			(effects
				(font
					(size 1 1)
					(thickness 0.15)
				)
			)
		)
		(property "Dielectric" ""
			(at 0 0 90)
			(unlocked yes)
			(layer "F.Fab")
			(hide yes)
			(effects
				(font
					(size 1 1)
					(thickness 0.15)
				)
			)
		)
		(sheetname "/Ethernet/")
		(sheetfile "ethernet.kicad_sch")
		(attr smd)
		(fp_rect
			(start -0.925 -0.47)
			(end 0.925 0.47)
			(stroke
				(width 0.05)
				(type default)
			)
			(fill no)
			(layer "F.CrtYd")
		)
		(fp_line
			(start 0.504 -0.25)
			(end 0.504 0.248)
			(stroke
				(width 0.15)
				(type solid)
			)
			(layer "F.Fab")
		)
		(fp_line
			(start -0.494 -0.25)
			(end 0.504 -0.25)
			(stroke
				(width 0.15)
				(type solid)
			)
			(layer "F.Fab")
		)
		(fp_line
			(start 0.504 0.248)
			(end -0.494 0.248)
			(stroke
				(width 0.15)
				(type solid)
			)
			(layer "F.Fab")
		)
		(fp_line
			(start -0.494 0.248)
			(end -0.494 -0.25)
			(stroke
				(width 0.15)
				(type solid)
			)
			(layer "F.Fab")
		)
		(fp_text user "Author: Antmicro"
			(at -0.939 3.399 90)
			(layer "F.Fab")
			(effects
				(font
					(size 0.7 0.7)
					(thickness 0.15)
				)
				(justify left bottom)
			)
		)
		(fp_text user "License: Apache-2.0"
			(at -0.939 5.799 90)
			(layer "F.Fab")
			(effects
				(font
					(size 0.7 0.7)
					(thickness 0.15)
				)
				(justify left bottom)
			)
		)
		(fp_text user "${REFERENCE}"
			(at -0.939 4.599 90)
			(layer "F.Fab")
			(effects
				(font
					(size 0.7 0.7)
					(thickness 0.15)
				)
				(justify left bottom)
			)
		)
		(pad "1" smd roundrect
			(at -0.48 0 90)
			(size 0.59 0.64)
			(layers "F.Cu" "F.Mask" "F.Paste")
			(roundrect_rratio 0.25)
			(net 1 "GND")
			(pintype "passive")
		)
		(pad "2" smd roundrect
			(at 0.48 0 90)
			(size 0.59 0.64)
			(layers "F.Cu" "F.Mask" "F.Paste")
			(roundrect_rratio 0.25)
			(net 96 "/Ethernet/AVDDL_PLL")
			(pintype "passive")
		)
	)
	(footprint "antmicro-footprints:C_0402_1005Metric"
		(layer "F.Cu")
		(at 129.625 142.507851 -90)
		(descr "Capacitor SMD 0402")
		(tags "capacitor SMD 0402")
		(property "Reference" "C138"
			(at -0.982851 1.6 90)
			(layer "F.SilkS")
			(effects
				(font
					(size 0.7 0.7)
					(thickness 0.15)
				)
				(justify right bottom)
			)
		)
		(property "Value" "C_470n_0402"
			(at -1.022927 2.155213 90)
			(layer "F.Fab")
			(effects
				(font
					(size 0.7 0.7)
					(thickness 0.15)
				)
				(justify right bottom)
			)
		)
		(property "Datasheet" "https://product.tdk.com/en/search/capacitor/ceramic/mlcc/info?part_no=C1005X5R1E474M050BB"
			(at 0 0 270)
			(layer "F.Fab")
			(hide yes)
			(effects
				(font
					(size 1.27 1.27)
					(thickness 0.15)
				)
			)
		)
		(property "Manufacturer" "TDK"
			(at 0 0 270)
			(unlocked yes)
			(layer "F.Fab")
			(hide yes)
			(effects
				(font
					(size 1 1)
					(thickness 0.15)
				)
			)
		)
		(property "MPN" "C1005X5R1E474M050BB"
			(at 0 0 270)
			(unlocked yes)
			(layer "F.Fab")
			(hide yes)
			(effects
				(font
					(size 1 1)
					(thickness 0.15)
				)
			)
		)
		(property "Val" "470n"
			(at 0 0 270)
			(unlocked yes)
			(layer "F.Fab")
			(hide yes)
			(effects
				(font
					(size 1 1)
					(thickness 0.15)
				)
			)
		)
		(property "License" "Apache-2.0"
			(at 0 0 270)
			(unlocked yes)
			(layer "F.Fab")
			(hide yes)
			(effects
				(font
					(size 1 1)
					(thickness 0.15)
				)
			)
		)
		(property "Author" "Antmicro"
			(at 0 0 270)
			(unlocked yes)
			(layer "F.Fab")
			(hide yes)
			(effects
				(font
					(size 1 1)
					(thickness 0.15)
				)
			)
		)
		(property "Voltage" ""
			(at 0 0 270)
			(unlocked yes)
			(layer "F.Fab")
			(hide yes)
			(effects
				(font
					(size 1 1)
					(thickness 0.15)
				)
			)
		)
		(property "Dielectric" ""
			(at 0 0 270)
			(unlocked yes)
			(layer "F.Fab")
			(hide yes)
			(effects
				(font
					(size 1 1)
					(thickness 0.15)
				)
			)
		)
		(sheetname "/Ethernet/")
		(sheetfile "ethernet.kicad_sch")
		(attr smd)
		(fp_rect
			(start -0.925 -0.47)
			(end 0.925 0.47)
			(stroke
				(width 0.05)
				(type default)
			)
			(fill no)
			(layer "F.CrtYd")
		)
		(fp_line
			(start -0.494 0.248)
			(end -0.494 -0.25)
			(stroke
				(width 0.15)
				(type solid)
			)
			(layer "F.Fab")
		)
		(fp_line
			(start 0.504 0.248)
			(end -0.494 0.248)
			(stroke
				(width 0.15)
				(type solid)
			)
			(layer "F.Fab")
		)
		(fp_line
			(start -0.494 -0.25)
			(end 0.504 -0.25)
			(stroke
				(width 0.15)
				(type solid)
			)
			(layer "F.Fab")
		)
		(fp_line
			(start 0.504 -0.25)
			(end 0.504 0.248)
			(stroke
				(width 0.15)
				(type solid)
			)
			(layer "F.Fab")
		)
		(fp_text user "Author: Antmicro"
			(at -0.939 3.399 270)
			(layer "F.Fab")
			(effects
				(font
					(size 0.7 0.7)
					(thickness 0.15)
				)
				(justify left bottom)
			)
		)
		(fp_text user "${REFERENCE}"
			(at -0.939 4.599 270)
			(layer "F.Fab")
			(effects
				(font
					(size 0.7 0.7)
					(thickness 0.15)
				)
				(justify left bottom)
			)
		)
		(fp_text user "License: Apache-2.0"
			(at -0.939 5.799 270)
			(layer "F.Fab")
			(effects
				(font
					(size 0.7 0.7)
					(thickness 0.15)
				)
				(justify left bottom)
			)
		)
		(pad "1" smd roundrect
			(at -0.48 0 270)
			(size 0.59 0.64)
			(layers "F.Cu" "F.Mask" "F.Paste")
			(roundrect_rratio 0.25)
			(net 797 "+1V8")
			(pintype "passive")
		)
		(pad "2" smd roundrect
			(at 0.48 0 270)
			(size 0.59 0.64)
			(layers "F.Cu" "F.Mask" "F.Paste")
			(roundrect_rratio 0.25)
			(net 1 "GND")
			(pintype "passive")
		)
	)
	(footprint "antmicro-footprints:C_0402_1005Metric"
		(layer "F.Cu")
		(at 142.625 144.907851 90)
		(descr "Capacitor SMD 0402")
		(tags "capacitor SMD 0402")
		(property "Reference" "C157"
			(at -5.992149 0.325 90)
			(layer "F.SilkS")
			(effects
				(font
					(size 0.7 0.7)
					(thickness 0.15)
				)
				(justify left bottom)
			)
		)
		(property "Value" "C_100n_0402"
			(at -1.022927 2.155213 90)
			(layer "F.Fab")
			(effects
				(font
					(size 0.7 0.7)
					(thickness 0.15)
				)
				(justify left bottom)
			)
		)
		(property "Datasheet" "https://www.murata.com/products/productdetail?partno=GRM155R61H104KE14%23"
			(at 0 0 90)
			(layer "F.Fab")
			(hide yes)
			(effects
				(font
					(size 1.27 1.27)
					(thickness 0.15)
				)
			)
		)
		(property "MPN" "GRM155R61H104KE14D"
			(at 0 0 90)
			(unlocked yes)
			(layer "F.Fab")
			(hide yes)
			(effects
				(font
					(size 1 1)
					(thickness 0.15)
				)
			)
		)
		(property "Manufacturer" "Murata"
			(at 0 0 90)
			(unlocked yes)
			(layer "F.Fab")
			(hide yes)
			(effects
				(font
					(size 1 1)
					(thickness 0.15)
				)
			)
		)
		(property "License" "Apache-2.0"
			(at 0 0 90)
			(unlocked yes)
			(layer "F.Fab")
			(hide yes)
			(effects
				(font
					(size 1 1)
					(thickness 0.15)
				)
			)
		)
		(property "Author" "Antmicro"
			(at 0 0 90)
			(unlocked yes)
			(layer "F.Fab")
			(hide yes)
			(effects
				(font
					(size 1 1)
					(thickness 0.15)
				)
			)
		)
		(property "Val" "100n"
			(at 0 0 90)
			(unlocked yes)
			(layer "F.Fab")
			(hide yes)
			(effects
				(font
					(size 1 1)
					(thickness 0.15)
				)
			)
		)
		(property "Voltage" "50V"
			(at 0 0 90)
			(unlocked yes)
			(layer "F.Fab")
			(hide yes)
			(effects
				(font
					(size 1 1)
					(thickness 0.15)
				)
			)
		)
		(property "Dielectric" "X5R"
			(at 0 0 90)
			(unlocked yes)
			(layer "F.Fab")
			(hide yes)
			(effects
				(font
					(size 1 1)
					(thickness 0.15)
				)
			)
		)
		(sheetname "/Ethernet/")
		(sheetfile "ethernet.kicad_sch")
		(attr smd)
		(fp_rect
			(start -0.925 -0.47)
			(end 0.925 0.47)
			(stroke
				(width 0.05)
				(type default)
			)
			(fill no)
			(layer "F.CrtYd")
		)
		(fp_line
			(start 0.504 -0.25)
			(end 0.504 0.248)
			(stroke
				(width 0.15)
				(type solid)
			)
			(layer "F.Fab")
		)
		(fp_line
			(start -0.494 -0.25)
			(end 0.504 -0.25)
			(stroke
				(width 0.15)
				(type solid)
			)
			(layer "F.Fab")
		)
		(fp_line
			(start 0.504 0.248)
			(end -0.494 0.248)
			(stroke
				(width 0.15)
				(type solid)
			)
			(layer "F.Fab")
		)
		(fp_line
			(start -0.494 0.248)
			(end -0.494 -0.25)
			(stroke
				(width 0.15)
				(type solid)
			)
			(layer "F.Fab")
		)
		(fp_text user "${REFERENCE}"
			(at -0.939 4.599 90)
			(layer "F.Fab")
			(effects
				(font
					(size 0.7 0.7)
					(thickness 0.15)
				)
				(justify left bottom)
			)
		)
		(fp_text user "License: Apache-2.0"
			(at -0.939 5.799 90)
			(layer "F.Fab")
			(effects
				(font
					(size 0.7 0.7)
					(thickness 0.15)
				)
				(justify left bottom)
			)
		)
		(fp_text user "Author: Antmicro"
			(at -0.939 3.399 90)
			(layer "F.Fab")
			(effects
				(font
					(size 0.7 0.7)
					(thickness 0.15)
				)
				(justify left bottom)
			)
		)
		(pad "1" smd roundrect
			(at -0.48 0 90)
			(size 0.59 0.64)
			(layers "F.Cu" "F.Mask" "F.Paste")
			(roundrect_rratio 0.25)
			(net 1 "GND")
			(pintype "passive")
		)
		(pad "2" smd roundrect
			(at 0.48 0 90)
			(size 0.59 0.64)
			(layers "F.Cu" "F.Mask" "F.Paste")
			(roundrect_rratio 0.25)
			(net 96 "/Ethernet/AVDDL_PLL")
			(pintype "passive")
		)
	)
	(footprint "antmicro-footprints:C_0402_1005Metric"
		(layer "F.Cu")
		(at 129.625 140.182157 90)
		(descr "Capacitor SMD 0402")
		(tags "capacitor SMD 0402")
		(property "Reference" "C149"
			(at -1.042843 -1.65 90)
			(layer "F.SilkS")
			(effects
				(font
					(size 0.7 0.7)
					(thickness 0.15)
				)
				(justify left bottom)
			)
		)
		(property "Value" "C_470n_0402"
			(at -1.022927 2.155213 90)
			(layer "F.Fab")
			(effects
				(font
					(size 0.7 0.7)
					(thickness 0.15)
				)
				(justify left bottom)
			)
		)
		(property "Datasheet" "https://product.tdk.com/en/search/capacitor/ceramic/mlcc/info?part_no=C1005X5R1E474M050BB"
			(at 0 0 90)
			(layer "F.Fab")
			(hide yes)
			(effects
				(font
					(size 1.27 1.27)
					(thickness 0.15)
				)
			)
		)
		(property "Manufacturer" "TDK"
			(at 0 0 90)
			(unlocked yes)
			(layer "F.Fab")
			(hide yes)
			(effects
				(font
					(size 1 1)
					(thickness 0.15)
				)
			)
		)
		(property "MPN" "C1005X5R1E474M050BB"
			(at 0 0 90)
			(unlocked yes)
			(layer "F.Fab")
			(hide yes)
			(effects
				(font
					(size 1 1)
					(thickness 0.15)
				)
			)
		)
		(property "Val" "470n"
			(at 0 0 90)
			(unlocked yes)
			(layer "F.Fab")
			(hide yes)
			(effects
				(font
					(size 1 1)
					(thickness 0.15)
				)
			)
		)
		(property "License" "Apache-2.0"
			(at 0 0 90)
			(unlocked yes)
			(layer "F.Fab")
			(hide yes)
			(effects
				(font
					(size 1 1)
					(thickness 0.15)
				)
			)
		)
		(property "Author" "Antmicro"
			(at 0 0 90)
			(unlocked yes)
			(layer "F.Fab")
			(hide yes)
			(effects
				(font
					(size 1 1)
					(thickness 0.15)
				)
			)
		)
		(property "Voltage" ""
			(at 0 0 90)
			(unlocked yes)
			(layer "F.Fab")
			(hide yes)
			(effects
				(font
					(size 1 1)
					(thickness 0.15)
				)
			)
		)
		(property "Dielectric" ""
			(at 0 0 90)
			(unlocked yes)
			(layer "F.Fab")
			(hide yes)
			(effects
				(font
					(size 1 1)
					(thickness 0.15)
				)
			)
		)
		(sheetname "/Ethernet/")
		(sheetfile "ethernet.kicad_sch")
		(attr smd)
		(fp_rect
			(start -0.925 -0.47)
			(end 0.925 0.47)
			(stroke
				(width 0.05)
				(type default)
			)
			(fill no)
			(layer "F.CrtYd")
		)
		(fp_line
			(start 0.504 -0.25)
			(end 0.504 0.248)
			(stroke
				(width 0.15)
				(type solid)
			)
			(layer "F.Fab")
		)
		(fp_line
			(start -0.494 -0.25)
			(end 0.504 -0.25)
			(stroke
				(width 0.15)
				(type solid)
			)
			(layer "F.Fab")
		)
		(fp_line
			(start 0.504 0.248)
			(end -0.494 0.248)
			(stroke
				(width 0.15)
				(type solid)
			)
			(layer "F.Fab")
		)
		(fp_line
			(start -0.494 0.248)
			(end -0.494 -0.25)
			(stroke
				(width 0.15)
				(type solid)
			)
			(layer "F.Fab")
		)
		(fp_text user "${REFERENCE}"
			(at -0.939 4.599 90)
			(layer "F.Fab")
			(effects
				(font
					(size 0.7 0.7)
					(thickness 0.15)
				)
				(justify left bottom)
			)
		)
		(fp_text user "Author: Antmicro"
			(at -0.939 3.399 90)
			(layer "F.Fab")
			(effects
				(font
					(size 0.7 0.7)
					(thickness 0.15)
				)
				(justify left bottom)
			)
		)
		(fp_text user "License: Apache-2.0"
			(at -0.939 5.799 90)
			(layer "F.Fab")
			(effects
				(font
					(size 0.7 0.7)
					(thickness 0.15)
				)
				(justify left bottom)
			)
		)
		(pad "1" smd roundrect
			(at -0.48 0 90)
			(size 0.59 0.64)
			(layers "F.Cu" "F.Mask" "F.Paste")
			(roundrect_rratio 0.25)
			(net 150 "+1V2")
			(pintype "passive")
		)
		(pad "2" smd roundrect
			(at 0.48 0 90)
			(size 0.59 0.64)
			(layers "F.Cu" "F.Mask" "F.Paste")
			(roundrect_rratio 0.25)
			(net 1 "GND")
			(pintype "passive")
		)
	)
	(footprint "antmicro-footprints:C_0402_1005Metric"
		(layer "F.Cu")
		(at 143.725 144.907851 90)
		(descr "Capacitor SMD 0402")
		(tags "capacitor SMD 0402")
		(property "Reference" "C154"
			(at -5.992149 0.2 90)
			(layer "F.SilkS")
			(effects
				(font
					(size 0.7 0.7)
					(thickness 0.15)
				)
				(justify left bottom)
			)
		)
		(property "Value" "C_10n_0402"
			(at -1.022927 2.155213 90)
			(layer "F.Fab")
			(effects
				(font
					(size 0.7 0.7)
					(thickness 0.15)
				)
				(justify left bottom)
			)
		)
		(property "Datasheet" "https://www.murata.com/products/productdetail?partno=GRM155R71H103KA88%23"
			(at 0 0 90)
			(layer "F.Fab")
			(hide yes)
			(effects
				(font
					(size 1.27 1.27)
					(thickness 0.15)
				)
			)
		)
		(property "Manufacturer" "Murata"
			(at 0 0 90)
			(unlocked yes)
			(layer "F.Fab")
			(hide yes)
			(effects
				(font
					(size 1 1)
					(thickness 0.15)
				)
			)
		)
		(property "MPN" "GRM155R71H103KA88D"
			(at 0 0 90)
			(unlocked yes)
			(layer "F.Fab")
			(hide yes)
			(effects
				(font
					(size 1 1)
					(thickness 0.15)
				)
			)
		)
		(property "Val" "10n"
			(at 0 0 90)
			(unlocked yes)
			(layer "F.Fab")
			(hide yes)
			(effects
				(font
					(size 1 1)
					(thickness 0.15)
				)
			)
		)
		(property "License" "Apache-2.0"
			(at 0 0 90)
			(unlocked yes)
			(layer "F.Fab")
			(hide yes)
			(effects
				(font
					(size 1 1)
					(thickness 0.15)
				)
			)
		)
		(property "Author" "Antmicro"
			(at 0 0 90)
			(unlocked yes)
			(layer "F.Fab")
			(hide yes)
			(effects
				(font
					(size 1 1)
					(thickness 0.15)
				)
			)
		)
		(property "Voltage" "50V"
			(at 0 0 90)
			(unlocked yes)
			(layer "F.Fab")
			(hide yes)
			(effects
				(font
					(size 1 1)
					(thickness 0.15)
				)
			)
		)
		(property "Dielectric" "X7R"
			(at 0 0 90)
			(unlocked yes)
			(layer "F.Fab")
			(hide yes)
			(effects
				(font
					(size 1 1)
					(thickness 0.15)
				)
			)
		)
		(sheetname "/Ethernet/")
		(sheetfile "ethernet.kicad_sch")
		(attr smd)
		(fp_rect
			(start -0.925 -0.47)
			(end 0.925 0.47)
			(stroke
				(width 0.05)
				(type default)
			)
			(fill no)
			(layer "F.CrtYd")
		)
		(fp_line
			(start 0.504 -0.25)
			(end 0.504 0.248)
			(stroke
				(width 0.15)
				(type solid)
			)
			(layer "F.Fab")
		)
		(fp_line
			(start -0.494 -0.25)
			(end 0.504 -0.25)
			(stroke
				(width 0.15)
				(type solid)
			)
			(layer "F.Fab")
		)
		(fp_line
			(start 0.504 0.248)
			(end -0.494 0.248)
			(stroke
				(width 0.15)
				(type solid)
			)
			(layer "F.Fab")
		)
		(fp_line
			(start -0.494 0.248)
			(end -0.494 -0.25)
			(stroke
				(width 0.15)
				(type solid)
			)
			(layer "F.Fab")
		)
		(fp_text user "License: Apache-2.0"
			(at -0.939 5.799 90)
			(layer "F.Fab")
			(effects
				(font
					(size 0.7 0.7)
					(thickness 0.15)
				)
				(justify left bottom)
			)
		)
		(fp_text user "${REFERENCE}"
			(at -0.939 4.599 90)
			(layer "F.Fab")
			(effects
				(font
					(size 0.7 0.7)
					(thickness 0.15)
				)
				(justify left bottom)
			)
		)
		(fp_text user "Author: Antmicro"
			(at -0.939 3.399 90)
			(layer "F.Fab")
			(effects
				(font
					(size 0.7 0.7)
					(thickness 0.15)
				)
				(justify left bottom)
			)
		)
		(pad "1" smd roundrect
			(at -0.48 0 90)
			(size 0.59 0.64)
			(layers "F.Cu" "F.Mask" "F.Paste")
			(roundrect_rratio 0.25)
			(net 1 "GND")
			(pintype "passive")
		)
		(pad "2" smd roundrect
			(at 0.48 0 90)
			(size 0.59 0.64)
			(layers "F.Cu" "F.Mask" "F.Paste")
			(roundrect_rratio 0.25)
			(net 96 "/Ethernet/AVDDL_PLL")
			(pintype "passive")
		)
	)
	(footprint "antmicro-footprints:C_0402_1005Metric"
		(layer "F.Cu")
		(at 129.625 146.03 -90)
		(descr "Capacitor SMD 0402")
		(tags "capacitor SMD 0402")
		(property "Reference" "C150"
			(at 1.017149 -0.4 90)
			(layer "F.SilkS")
			(effects
				(font
					(size 0.7 0.7)
					(thickness 0.15)
				)
				(justify right bottom)
			)
		)
		(property "Value" "C_10n_0402"
			(at -1.022927 2.155213 90)
			(layer "F.Fab")
			(effects
				(font
					(size 0.7 0.7)
					(thickness 0.15)
				)
				(justify right bottom)
			)
		)
		(property "Datasheet" "https://www.murata.com/products/productdetail?partno=GRM155R71H103KA88%23"
			(at 0 0 270)
			(layer "F.Fab")
			(hide yes)
			(effects
				(font
					(size 1.27 1.27)
					(thickness 0.15)
				)
			)
		)
		(property "Manufacturer" "Murata"
			(at 0 0 270)
			(unlocked yes)
			(layer "F.Fab")
			(hide yes)
			(effects
				(font
					(size 1 1)
					(thickness 0.15)
				)
			)
		)
		(property "MPN" "GRM155R71H103KA88D"
			(at 0 0 270)
			(unlocked yes)
			(layer "F.Fab")
			(hide yes)
			(effects
				(font
					(size 1 1)
					(thickness 0.15)
				)
			)
		)
		(property "Val" "10n"
			(at 0 0 270)
			(unlocked yes)
			(layer "F.Fab")
			(hide yes)
			(effects
				(font
					(size 1 1)
					(thickness 0.15)
				)
			)
		)
		(property "License" "Apache-2.0"
			(at 0 0 270)
			(unlocked yes)
			(layer "F.Fab")
			(hide yes)
			(effects
				(font
					(size 1 1)
					(thickness 0.15)
				)
			)
		)
		(property "Author" "Antmicro"
			(at 0 0 270)
			(unlocked yes)
			(layer "F.Fab")
			(hide yes)
			(effects
				(font
					(size 1 1)
					(thickness 0.15)
				)
			)
		)
		(property "Voltage" "50V"
			(at 0 0 270)
			(unlocked yes)
			(layer "F.Fab")
			(hide yes)
			(effects
				(font
					(size 1 1)
					(thickness 0.15)
				)
			)
		)
		(property "Dielectric" "X7R"
			(at 0 0 270)
			(unlocked yes)
			(layer "F.Fab")
			(hide yes)
			(effects
				(font
					(size 1 1)
					(thickness 0.15)
				)
			)
		)
		(sheetname "/Ethernet/")
		(sheetfile "ethernet.kicad_sch")
		(attr smd)
		(fp_rect
			(start -0.925 -0.47)
			(end 0.925 0.47)
			(stroke
				(width 0.05)
				(type default)
			)
			(fill no)
			(layer "F.CrtYd")
		)
		(fp_line
			(start -0.494 0.248)
			(end -0.494 -0.25)
			(stroke
				(width 0.15)
				(type solid)
			)
			(layer "F.Fab")
		)
		(fp_line
			(start 0.504 0.248)
			(end -0.494 0.248)
			(stroke
				(width 0.15)
				(type solid)
			)
			(layer "F.Fab")
		)
		(fp_line
			(start -0.494 -0.25)
			(end 0.504 -0.25)
			(stroke
				(width 0.15)
				(type solid)
			)
			(layer "F.Fab")
		)
		(fp_line
			(start 0.504 -0.25)
			(end 0.504 0.248)
			(stroke
				(width 0.15)
				(type solid)
			)
			(layer "F.Fab")
		)
		(fp_text user "License: Apache-2.0"
			(at -0.939 5.799 270)
			(layer "F.Fab")
			(effects
				(font
					(size 0.7 0.7)
					(thickness 0.15)
				)
				(justify left bottom)
			)
		)
		(fp_text user "${REFERENCE}"
			(at -0.939 4.599 270)
			(layer "F.Fab")
			(effects
				(font
					(size 0.7 0.7)
					(thickness 0.15)
				)
				(justify left bottom)
			)
		)
		(fp_text user "Author: Antmicro"
			(at -0.939 3.399 270)
			(layer "F.Fab")
			(effects
				(font
					(size 0.7 0.7)
					(thickness 0.15)
				)
				(justify left bottom)
			)
		)
		(pad "1" smd roundrect
			(at -0.48 0 270)
			(size 0.59 0.64)
			(layers "F.Cu" "F.Mask" "F.Paste")
			(roundrect_rratio 0.25)
			(net 150 "+1V2")
			(pintype "passive")
		)
		(pad "2" smd roundrect
			(at 0.48 0 270)
			(size 0.59 0.64)
			(layers "F.Cu" "F.Mask" "F.Paste")
			(roundrect_rratio 0.25)
			(net 1 "GND")
			(pintype "passive")
		)
	)
	(footprint "antmicro-footprints:C_0402_1005Metric"
		(layer "F.Cu")
		(at 128.525 142.507851 -90)
		(descr "Capacitor SMD 0402")
		(tags "capacitor SMD 0402")
		(property "Reference" "C147"
			(at -0.982851 1.6 90)
			(layer "F.SilkS")
			(effects
				(font
					(size 0.7 0.7)
					(thickness 0.15)
				)
				(justify right bottom)
			)
		)
		(property "Value" "C_10n_0402"
			(at -1.022927 2.155213 90)
			(layer "F.Fab")
			(effects
				(font
					(size 0.7 0.7)
					(thickness 0.15)
				)
				(justify right bottom)
			)
		)
		(property "Datasheet" "https://www.murata.com/products/productdetail?partno=GRM155R71H103KA88%23"
			(at 0 0 270)
			(layer "F.Fab")
			(hide yes)
			(effects
				(font
					(size 1.27 1.27)
					(thickness 0.15)
				)
			)
		)
		(property "Manufacturer" "Murata"
			(at 0 0 270)
			(unlocked yes)
			(layer "F.Fab")
			(hide yes)
			(effects
				(font
					(size 1 1)
					(thickness 0.15)
				)
			)
		)
		(property "MPN" "GRM155R71H103KA88D"
			(at 0 0 270)
			(unlocked yes)
			(layer "F.Fab")
			(hide yes)
			(effects
				(font
					(size 1 1)
					(thickness 0.15)
				)
			)
		)
		(property "Val" "10n"
			(at 0 0 270)
			(unlocked yes)
			(layer "F.Fab")
			(hide yes)
			(effects
				(font
					(size 1 1)
					(thickness 0.15)
				)
			)
		)
		(property "License" "Apache-2.0"
			(at 0 0 270)
			(unlocked yes)
			(layer "F.Fab")
			(hide yes)
			(effects
				(font
					(size 1 1)
					(thickness 0.15)
				)
			)
		)
		(property "Author" "Antmicro"
			(at 0 0 270)
			(unlocked yes)
			(layer "F.Fab")
			(hide yes)
			(effects
				(font
					(size 1 1)
					(thickness 0.15)
				)
			)
		)
		(property "Voltage" "50V"
			(at 0 0 270)
			(unlocked yes)
			(layer "F.Fab")
			(hide yes)
			(effects
				(font
					(size 1 1)
					(thickness 0.15)
				)
			)
		)
		(property "Dielectric" "X7R"
			(at 0 0 270)
			(unlocked yes)
			(layer "F.Fab")
			(hide yes)
			(effects
				(font
					(size 1 1)
					(thickness 0.15)
				)
			)
		)
		(sheetname "/Ethernet/")
		(sheetfile "ethernet.kicad_sch")
		(attr smd)
		(fp_rect
			(start -0.925 -0.47)
			(end 0.925 0.47)
			(stroke
				(width 0.05)
				(type default)
			)
			(fill no)
			(layer "F.CrtYd")
		)
		(fp_line
			(start -0.494 0.248)
			(end -0.494 -0.25)
			(stroke
				(width 0.15)
				(type solid)
			)
			(layer "F.Fab")
		)
		(fp_line
			(start 0.504 0.248)
			(end -0.494 0.248)
			(stroke
				(width 0.15)
				(type solid)
			)
			(layer "F.Fab")
		)
		(fp_line
			(start -0.494 -0.25)
			(end 0.504 -0.25)
			(stroke
				(width 0.15)
				(type solid)
			)
			(layer "F.Fab")
		)
		(fp_line
			(start 0.504 -0.25)
			(end 0.504 0.248)
			(stroke
				(width 0.15)
				(type solid)
			)
			(layer "F.Fab")
		)
		(fp_text user "${REFERENCE}"
			(at -0.939 4.599 270)
			(layer "F.Fab")
			(effects
				(font
					(size 0.7 0.7)
					(thickness 0.15)
				)
				(justify left bottom)
			)
		)
		(fp_text user "Author: Antmicro"
			(at -0.939 3.399 270)
			(layer "F.Fab")
			(effects
				(font
					(size 0.7 0.7)
					(thickness 0.15)
				)
				(justify left bottom)
			)
		)
		(fp_text user "License: Apache-2.0"
			(at -0.939 5.799 270)
			(layer "F.Fab")
			(effects
				(font
					(size 0.7 0.7)
					(thickness 0.15)
				)
				(justify left bottom)
			)
		)
		(pad "1" smd roundrect
			(at -0.48 0 270)
			(size 0.59 0.64)
			(layers "F.Cu" "F.Mask" "F.Paste")
			(roundrect_rratio 0.25)
			(net 797 "+1V8")
			(pintype "passive")
		)
		(pad "2" smd roundrect
			(at 0.48 0 270)
			(size 0.59 0.64)
			(layers "F.Cu" "F.Mask" "F.Paste")
			(roundrect_rratio 0.25)
			(net 1 "GND")
			(pintype "passive")
		)
	)
	(footprint "antmicro-footprints:C_0402_1005Metric"
		(layer "F.Cu")
		(at 143.925 143.407851 180)
		(descr "Capacitor SMD 0402")
		(tags "capacitor SMD 0402")
		(property "Reference" "C163"
			(at -3.9 -0.442149 0)
			(layer "F.SilkS")
			(effects
				(font
					(size 0.7 0.7)
					(thickness 0.15)
				)
				(justify right bottom)
			)
		)
		(property "Value" "C_18p_0402"
			(at -1.022927 2.155213 0)
			(layer "F.Fab")
			(effects
				(font
					(size 0.7 0.7)
					(thickness 0.15)
				)
				(justify right bottom)
			)
		)
		(property "Datasheet" "https://product.samsungsem.com/mlcc/CL05C180JB51PN.do"
			(at 0 0 180)
			(layer "F.Fab")
			(hide yes)
			(effects
				(font
					(size 1.27 1.27)
					(thickness 0.15)
				)
			)
		)
		(property "MPN" "CL05C180JB51PNC"
			(at 0 0 180)
			(unlocked yes)
			(layer "F.Fab")
			(hide yes)
			(effects
				(font
					(size 1 1)
					(thickness 0.15)
				)
			)
		)
		(property "Manufacturer" "Samsung Electro-Mechanics"
			(at 0 0 180)
			(unlocked yes)
			(layer "F.Fab")
			(hide yes)
			(effects
				(font
					(size 1 1)
					(thickness 0.15)
				)
			)
		)
		(property "License" "Apache-2.0"
			(at 0 0 180)
			(unlocked yes)
			(layer "F.Fab")
			(hide yes)
			(effects
				(font
					(size 1 1)
					(thickness 0.15)
				)
			)
		)
		(property "Author" "Antmicro"
			(at 0 0 180)
			(unlocked yes)
			(layer "F.Fab")
			(hide yes)
			(effects
				(font
					(size 1 1)
					(thickness 0.15)
				)
			)
		)
		(property "Val" "18p"
			(at 0 0 180)
			(unlocked yes)
			(layer "F.Fab")
			(hide yes)
			(effects
				(font
					(size 1 1)
					(thickness 0.15)
				)
			)
		)
		(property "Voltage" ""
			(at 0 0 180)
			(unlocked yes)
			(layer "F.Fab")
			(hide yes)
			(effects
				(font
					(size 1 1)
					(thickness 0.15)
				)
			)
		)
		(property "Dielectric" ""
			(at 0 0 180)
			(unlocked yes)
			(layer "F.Fab")
			(hide yes)
			(effects
				(font
					(size 1 1)
					(thickness 0.15)
				)
			)
		)
		(sheetname "/Ethernet/")
		(sheetfile "ethernet.kicad_sch")
		(attr smd)
		(fp_rect
			(start -0.925 -0.47)
			(end 0.925 0.47)
			(stroke
				(width 0.05)
				(type default)
			)
			(fill no)
			(layer "F.CrtYd")
		)
		(fp_line
			(start 0.504 0.248)
			(end -0.494 0.248)
			(stroke
				(width 0.15)
				(type solid)
			)
			(layer "F.Fab")
		)
		(fp_line
			(start 0.504 -0.25)
			(end 0.504 0.248)
			(stroke
				(width 0.15)
				(type solid)
			)
			(layer "F.Fab")
		)
		(fp_line
			(start -0.494 0.248)
			(end -0.494 -0.25)
			(stroke
				(width 0.15)
				(type solid)
			)
			(layer "F.Fab")
		)
		(fp_line
			(start -0.494 -0.25)
			(end 0.504 -0.25)
			(stroke
				(width 0.15)
				(type solid)
			)
			(layer "F.Fab")
		)
		(fp_text user "Author: Antmicro"
			(at -0.939 3.399 180)
			(layer "F.Fab")
			(effects
				(font
					(size 0.7 0.7)
					(thickness 0.15)
				)
				(justify left bottom)
			)
		)
		(fp_text user "${REFERENCE}"
			(at -0.939 4.599 180)
			(layer "F.Fab")
			(effects
				(font
					(size 0.7 0.7)
					(thickness 0.15)
				)
				(justify left bottom)
			)
		)
		(fp_text user "License: Apache-2.0"
			(at -0.939 5.799 180)
			(layer "F.Fab")
			(effects
				(font
					(size 0.7 0.7)
					(thickness 0.15)
				)
				(justify left bottom)
			)
		)
		(pad "1" smd roundrect
			(at -0.48 0 180)
			(size 0.59 0.64)
			(layers "F.Cu" "F.Mask" "F.Paste")
			(roundrect_rratio 0.25)
			(net 1 "GND")
			(pintype "passive")
		)
		(pad "2" smd roundrect
			(at 0.48 0 180)
			(size 0.59 0.64)
			(layers "F.Cu" "F.Mask" "F.Paste")
			(roundrect_rratio 0.25)
			(net 228 "Net-(U15-XO)")
			(pintype "passive")
		)
	)
	(footprint "antmicro-footprints:C_0402_1005Metric"
		(layer "F.Cu")
		(at 145.125 138.607851)
		(descr "Capacitor SMD 0402")
		(tags "capacitor SMD 0402")
		(property "Reference" "C162"
			(at 0 -0.699 0)
			(layer "F.SilkS")
			(effects
				(font
					(size 0.7 0.7)
					(thickness 0.15)
				)
				(justify left bottom)
			)
		)
		(property "Value" "C_18p_0402"
			(at -1.022927 2.155213 0)
			(layer "F.Fab")
			(effects
				(font
					(size 0.7 0.7)
					(thickness 0.15)
				)
				(justify left bottom)
			)
		)
		(property "Datasheet" "https://product.samsungsem.com/mlcc/CL05C180JB51PN.do"
			(at 0 0 0)
			(layer "F.Fab")
			(hide yes)
			(effects
				(font
					(size 1.27 1.27)
					(thickness 0.15)
				)
			)
		)
		(property "MPN" "CL05C180JB51PNC"
			(at 0 0 0)
			(unlocked yes)
			(layer "F.Fab")
			(hide yes)
			(effects
				(font
					(size 1 1)
					(thickness 0.15)
				)
			)
		)
		(property "Manufacturer" "Samsung Electro-Mechanics"
			(at 0 0 0)
			(unlocked yes)
			(layer "F.Fab")
			(hide yes)
			(effects
				(font
					(size 1 1)
					(thickness 0.15)
				)
			)
		)
		(property "License" "Apache-2.0"
			(at 0 0 0)
			(unlocked yes)
			(layer "F.Fab")
			(hide yes)
			(effects
				(font
					(size 1 1)
					(thickness 0.15)
				)
			)
		)
		(property "Author" "Antmicro"
			(at 0 0 0)
			(unlocked yes)
			(layer "F.Fab")
			(hide yes)
			(effects
				(font
					(size 1 1)
					(thickness 0.15)
				)
			)
		)
		(property "Val" "18p"
			(at 0 0 0)
			(unlocked yes)
			(layer "F.Fab")
			(hide yes)
			(effects
				(font
					(size 1 1)
					(thickness 0.15)
				)
			)
		)
		(property "Voltage" ""
			(at 0 0 0)
			(unlocked yes)
			(layer "F.Fab")
			(hide yes)
			(effects
				(font
					(size 1 1)
					(thickness 0.15)
				)
			)
		)
		(property "Dielectric" ""
			(at 0 0 0)
			(unlocked yes)
			(layer "F.Fab")
			(hide yes)
			(effects
				(font
					(size 1 1)
					(thickness 0.15)
				)
			)
		)
		(sheetname "/Ethernet/")
		(sheetfile "ethernet.kicad_sch")
		(attr smd)
		(fp_rect
			(start -0.925 -0.47)
			(end 0.925 0.47)
			(stroke
				(width 0.05)
				(type default)
			)
			(fill no)
			(layer "F.CrtYd")
		)
		(fp_line
			(start -0.494 -0.25)
			(end 0.504 -0.25)
			(stroke
				(width 0.15)
				(type solid)
			)
			(layer "F.Fab")
		)
		(fp_line
			(start -0.494 0.248)
			(end -0.494 -0.25)
			(stroke
				(width 0.15)
				(type solid)
			)
			(layer "F.Fab")
		)
		(fp_line
			(start 0.504 -0.25)
			(end 0.504 0.248)
			(stroke
				(width 0.15)
				(type solid)
			)
			(layer "F.Fab")
		)
		(fp_line
			(start 0.504 0.248)
			(end -0.494 0.248)
			(stroke
				(width 0.15)
				(type solid)
			)
			(layer "F.Fab")
		)
		(fp_text user "${REFERENCE}"
			(at -0.939 4.599 0)
			(layer "F.Fab")
			(effects
				(font
					(size 0.7 0.7)
					(thickness 0.15)
				)
				(justify left bottom)
			)
		)
		(fp_text user "License: Apache-2.0"
			(at -0.939 5.799 0)
			(layer "F.Fab")
			(effects
				(font
					(size 0.7 0.7)
					(thickness 0.15)
				)
				(justify left bottom)
			)
		)
		(fp_text user "Author: Antmicro"
			(at -0.939 3.399 0)
			(layer "F.Fab")
			(effects
				(font
					(size 0.7 0.7)
					(thickness 0.15)
				)
				(justify left bottom)
			)
		)
		(pad "1" smd roundrect
			(at -0.48 0)
			(size 0.59 0.64)
			(layers "F.Cu" "F.Mask" "F.Paste")
			(roundrect_rratio 0.25)
			(net 1 "GND")
			(pintype "passive")
		)
		(pad "2" smd roundrect
			(at 0.48 0)
			(size 0.59 0.64)
			(layers "F.Cu" "F.Mask" "F.Paste")
			(roundrect_rratio 0.25)
			(net 227 "Net-(U15-XI)")
			(pintype "passive")
		)
	)
	(footprint "antmicro-footprints:FB_0603_1608Metric"
		(layer "F.Cu")
		(at 145.625 144.672149 180)
		(property "Reference" "FB6"
			(at -3.35 -0.602851 0)
			(layer "F.SilkS")
			(effects
				(font
					(size 0.7 0.7)
					(thickness 0.15)
				)
				(justify right bottom)
			)
		)
		(property "Value" "FB_120Z_2A_Murata-BLM18PG_0603"
			(at 0 1.5 0)
			(layer "F.Fab")
			(effects
				(font
					(size 0.7 0.7)
					(thickness 0.15)
				)
				(justify right bottom)
			)
		)
		(property "Datasheet" "https://www.murata.com/en-us/products/productdata/8796738650142/ENFA0003.pdf"
			(at 0 0 180)
			(layer "F.Fab")
			(hide yes)
			(effects
				(font
					(size 1.27 1.27)
					(thickness 0.15)
				)
			)
		)
		(property "Val" "120Z/2A"
			(at 0 0 180)
			(unlocked yes)
			(layer "F.Fab")
			(hide yes)
			(effects
				(font
					(size 1 1)
					(thickness 0.15)
				)
			)
		)
		(property "MPN" "BLM18PG121SN1D"
			(at 0 0 180)
			(unlocked yes)
			(layer "F.Fab")
			(hide yes)
			(effects
				(font
					(size 1 1)
					(thickness 0.15)
				)
			)
		)
		(property "Manufacturer" "Murata"
			(at 0 0 180)
			(unlocked yes)
			(layer "F.Fab")
			(hide yes)
			(effects
				(font
					(size 1 1)
					(thickness 0.15)
				)
			)
		)
		(property "Author" "Antmicro"
			(at 0 0 180)
			(unlocked yes)
			(layer "F.Fab")
			(hide yes)
			(effects
				(font
					(size 1 1)
					(thickness 0.15)
				)
			)
		)
		(property "License" "Apache-2.0"
			(at 0 0 180)
			(unlocked yes)
			(layer "F.Fab")
			(hide yes)
			(effects
				(font
					(size 1 1)
					(thickness 0.15)
				)
			)
		)
		(sheetname "/Ethernet/")
		(sheetfile "ethernet.kicad_sch")
		(attr smd)
		(fp_line
			(start -0.15 0.4)
			(end 0.15 0.4)
			(stroke
				(width 0.15)
				(type solid)
			)
			(layer "F.SilkS")
		)
		(fp_line
			(start -0.15 -0.4)
			(end 0.15 -0.4)
			(stroke
				(width 0.15)
				(type solid)
			)
			(layer "F.SilkS")
		)
		(fp_rect
			(start -1.25 -0.65)
			(end 1.25 0.65)
			(stroke
				(width 0.05)
				(type solid)
			)
			(fill no)
			(layer "F.CrtYd")
		)
		(fp_line
			(start 0.8 0.406)
			(end -0.803 0.406)
			(stroke
				(width 0.15)
				(type solid)
			)
			(layer "F.Fab")
		)
		(fp_line
			(start 0.8 -0.408)
			(end 0.8 0.406)
			(stroke
				(width 0.15)
				(type solid)
			)
			(layer "F.Fab")
		)
		(fp_line
			(start 0.8 -0.408)
			(end -0.803 -0.408)
			(stroke
				(width 0.15)
				(type solid)
			)
			(layer "F.Fab")
		)
		(fp_line
			(start -0.803 0.406)
			(end -0.803 -0.408)
			(stroke
				(width 0.15)
				(type solid)
			)
			(layer "F.Fab")
		)
		(fp_text user "License: Apache-2.0"
			(at -1.653 5.9 180)
			(layer "F.Fab")
			(effects
				(font
					(size 0.7 0.7)
					(thickness 0.15)
				)
				(justify left bottom)
			)
		)
		(fp_text user "${REFERENCE}"
			(at -1.653 4.6 180)
			(layer "F.Fab")
			(effects
				(font
					(size 0.7 0.7)
					(thickness 0.15)
				)
				(justify left bottom)
			)
		)
		(fp_text user "Author: Antmicro"
			(at -1.653 3.162 180)
			(layer "F.Fab")
			(effects
				(font
					(size 0.7 0.7)
					(thickness 0.15)
				)
				(justify left bottom)
			)
		)
		(pad "1" smd roundrect
			(at -0.7 0 180)
			(size 0.8 1)
			(layers "F.Cu" "F.Mask" "F.Paste")
			(roundrect_rratio 0.2)
			(net 150 "+1V2")
			(pintype "passive")
		)
		(pad "2" smd roundrect
			(at 0.7 0 180)
			(size 0.8 1)
			(layers "F.Cu" "F.Mask" "F.Paste")
			(roundrect_rratio 0.2)
			(net 96 "/Ethernet/AVDDL_PLL")
			(pintype "passive")
		)
	)
	(footprint "antmicro-footprints:R_0402_1005Metric"
		(layer "F.Cu")
		(at 141.525 139.807851 -90)
		(descr "Resistor SMD 0402")
		(tags "resistor SMD 0402")
		(property "Reference" "R112"
			(at -1.063186 0.852303 90)
			(layer "F.SilkS")
			(effects
				(font
					(size 0.7 0.7)
					(thickness 0.15)
				)
				(justify right bottom)
			)
		)
		(property "Value" "R_12k1_0402"
			(at -1.011843 1.772047 90)
			(layer "F.Fab")
			(effects
				(font
					(size 0.7 0.7)
					(thickness 0.15)
				)
				(justify right bottom)
			)
		)
		(property "Datasheet" "https://www.bourns.com/docs/product-datasheets/cr.pdf"
			(at 0 0 270)
			(layer "F.Fab")
			(hide yes)
			(effects
				(font
					(size 1.27 1.27)
					(thickness 0.15)
				)
			)
		)
		(property "Manufacturer" "Bourns"
			(at 0 0 270)
			(unlocked yes)
			(layer "F.Fab")
			(hide yes)
			(effects
				(font
					(size 1 1)
					(thickness 0.15)
				)
			)
		)
		(property "MPN" "CR0402-FX-1212GLF"
			(at 0 0 270)
			(unlocked yes)
			(layer "F.Fab")
			(hide yes)
			(effects
				(font
					(size 1 1)
					(thickness 0.15)
				)
			)
		)
		(property "Val" "12k1"
			(at 0 0 270)
			(unlocked yes)
			(layer "F.Fab")
			(hide yes)
			(effects
				(font
					(size 1 1)
					(thickness 0.15)
				)
			)
		)
		(property "License" "Apache-2.0"
			(at 0 0 270)
			(unlocked yes)
			(layer "F.Fab")
			(hide yes)
			(effects
				(font
					(size 1 1)
					(thickness 0.15)
				)
			)
		)
		(property "Author" "Antmicro"
			(at 0 0 270)
			(unlocked yes)
			(layer "F.Fab")
			(hide yes)
			(effects
				(font
					(size 1 1)
					(thickness 0.15)
				)
			)
		)
		(property "Tolerance" "1%"
			(at 0 0 270)
			(unlocked yes)
			(layer "F.Fab")
			(hide yes)
			(effects
				(font
					(size 1 1)
					(thickness 0.15)
				)
			)
		)
		(sheetname "/Ethernet/")
		(sheetfile "ethernet.kicad_sch")
		(attr smd)
		(fp_rect
			(start -0.925 -0.47)
			(end 0.925 0.47)
			(stroke
				(width 0.05)
				(type default)
			)
			(fill no)
			(layer "F.CrtYd")
		)
		(fp_rect
			(start -0.5 -0.25)
			(end 0.5 0.25)
			(stroke
				(width 0.15)
				(type solid)
			)
			(fill no)
			(layer "F.Fab")
		)
		(fp_text user "${REFERENCE}"
			(at -0.95 3.168 270)
			(layer "F.Fab")
			(effects
				(font
					(size 0.7 0.7)
					(thickness 0.15)
				)
				(justify left bottom)
			)
		)
		(fp_text user "Author: Antmicro"
			(at -0.95 4.169 270)
			(layer "F.Fab")
			(effects
				(font
					(size 0.7 0.7)
					(thickness 0.15)
				)
				(justify left bottom)
			)
		)
		(fp_text user "License: Apache-2.0"
			(at -0.95 5.169 270)
			(layer "F.Fab")
			(effects
				(font
					(size 0.7 0.7)
					(thickness 0.15)
				)
				(justify left bottom)
			)
		)
		(pad "1" smd roundrect
			(at -0.48 0 270)
			(size 0.59 0.64)
			(layers "F.Cu" "F.Mask" "F.Paste")
			(roundrect_rratio 0.25)
			(net 1 "GND")
			(pintype "passive")
		)
		(pad "2" smd roundrect
			(at 0.48 0 270)
			(size 0.59 0.64)
			(layers "F.Cu" "F.Mask" "F.Paste")
			(roundrect_rratio 0.25)
			(net 302 "Net-(U15-ISET)")
			(pintype "passive")
		)
	)
	(footprint "antmicro-footprints:R_0402_1005Metric"
		(layer "F.Cu")
		(at 141.525 141.807851 90)
		(descr "Resistor SMD 0402")
		(tags "resistor SMD 0402")
		(property "Reference" "R100"
			(at -2.617149 -0.875 90)
			(layer "F.SilkS")
			(effects
				(font
					(size 0.7 0.7)
					(thickness 0.15)
				)
				(justify left bottom)
			)
		)
		(property "Value" "R_1M8_0402"
			(at -1.011843 1.772047 90)
			(layer "F.Fab")
			(effects
				(font
					(size 0.7 0.7)
					(thickness 0.15)
				)
				(justify left bottom)
			)
		)
		(property "Datasheet" "https://www.bourns.com/docs/product-datasheets/cr.pdf"
			(at 0 0 90)
			(layer "F.Fab")
			(hide yes)
			(effects
				(font
					(size 1.27 1.27)
					(thickness 0.15)
				)
			)
		)
		(property "Manufacturer" "Bourns"
			(at 0 0 90)
			(unlocked yes)
			(layer "F.Fab")
			(hide yes)
			(effects
				(font
					(size 1 1)
					(thickness 0.15)
				)
			)
		)
		(property "MPN" "CR0402-FX-1804GLF"
			(at 0 0 90)
			(unlocked yes)
			(layer "F.Fab")
			(hide yes)
			(effects
				(font
					(size 1 1)
					(thickness 0.15)
				)
			)
		)
		(property "Val" "1M8"
			(at 0 0 90)
			(unlocked yes)
			(layer "F.Fab")
			(hide yes)
			(effects
				(font
					(size 1 1)
					(thickness 0.15)
				)
			)
		)
		(property "License" "Apache-2.0"
			(at 0 0 90)
			(unlocked yes)
			(layer "F.Fab")
			(hide yes)
			(effects
				(font
					(size 1 1)
					(thickness 0.15)
				)
			)
		)
		(property "Author" "Antmicro"
			(at 0 0 90)
			(unlocked yes)
			(layer "F.Fab")
			(hide yes)
			(effects
				(font
					(size 1 1)
					(thickness 0.15)
				)
			)
		)
		(property "Tolerance" "1%"
			(at 0 0 90)
			(unlocked yes)
			(layer "F.Fab")
			(hide yes)
			(effects
				(font
					(size 1 1)
					(thickness 0.15)
				)
			)
		)
		(sheetname "/Ethernet/")
		(sheetfile "ethernet.kicad_sch")
		(attr smd)
		(fp_rect
			(start -0.925 -0.47)
			(end 0.925 0.47)
			(stroke
				(width 0.05)
				(type default)
			)
			(fill no)
			(layer "F.CrtYd")
		)
		(fp_rect
			(start -0.5 -0.25)
			(end 0.5 0.25)
			(stroke
				(width 0.15)
				(type solid)
			)
			(fill no)
			(layer "F.Fab")
		)
		(fp_text user "Author: Antmicro"
			(at -0.95 4.169 90)
			(layer "F.Fab")
			(effects
				(font
					(size 0.7 0.7)
					(thickness 0.15)
				)
				(justify left bottom)
			)
		)
		(fp_text user "License: Apache-2.0"
			(at -0.95 5.169 90)
			(layer "F.Fab")
			(effects
				(font
					(size 0.7 0.7)
					(thickness 0.15)
				)
				(justify left bottom)
			)
		)
		(fp_text user "${REFERENCE}"
			(at -0.95 3.168 90)
			(layer "F.Fab")
			(effects
				(font
					(size 0.7 0.7)
					(thickness 0.15)
				)
				(justify left bottom)
			)
		)
		(pad "1" smd roundrect
			(at -0.48 0 90)
			(size 0.59 0.64)
			(layers "F.Cu" "F.Mask" "F.Paste")
			(roundrect_rratio 0.25)
			(net 228 "Net-(U15-XO)")
			(pintype "passive")
		)
		(pad "2" smd roundrect
			(at 0.48 0 90)
			(size 0.59 0.64)
			(layers "F.Cu" "F.Mask" "F.Paste")
			(roundrect_rratio 0.25)
			(net 227 "Net-(U15-XI)")
			(pintype "passive")
		)
	)
	(footprint "antmicro-footprints:Resonator_SMD_Abracon_ABM8G_3.2x2.5mm"
		(layer "F.Cu")
		(at 144.425 141.007851)
		(property "Reference" "Y2"
			(at 3.3 1.542149 0)
			(layer "F.SilkS")
			(effects
				(font
					(size 0.7 0.7)
					(thickness 0.15)
				)
				(justify right bottom)
			)
		)
		(property "Value" "Resonator_25MHz_ABM8G"
			(at -1.75 2.548 0)
			(layer "F.Fab")
			(effects
				(font
					(size 0.7 0.7)
					(thickness 0.15)
				)
				(justify left bottom)
			)
		)
		(property "Datasheet" "https://abracon.com/Resonators/ABM8G.pdf"
			(at 0 0 0)
			(layer "F.Fab")
			(hide yes)
			(effects
				(font
					(size 1.27 1.27)
					(thickness 0.15)
				)
			)
		)
		(property "MPN" "ABM8G-25.000MHZ-18-D2Y-T3"
			(at 0 0 0)
			(unlocked yes)
			(layer "F.Fab")
			(hide yes)
			(effects
				(font
					(size 1 1)
					(thickness 0.15)
				)
			)
		)
		(property "Manufacturer" "Abracon"
			(at 0 0 0)
			(unlocked yes)
			(layer "F.Fab")
			(hide yes)
			(effects
				(font
					(size 1 1)
					(thickness 0.15)
				)
			)
		)
		(property "Author" "Antmicro"
			(at 0 0 0)
			(unlocked yes)
			(layer "F.Fab")
			(hide yes)
			(effects
				(font
					(size 1 1)
					(thickness 0.15)
				)
			)
		)
		(property "License" "Apache-2.0"
			(at 0 0 0)
			(unlocked yes)
			(layer "F.Fab")
			(hide yes)
			(effects
				(font
					(size 1 1)
					(thickness 0.15)
				)
			)
		)
		(property "Val" "25 MHz"
			(at 0 0 0)
			(unlocked yes)
			(layer "F.Fab")
			(hide yes)
			(effects
				(font
					(size 1 1)
					(thickness 0.15)
				)
			)
		)
		(sheetname "/Ethernet/")
		(sheetfile "ethernet.kicad_sch")
		(attr smd)
		(fp_line
			(start -1.6 0.3)
			(end -1.6 -0.2)
			(stroke
				(width 0.15)
				(type solid)
			)
			(layer "F.SilkS")
		)
		(fp_line
			(start -0.35 -1.25)
			(end 0.45 -1.25)
			(stroke
				(width 0.15)
				(type solid)
			)
			(layer "F.SilkS")
		)
		(fp_line
			(start -0.35 1.25)
			(end 0.45 1.25)
			(stroke
				(width 0.15)
				(type solid)
			)
			(layer "F.SilkS")
		)
		(fp_line
			(start 1.6 0.3)
			(end 1.6 -0.2)
			(stroke
				(width 0.15)
				(type solid)
			)
			(layer "F.SilkS")
		)
		(fp_circle
			(center -1.75 1.5)
			(end -1.7 1.5)
			(stroke
				(width 0.15)
				(type solid)
			)
			(fill no)
			(layer "F.SilkS")
		)
		(fp_rect
			(start -1.907 -1.55)
			(end 2.006 1.649)
			(stroke
				(width 0.05)
				(type solid)
			)
			(fill no)
			(layer "F.CrtYd")
		)
		(fp_text user "Author: Antmicro"
			(at -1.75 5 0)
			(layer "F.Fab")
			(effects
				(font
					(size 0.7 0.7)
					(thickness 0.15)
				)
				(justify left bottom)
			)
		)
		(fp_text user "License: Apache-2.0"
			(at -1.75 6.5 0)
			(layer "F.Fab")
			(effects
				(font
					(size 0.7 0.7)
					(thickness 0.15)
				)
				(justify left bottom)
			)
		)
		(fp_text user "${REFERENCE}"
			(at -1.75 3.75 0)
			(layer "F.Fab")
			(effects
				(font
					(size 0.7 0.7)
					(thickness 0.15)
				)
				(justify left bottom)
			)
		)
		(pad "1" smd roundrect
			(at -1.101 0.949)
			(size 1.3 1.1)
			(layers "F.Cu" "F.Mask" "F.Paste")
			(roundrect_rratio 0)
			(chamfer_ratio 0.2)
			(chamfer bottom_left)
			(net 228 "Net-(U15-XO)")
			(pintype "passive")
		)
		(pad "2" smd rect
			(at 1.199 0.949)
			(size 1.3 1.1)
			(layers "F.Cu" "F.Mask" "F.Paste")
			(net 1 "GND")
			(pinfunction "SH")
			(pintype "passive")
		)
		(pad "3" smd rect
			(at 1.199 -0.85)
			(size 1.3 1.1)
			(layers "F.Cu" "F.Mask" "F.Paste")
			(net 227 "Net-(U15-XI)")
			(pintype "passive")
		)
		(pad "4" smd rect
			(at -1.101 -0.85)
			(size 1.3 1.1)
			(layers "F.Cu" "F.Mask" "F.Paste")
			(net 1 "GND")
			(pinfunction "SH")
			(pintype "passive")
		)
	)
	(footprint "antmicro-footprints:QFN-48-1EP_7x7x0.9mm_P0.5mm_EP3.5x3.5mm"
		(layer "F.Cu")
		(at 134.675 143.235 -90)
		(property "Reference" "U15"
			(at 5.114 -2.249499 0)
			(layer "F.SilkS")
			(effects
				(font
					(size 0.7 0.7)
					(thickness 0.15)
				)
				(justify left bottom)
			)
		)
		(property "Value" "KSZ9031RNXCA"
			(at 0 5.1 90)
			(layer "F.Fab")
			(hide yes)
			(effects
				(font
					(size 0.7 0.7)
					(thickness 0.15)
				)
				(justify right bottom)
			)
		)
		(property "Datasheet" "http://ww1.microchip.com/downloads/en/DeviceDoc/00002117F.pdf"
			(at 0 0 270)
			(layer "F.Fab")
			(hide yes)
			(effects
				(font
					(size 1.27 1.27)
					(thickness 0.15)
				)
			)
		)
		(property "Manufacturer" "Microchip Technology"
			(at 0 0 270)
			(unlocked yes)
			(layer "F.Fab")
			(hide yes)
			(effects
				(font
					(size 1 1)
					(thickness 0.15)
				)
			)
		)
		(property "MPN" "KSZ9031RNXCA"
			(at 0 0 270)
			(unlocked yes)
			(layer "F.Fab")
			(hide yes)
			(effects
				(font
					(size 1 1)
					(thickness 0.15)
				)
			)
		)
		(property "Author" "Antmicro"
			(at 0 0 270)
			(unlocked yes)
			(layer "F.Fab")
			(hide yes)
			(effects
				(font
					(size 1 1)
					(thickness 0.15)
				)
			)
		)
		(property "License" "Apache-2.0"
			(at 0 0 270)
			(unlocked yes)
			(layer "F.Fab")
			(hide yes)
			(effects
				(font
					(size 1 1)
					(thickness 0.15)
				)
			)
		)
		(sheetname "/Ethernet/")
		(sheetfile "ethernet.kicad_sch")
		(attr smd)
		(fp_line
			(start -3.65 3.648)
			(end -3.65 3.249)
			(stroke
				(width 0.15)
				(type solid)
			)
			(layer "F.SilkS")
		)
		(fp_line
			(start -3.25 3.648)
			(end -3.65 3.648)
			(stroke
				(width 0.15)
				(type solid)
			)
			(layer "F.SilkS")
		)
		(fp_line
			(start 3.249 3.648)
			(end 3.648 3.648)
			(stroke
				(width 0.15)
				(type solid)
			)
			(layer "F.SilkS")
		)
		(fp_line
			(start 3.648 3.648)
			(end 3.648 3.249)
			(stroke
				(width 0.15)
				(type solid)
			)
			(layer "F.SilkS")
		)
		(fp_line
			(start -3.65 -3.3)
			(end -3.65 -3.65)
			(stroke
				(width 0.15)
				(type solid)
			)
			(layer "F.SilkS")
		)
		(fp_line
			(start -3.3 -3.65)
			(end -3.65 -3.65)
			(stroke
				(width 0.15)
				(type solid)
			)
			(layer "F.SilkS")
		)
		(fp_line
			(start 3.249 -3.65)
			(end 3.648 -3.65)
			(stroke
				(width 0.15)
				(type solid)
			)
			(layer "F.SilkS")
		)
		(fp_line
			(start 3.648 -3.65)
			(end 3.648 -3.25)
			(stroke
				(width 0.15)
				(type solid)
			)
			(layer "F.SilkS")
		)
		(fp_circle
			(center -3.7 -3.05)
			(end -3.65 -3.05)
			(stroke
				(width 0.15)
				(type solid)
			)
			(fill yes)
			(layer "F.SilkS")
		)
		(fp_rect
			(start -4.15 -4.15)
			(end 4.15 4.15)
			(stroke
				(width 0.05)
				(type solid)
			)
			(fill no)
			(layer "F.CrtYd")
		)
		(fp_line
			(start -3.5 3.499)
			(end 3.499 3.499)
			(stroke
				(width 0.15)
				(type solid)
			)
			(layer "F.Fab")
		)
		(fp_line
			(start 3.499 3.499)
			(end 3.499 -3.5)
			(stroke
				(width 0.15)
				(type solid)
			)
			(layer "F.Fab")
		)
		(fp_line
			(start -3.5 -2.5)
			(end -3.5 3.499)
			(stroke
				(width 0.15)
				(type solid)
			)
			(layer "F.Fab")
		)
		(fp_line
			(start -2.5 -3.5)
			(end -3.5 -2.5)
			(stroke
				(width 0.15)
				(type solid)
			)
			(layer "F.Fab")
		)
		(fp_line
			(start 3.499 -3.5)
			(end -2.5 -3.5)
			(stroke
				(width 0.15)
				(type solid)
			)
			(layer "F.Fab")
		)
		(fp_text user "Author: Antmicro"
			(at -4.202 8.4 270)
			(layer "F.Fab")
			(effects
				(font
					(size 0.7 0.7)
					(thickness 0.15)
				)
				(justify left bottom)
			)
		)
		(fp_text user "License: Apache-2.0"
			(at -4.202 9.598 270)
			(layer "F.Fab")
			(effects
				(font
					(size 0.7 0.7)
					(thickness 0.15)
				)
				(justify left bottom)
			)
		)
		(fp_text user "${REFERENCE}"
			(at -4.202 7.2 270)
			(layer "F.Fab")
			(effects
				(font
					(size 0.7 0.7)
					(thickness 0.15)
				)
				(justify left bottom)
			)
		)
		(pad "1" smd oval
			(at -3.5 -2.75)
			(size 0.3 0.9)
			(layers "F.Cu" "F.Mask" "F.Paste")
			(net 97 "/Ethernet/AVDDH")
			(pinfunction "AVDDH")
			(pintype "power_in")
		)
		(pad "2" smd oval
			(at -3.5 -2.25)
			(size 0.3 0.9)
			(layers "F.Cu" "F.Mask" "F.Paste")
			(net 88 "/Ethernet/ETH1_P")
			(pinfunction "TXRXP_A")
			(pintype "bidirectional")
		)
		(pad "3" smd oval
			(at -3.5 -1.75)
			(size 0.3 0.9)
			(layers "F.Cu" "F.Mask" "F.Paste")
			(net 91 "/Ethernet/ETH1_N")
			(pinfunction "TXRXM_A")
			(pintype "bidirectional")
		)
		(pad "4" smd oval
			(at -3.5 -1.25)
			(size 0.3 0.9)
			(layers "F.Cu" "F.Mask" "F.Paste")
			(net 95 "/Ethernet/AVDDL")
			(pinfunction "AVDDL")
			(pintype "power_in")
		)
		(pad "5" smd oval
			(at -3.5 -0.75)
			(size 0.3 0.9)
			(layers "F.Cu" "F.Mask" "F.Paste")
			(net 87 "/Ethernet/ETH2_P")
			(pinfunction "TXRXP_B")
			(pintype "bidirectional")
		)
		(pad "6" smd oval
			(at -3.5 -0.25)
			(size 0.3 0.9)
			(layers "F.Cu" "F.Mask" "F.Paste")
			(net 90 "/Ethernet/ETH2_N")
			(pinfunction "TXRXM_B")
			(pintype "bidirectional")
		)
		(pad "7" smd oval
			(at -3.5 0.248)
			(size 0.3 0.9)
			(layers "F.Cu" "F.Mask" "F.Paste")
			(net 86 "/Ethernet/ETH3_P")
			(pinfunction "TXRXP_C")
			(pintype "bidirectional")
		)
		(pad "8" smd oval
			(at -3.5 0.748)
			(size 0.3 0.9)
			(layers "F.Cu" "F.Mask" "F.Paste")
			(net 92 "/Ethernet/ETH3_N")
			(pinfunction "TXRXM_C")
			(pintype "bidirectional")
		)
		(pad "9" smd oval
			(at -3.5 1.249)
			(size 0.3 0.9)
			(layers "F.Cu" "F.Mask" "F.Paste")
			(net 95 "/Ethernet/AVDDL")
			(pinfunction "AVDDL")
			(pintype "passive")
		)
		(pad "10" smd oval
			(at -3.5 1.749)
			(size 0.3 0.9)
			(layers "F.Cu" "F.Mask" "F.Paste")
			(net 89 "/Ethernet/ETH4_P")
			(pinfunction "TXRXP_D")
			(pintype "bidirectional")
		)
		(pad "11" smd oval
			(at -3.5 2.249)
			(size 0.3 0.9)
			(layers "F.Cu" "F.Mask" "F.Paste")
			(net 93 "/Ethernet/ETH4_N")
			(pinfunction "TXRXM_D")
			(pintype "bidirectional")
		)
		(pad "12" smd oval
			(at -3.5 2.749)
			(size 0.3 0.9)
			(layers "F.Cu" "F.Mask" "F.Paste")
			(net 97 "/Ethernet/AVDDH")
			(pinfunction "AVDDH")
			(pintype "passive")
		)
		(pad "13" smd oval
			(at -2.75 3.499 270)
			(size 0.3 0.9)
			(layers "F.Cu" "F.Mask" "F.Paste")
			(net 425 "unconnected-(U15-NC-Pad13)")
			(pinfunction "NC")
			(pintype "no_connect")
		)
		(pad "14" smd oval
			(at -2.25 3.499 270)
			(size 0.3 0.9)
			(layers "F.Cu" "F.Mask" "F.Paste")
			(net 150 "+1V2")
			(pinfunction "DVDDL")
			(pintype "power_in")
		)
		(pad "15" smd oval
			(at -1.75 3.499 270)
			(size 0.3 0.9)
			(layers "F.Cu" "F.Mask" "F.Paste")
			(net 330 "/Ethernet/LED_SPD")
			(pinfunction "LED2/PHYAD1")
			(pintype "bidirectional")
		)
		(pad "16" smd oval
			(at -1.25 3.499 270)
			(size 0.3 0.9)
			(layers "F.Cu" "F.Mask" "F.Paste")
			(net 797 "+1V8")
			(pinfunction "DVDDH")
			(pintype "power_in")
		)
		(pad "17" smd oval
			(at -0.75 3.499 270)
			(size 0.3 0.9)
			(layers "F.Cu" "F.Mask" "F.Paste")
			(net 331 "/Ethernet/LED_LINK")
			(pinfunction "LED1/PHYAD0/PME_N1")
			(pintype "bidirectional")
		)
		(pad "18" smd oval
			(at -0.25 3.499 270)
			(size 0.3 0.9)
			(layers "F.Cu" "F.Mask" "F.Paste")
			(net 150 "+1V2")
			(pinfunction "DVDDL")
			(pintype "passive")
		)
		(pad "19" smd oval
			(at 0.248 3.499 270)
			(size 0.3 0.9)
			(layers "F.Cu" "F.Mask" "F.Paste")
			(net 436 "/Ethernet/ETH.TXD0")
			(pinfunction "TXD0")
			(pintype "input")
		)
		(pad "20" smd oval
			(at 0.748 3.499 270)
			(size 0.3 0.9)
			(layers "F.Cu" "F.Mask" "F.Paste")
			(net 440 "/Ethernet/ETH.TXD1")
			(pinfunction "TXD1")
			(pintype "input")
		)
		(pad "21" smd oval
			(at 1.249 3.499 270)
			(size 0.3 0.9)
			(layers "F.Cu" "F.Mask" "F.Paste")
			(net 439 "/Ethernet/ETH.TXD2")
			(pinfunction "TXD2")
			(pintype "input")
		)
		(pad "22" smd oval
			(at 1.749 3.499 270)
			(size 0.3 0.9)
			(layers "F.Cu" "F.Mask" "F.Paste")
			(net 438 "/Ethernet/ETH.TXD3")
			(pinfunction "TXD3")
			(pintype "input")
		)
		(pad "23" smd oval
			(at 2.249 3.499 270)
			(size 0.3 0.9)
			(layers "F.Cu" "F.Mask" "F.Paste")
			(net 150 "+1V2")
			(pinfunction "DVDDL")
			(pintype "passive")
		)
		(pad "24" smd oval
			(at 2.749 3.499 270)
			(size 0.3 0.9)
			(layers "F.Cu" "F.Mask" "F.Paste")
			(net 409 "/Ethernet/ETH.TXC")
			(pinfunction "GTX_CLK")
			(pintype "input")
		)
		(pad "25" smd oval
			(at 3.499 2.749)
			(size 0.3 0.9)
			(layers "F.Cu" "F.Mask" "F.Paste")
			(net 435 "/Ethernet/ETH.TX_CTL")
			(pinfunction "TX_EN")
			(pintype "input")
		)
		(pad "26" smd oval
			(at 3.499 2.249)
			(size 0.3 0.9)
			(layers "F.Cu" "F.Mask" "F.Paste")
			(net 150 "+1V2")
			(pinfunction "DVDDL")
			(pintype "passive")
		)
		(pad "27" smd oval
			(at 3.499 1.749)
			(size 0.3 0.9)
			(layers "F.Cu" "F.Mask" "F.Paste")
			(net 396 "/Ethernet/ETH.RXD3")
			(pinfunction "RXD3/MODE3")
			(pintype "input")
		)
		(pad "28" smd oval
			(at 3.499 1.249)
			(size 0.3 0.9)
			(layers "F.Cu" "F.Mask" "F.Paste")
			(net 395 "/Ethernet/ETH.RXD2")
			(pinfunction "RXD2/MODE2")
			(pintype "input")
		)
		(pad "29" smd oval
			(at 3.499 0.748)
			(size 0.3 0.9)
			(layers "F.Cu" "F.Mask" "F.Paste")
			(net 1 "GND")
			(pinfunction "VSS")
			(pintype "power_in")
		)
		(pad "30" smd oval
			(at 3.499 0.248)
			(size 0.3 0.9)
			(layers "F.Cu" "F.Mask" "F.Paste")
			(net 150 "+1V2")
			(pinfunction "DVDDL")
			(pintype "passive")
		)
		(pad "31" smd oval
			(at 3.499 -0.25)
			(size 0.3 0.9)
			(layers "F.Cu" "F.Mask" "F.Paste")
			(net 394 "/Ethernet/ETH.RXD1")
			(pinfunction "RXD1/MODE1")
			(pintype "input")
		)
		(pad "32" smd oval
			(at 3.499 -0.75)
			(size 0.3 0.9)
			(layers "F.Cu" "F.Mask" "F.Paste")
			(net 393 "/Ethernet/ETH.RXD0")
			(pinfunction "RXD0/MODE0")
			(pintype "input")
		)
		(pad "33" smd oval
			(at 3.499 -1.25)
			(size 0.3 0.9)
			(layers "F.Cu" "F.Mask" "F.Paste")
			(net 397 "/Ethernet/ETH.RX_CTL")
			(pinfunction "RX_DV/CLK125_EN")
			(pintype "input")
		)
		(pad "34" smd oval
			(at 3.499 -1.75)
			(size 0.3 0.9)
			(layers "F.Cu" "F.Mask" "F.Paste")
			(net 797 "+1V8")
			(pinfunction "DVDDH")
			(pintype "passive")
		)
		(pad "35" smd oval
			(at 3.499 -2.25)
			(size 0.3 0.9)
			(layers "F.Cu" "F.Mask" "F.Paste")
			(net 398 "/Ethernet/ETH.RXC")
			(pinfunction "RX_CLK/PHYAD2")
			(pintype "input")
		)
		(pad "36" smd oval
			(at 3.499 -2.75)
			(size 0.3 0.9)
			(layers "F.Cu" "F.Mask" "F.Paste")
			(net 410 "/Ethernet/ETH.MDC")
			(pinfunction "MDC")
			(pintype "input")
		)
		(pad "37" smd oval
			(at 2.749 -3.5 270)
			(size 0.3 0.9)
			(layers "F.Cu" "F.Mask" "F.Paste")
			(net 400 "/Ethernet/ETH.MDIO")
			(pinfunction "MDIO")
			(pintype "input")
		)
		(pad "38" smd oval
			(at 2.249 -3.5 270)
			(size 0.3 0.9)
			(layers "F.Cu" "F.Mask" "F.Paste")
			(net 437 "/Ethernet/ETH.~{INT}")
			(pinfunction "~{INT/PME}")
			(pintype "input")
		)
		(pad "39" smd oval
			(at 1.749 -3.5 270)
			(size 0.3 0.9)
			(layers "F.Cu" "F.Mask" "F.Paste")
			(net 150 "+1V2")
			(pinfunction "DVDDL")
			(pintype "passive")
		)
		(pad "40" smd oval
			(at 1.249 -3.5 270)
			(size 0.3 0.9)
			(layers "F.Cu" "F.Mask" "F.Paste")
			(net 797 "+1V8")
			(pinfunction "DVDDH")
			(pintype "passive")
		)
		(pad "41" smd oval
			(at 0.748 -3.5 270)
			(size 0.3 0.9)
			(layers "F.Cu" "F.Mask" "F.Paste")
			(net 399 "/Ethernet/ETH.REF_CLK")
			(pinfunction "CLK125_NDO/LED_MODE")
			(pintype "input")
		)
		(pad "42" smd oval
			(at 0.248 -3.5 270)
			(size 0.3 0.9)
			(layers "F.Cu" "F.Mask" "F.Paste")
			(net 401 "/Ethernet/ETH.~{RESET}")
			(pinfunction "~{RESET}")
			(pintype "input")
		)
		(pad "43" smd oval
			(at -0.25 -3.5 270)
			(size 0.3 0.9)
			(layers "F.Cu" "F.Mask" "F.Paste")
			(net 426 "unconnected-(U15-LDO_O-Pad43)")
			(pinfunction "LDO_O")
			(pintype "input+no_connect")
		)
		(pad "44" smd oval
			(at -0.75 -3.5 270)
			(size 0.3 0.9)
			(layers "F.Cu" "F.Mask" "F.Paste")
			(net 96 "/Ethernet/AVDDL_PLL")
			(pinfunction "AVDDL_PLL")
			(pintype "power_in")
		)
		(pad "45" smd oval
			(at -1.25 -3.5 270)
			(size 0.3 0.9)
			(layers "F.Cu" "F.Mask" "F.Paste")
			(net 228 "Net-(U15-XO)")
			(pinfunction "XO")
			(pintype "input")
		)
		(pad "46" smd oval
			(at -1.75 -3.5 270)
			(size 0.3 0.9)
			(layers "F.Cu" "F.Mask" "F.Paste")
			(net 227 "Net-(U15-XI)")
			(pinfunction "XI")
			(pintype "input")
		)
		(pad "47" smd oval
			(at -2.25 -3.5 270)
			(size 0.3 0.9)
			(layers "F.Cu" "F.Mask" "F.Paste")
			(net 427 "unconnected-(U15-NC-Pad47)")
			(pinfunction "NC")
			(pintype "no_connect")
		)
		(pad "48" smd oval
			(at -2.75 -3.5 270)
			(size 0.3 0.9)
			(layers "F.Cu" "F.Mask" "F.Paste")
			(net 302 "Net-(U15-ISET)")
			(pinfunction "ISET")
			(pintype "output")
		)
		(pad "49" smd rect
			(at 0 0 270)
			(size 3.5 3.5)
			(layers "F.Cu" "F.Mask" "F.Paste")
			(net 1 "GND")
			(pinfunction "PAD_GND")
			(pintype "power_in")
		)
	)
	(footprint "antmicro-footprints:HDMI-A_Receptacle_WE_685119134923"
		(layer "F.Cu")
		(at 104.145 179.215 90)
		(property "Reference" "J4"
			(at -9.16 6.88 0)
			(layer "F.SilkS")
			(effects
				(font
					(size 0.7 0.7)
					(thickness 0.15)
				)
				(justify right bottom)
			)
		)
		(property "Value" "HDMI-A_WE_685119134923"
			(at 0 7.8 90)
			(layer "F.Fab")
			(effects
				(font
					(size 0.7 0.7)
					(thickness 0.15)
				)
				(justify left bottom)
			)
		)
		(property "Datasheet" "https://www.we-online.com/components/products/datasheet/685119134923.pdf"
			(at 0 0 90)
			(layer "F.Fab")
			(hide yes)
			(effects
				(font
					(size 1.27 1.27)
					(thickness 0.15)
				)
			)
		)
		(property "MPN" "685119134923"
			(at 0 0 90)
			(unlocked yes)
			(layer "F.Fab")
			(hide yes)
			(effects
				(font
					(size 1 1)
					(thickness 0.15)
				)
			)
		)
		(property "Manufacturer" "Würth Elektronik"
			(at 0 0 90)
			(unlocked yes)
			(layer "F.Fab")
			(hide yes)
			(effects
				(font
					(size 1 1)
					(thickness 0.15)
				)
			)
		)
		(property "Author" "Antmicro"
			(at 0 0 90)
			(unlocked yes)
			(layer "F.Fab")
			(hide yes)
			(effects
				(font
					(size 1 1)
					(thickness 0.15)
				)
			)
		)
		(property "License" "Apache-2.0"
			(at 0 0 90)
			(unlocked yes)
			(layer "F.Fab")
			(hide yes)
			(effects
				(font
					(size 1 1)
					(thickness 0.15)
				)
			)
		)
		(property ki_fp_filters "685119134923")
		(sheetname "/HDMI + SD Card/")
		(sheetfile "hdmi-sd-card.kicad_sch")
		(attr smd)
		(fp_line
			(start -7.55 -0.125)
			(end -7.55 2.65)
			(stroke
				(width 0.12)
				(type solid)
			)
			(layer "F.SilkS")
		)
		(fp_line
			(start 7.55 2.75)
			(end 7.55 -0.15)
			(stroke
				(width 0.12)
				(type solid)
			)
			(layer "F.SilkS")
		)
		(fp_line
			(start 5.7 5.65)
			(end 4.75 5.65)
			(stroke
				(width 0.12)
				(type solid)
			)
			(layer "F.SilkS")
		)
		(fp_line
			(start -4.85 5.65)
			(end -5.8 5.65)
			(stroke
				(width 0.12)
				(type solid)
			)
			(layer "F.SilkS")
		)
		(fp_circle
			(center -4.9 5.9)
			(end -4.85 5.9)
			(stroke
				(width 0.15)
				(type solid)
			)
			(fill no)
			(layer "F.SilkS")
		)
		(fp_rect
			(start -8.05 -6.32)
			(end 7.949 6.78)
			(stroke
				(width 0.05)
				(type solid)
			)
			(fill no)
			(layer "F.CrtYd")
		)
		(fp_line
			(start -7.05 -5.616)
			(end 6.95 -5.616)
			(stroke
				(width 0.15)
				(type solid)
			)
			(layer "F.Fab")
		)
		(fp_line
			(start -7.05 5.525)
			(end -7.05 -5.616)
			(stroke
				(width 0.15)
				(type solid)
			)
			(layer "F.Fab")
		)
		(fp_line
			(start -7.05 5.525)
			(end -6.05 6.525)
			(stroke
				(width 0.15)
				(type solid)
			)
			(layer "F.Fab")
		)
		(fp_line
			(start 6.95 6.535)
			(end 6.95 -5.616)
			(stroke
				(width 0.15)
				(type solid)
			)
			(layer "F.Fab")
		)
		(fp_line
			(start 6.95 6.535)
			(end -6.05 6.535)
			(stroke
				(width 0.15)
				(type solid)
			)
			(layer "F.Fab")
		)
		(fp_text user "${REFERENCE}"
			(at -8 9.5 90)
			(layer "F.Fab")
			(effects
				(font
					(size 0.7 0.7)
					(thickness 0.15)
				)
				(justify left bottom)
			)
		)
		(fp_text user "License: Apache-2.0"
			(at -8 12.5 90)
			(layer "F.Fab")
			(effects
				(font
					(size 0.7 0.7)
					(thickness 0.15)
				)
				(justify left bottom)
			)
		)
		(fp_text user "Author: Antmicro"
			(at -8 11 90)
			(layer "F.Fab")
			(effects
				(font
					(size 0.7 0.7)
					(thickness 0.15)
				)
				(justify left bottom)
			)
		)
		(pad "1" smd rect
			(at -4.55 5.224 90)
			(size 0.28 2.6)
			(layers "F.Cu" "F.Mask" "F.Paste")
			(net 654 "/HDMI + SD Card/HDMI_OUT_CONN_D2_P")
			(pinfunction "D2+")
			(pintype "bidirectional")
		)
		(pad "2" smd rect
			(at -4.05 5.224 90)
			(size 0.28 2.6)
			(layers "F.Cu" "F.Mask" "F.Paste")
			(net 1 "GND")
			(pinfunction "D2S")
			(pintype "passive")
		)
		(pad "3" smd rect
			(at -3.551 5.224 90)
			(size 0.28 2.6)
			(layers "F.Cu" "F.Mask" "F.Paste")
			(net 655 "/HDMI + SD Card/HDMI_OUT_CONN_D2_N")
			(pinfunction "D2-")
			(pintype "bidirectional")
		)
		(pad "4" smd rect
			(at -3.051 5.224 90)
			(size 0.28 2.6)
			(layers "F.Cu" "F.Mask" "F.Paste")
			(net 656 "/HDMI + SD Card/HDMI_OUT_CONN_D1_P")
			(pinfunction "D1+")
			(pintype "bidirectional")
		)
		(pad "5" smd rect
			(at -2.551 5.224 90)
			(size 0.28 2.6)
			(layers "F.Cu" "F.Mask" "F.Paste")
			(net 1 "GND")
			(pinfunction "D1S")
			(pintype "passive")
		)
		(pad "6" smd rect
			(at -2.05 5.224 90)
			(size 0.28 2.6)
			(layers "F.Cu" "F.Mask" "F.Paste")
			(net 657 "/HDMI + SD Card/HDMI_OUT_CONN_D1_N")
			(pinfunction "D1-")
			(pintype "bidirectional")
		)
		(pad "7" smd rect
			(at -1.551 5.224 90)
			(size 0.28 2.6)
			(layers "F.Cu" "F.Mask" "F.Paste")
			(net 658 "/HDMI + SD Card/HDMI_OUT_CONN_D0_P")
			(pinfunction "D0+")
			(pintype "bidirectional")
		)
		(pad "8" smd rect
			(at -1.051 5.224 90)
			(size 0.28 2.6)
			(layers "F.Cu" "F.Mask" "F.Paste")
			(net 1 "GND")
			(pinfunction "D0S")
			(pintype "passive")
		)
		(pad "9" smd rect
			(at -0.551 5.224 90)
			(size 0.28 2.6)
			(layers "F.Cu" "F.Mask" "F.Paste")
			(net 659 "/HDMI + SD Card/HDMI_OUT_CONN_D0_N")
			(pinfunction "D0-")
			(pintype "bidirectional")
		)
		(pad "10" smd rect
			(at -0.051 5.224 90)
			(size 0.28 2.6)
			(layers "F.Cu" "F.Mask" "F.Paste")
			(net 660 "/HDMI + SD Card/HDMI_OUT_CONN_CLK_P")
			(pinfunction "CK+")
			(pintype "bidirectional")
		)
		(pad "11" smd rect
			(at 0.45 5.224 90)
			(size 0.28 2.6)
			(layers "F.Cu" "F.Mask" "F.Paste")
			(net 1 "GND")
			(pinfunction "CKS")
			(pintype "passive")
		)
		(pad "12" smd rect
			(at 0.95 5.224 90)
			(size 0.28 2.6)
			(layers "F.Cu" "F.Mask" "F.Paste")
			(net 661 "/HDMI + SD Card/HDMI_OUT_CONN_CLK_N")
			(pinfunction "CK-")
			(pintype "bidirectional")
		)
		(pad "13" smd rect
			(at 1.449 5.224 90)
			(size 0.28 2.6)
			(layers "F.Cu" "F.Mask" "F.Paste")
			(net 603 "unconnected-(J4-CEC-Pad13)")
			(pinfunction "CEC")
			(pintype "bidirectional+no_connect")
		)
		(pad "14" smd rect
			(at 1.949 5.224 90)
			(size 0.28 2.6)
			(layers "F.Cu" "F.Mask" "F.Paste")
			(net 247 "unconnected-(J4-UTILITY{slash}HEAC+-Pad14)")
			(pinfunction "UTILITY/HEAC+")
			(pintype "bidirectional+no_connect")
		)
		(pad "15" smd rect
			(at 2.45 5.224 90)
			(size 0.28 2.6)
			(layers "F.Cu" "F.Mask" "F.Paste")
			(net 467 "/HDMI + SD Card/HDMI_OUT_C.SCL")
			(pinfunction "SCL")
			(pintype "bidirectional")
		)
		(pad "16" smd rect
			(at 2.95 5.224 90)
			(size 0.28 2.6)
			(layers "F.Cu" "F.Mask" "F.Paste")
			(net 468 "/HDMI + SD Card/HDMI_OUT_C.SDA")
			(pinfunction "SDA")
			(pintype "bidirectional")
		)
		(pad "17" smd rect
			(at 3.45 5.224 90)
			(size 0.28 2.6)
			(layers "F.Cu" "F.Mask" "F.Paste")
			(net 1 "GND")
			(pinfunction "GND")
			(pintype "power_in")
		)
		(pad "18" smd rect
			(at 3.95 5.224 90)
			(size 0.28 2.6)
			(layers "F.Cu" "F.Mask" "F.Paste")
			(net 8 "/HDMI + SD Card/HDMI_CONN_5V")
			(pinfunction "+5V")
			(pintype "power_in")
		)
		(pad "19" smd rect
			(at 4.45 5.224 90)
			(size 0.28 2.6)
			(layers "F.Cu" "F.Mask" "F.Paste")
			(net 605 "/HDMI + SD Card/HDMI0.HPD")
			(pinfunction "HPD/HEAC-")
			(pintype "bidirectional")
		)
		(pad "SH" thru_hole oval
			(at -7.3 -1.577 90)
			(size 1.5 2.7)
			(drill oval 0.9 2.1)
			(layers "*.Cu" "*.Mask")
			(remove_unused_layers no)
			(net 188 "Net-(C132-Pad1)")
			(pinfunction "SH")
			(pintype "passive")
		)
		(pad "SH" thru_hole oval
			(at -7.3 4.424 90)
			(size 1.5 3.3)
			(drill oval 0.9 2.7)
			(layers "*.Cu" "*.Mask")
			(remove_unused_layers no)
			(net 188 "Net-(C132-Pad1)")
			(pinfunction "SH")
			(pintype "passive")
		)
		(pad "SH" thru_hole oval
			(at 7.2 -1.577 90)
			(size 1.5 2.7)
			(drill oval 0.9 2.1)
			(layers "*.Cu" "*.Mask")
			(remove_unused_layers no)
			(net 188 "Net-(C132-Pad1)")
			(pinfunction "SH")
			(pintype "passive")
		)
		(pad "SH" thru_hole oval
			(at 7.2 4.424 90)
			(size 1.5 3.3)
			(drill oval 0.9 2.7)
			(layers "*.Cu" "*.Mask")
			(remove_unused_layers no)
			(net 188 "Net-(C132-Pad1)")
			(pinfunction "SH")
			(pintype "passive")
		)
	)
	(footprint "antmicro-footprints:R_0402_1005Metric"
		(layer "F.Cu")
		(at 134.324499 166.449)
		(descr "Resistor SMD 0402")
		(tags "resistor SMD 0402")
		(property "Reference" "R43"
			(at 0.725501 1.451 0)
			(layer "F.SilkS")
			(effects
				(font
					(size 0.7 0.7)
					(thickness 0.15)
				)
				(justify left bottom)
			)
		)
		(property "Value" "R_10k_0402"
			(at -1.011843 1.772047 0)
			(layer "F.Fab")
			(effects
				(font
					(size 0.7 0.7)
					(thickness 0.15)
				)
				(justify left bottom)
			)
		)
		(property "Datasheet" "https://www.bourns.com/docs/product-datasheets/cr.pdf"
			(at 0 0 0)
			(layer "F.Fab")
			(hide yes)
			(effects
				(font
					(size 1.27 1.27)
					(thickness 0.15)
				)
			)
		)
		(property "Manufacturer" "Bourns"
			(at 0 0 0)
			(unlocked yes)
			(layer "F.Fab")
			(hide yes)
			(effects
				(font
					(size 1 1)
					(thickness 0.15)
				)
			)
		)
		(property "MPN" "CR0402-FX-1002GLF"
			(at 0 0 0)
			(unlocked yes)
			(layer "F.Fab")
			(hide yes)
			(effects
				(font
					(size 1 1)
					(thickness 0.15)
				)
			)
		)
		(property "Val" "10k"
			(at 0 0 0)
			(unlocked yes)
			(layer "F.Fab")
			(hide yes)
			(effects
				(font
					(size 1 1)
					(thickness 0.15)
				)
			)
		)
		(property "License" "Apache-2.0"
			(at 0 0 0)
			(unlocked yes)
			(layer "F.Fab")
			(hide yes)
			(effects
				(font
					(size 1 1)
					(thickness 0.15)
				)
			)
		)
		(property "Author" "Antmicro"
			(at 0 0 0)
			(unlocked yes)
			(layer "F.Fab")
			(hide yes)
			(effects
				(font
					(size 1 1)
					(thickness 0.15)
				)
			)
		)
		(property "Tolerance" "1%"
			(at 0 0 0)
			(unlocked yes)
			(layer "F.Fab")
			(hide yes)
			(effects
				(font
					(size 1 1)
					(thickness 0.15)
				)
			)
		)
		(sheetname "/Debug FTDI + VNA/")
		(sheetfile "debug-ftdi.kicad_sch")
		(attr smd)
		(fp_rect
			(start -0.925 -0.47)
			(end 0.925 0.47)
			(stroke
				(width 0.05)
				(type default)
			)
			(fill no)
			(layer "F.CrtYd")
		)
		(fp_rect
			(start -0.5 -0.25)
			(end 0.5 0.25)
			(stroke
				(width 0.15)
				(type solid)
			)
			(fill no)
			(layer "F.Fab")
		)
		(fp_text user "Author: Antmicro"
			(at -0.95 4.169 0)
			(layer "F.Fab")
			(effects
				(font
					(size 0.7 0.7)
					(thickness 0.15)
				)
				(justify left bottom)
			)
		)
		(fp_text user "${REFERENCE}"
			(at -0.95 3.168 0)
			(layer "F.Fab")
			(effects
				(font
					(size 0.7 0.7)
					(thickness 0.15)
				)
				(justify left bottom)
			)
		)
		(fp_text user "License: Apache-2.0"
			(at -0.95 5.169 0)
			(layer "F.Fab")
			(effects
				(font
					(size 0.7 0.7)
					(thickness 0.15)
				)
				(justify left bottom)
			)
		)
		(pad "1" smd roundrect
			(at -0.48 0)
			(size 0.59 0.64)
			(layers "F.Cu" "F.Mask" "F.Paste")
			(roundrect_rratio 0.25)
			(net 6 "/Debug FTDI + VNA/FTDI_3V3")
			(pintype "passive")
		)
		(pad "2" smd roundrect
			(at 0.48 0)
			(size 0.59 0.64)
			(layers "F.Cu" "F.Mask" "F.Paste")
			(roundrect_rratio 0.25)
			(net 289 "Net-(U6-~{RESET})")
			(pintype "passive")
		)
	)
	(footprint "antmicro-footprints:R_0402_1005Metric"
		(layer "F.Cu")
		(at 122.681 168.3125 90)
		(descr "Resistor SMD 0402")
		(tags "resistor SMD 0402")
		(property "Reference" "R221"
			(at -3.825 0.619 90)
			(layer "F.SilkS")
			(effects
				(font
					(size 0.7 0.7)
					(thickness 0.15)
				)
				(justify left bottom)
			)
		)
		(property "Value" "R_64k9_0402"
			(at -1.011843 1.772047 90)
			(layer "F.Fab")
			(effects
				(font
					(size 0.7 0.7)
					(thickness 0.15)
				)
				(justify left bottom)
			)
		)
		(property "Datasheet" "https://www.bourns.com/docs/product-datasheets/cr.pdf"
			(at 0 0 90)
			(layer "F.Fab")
			(hide yes)
			(effects
				(font
					(size 1.27 1.27)
					(thickness 0.15)
				)
			)
		)
		(property "MPN" "CR0402-FX-6492GLF"
			(at 0 0 90)
			(unlocked yes)
			(layer "F.Fab")
			(hide yes)
			(effects
				(font
					(size 1 1)
					(thickness 0.15)
				)
			)
		)
		(property "Manufacturer" "Bourns"
			(at 0 0 90)
			(unlocked yes)
			(layer "F.Fab")
			(hide yes)
			(effects
				(font
					(size 1 1)
					(thickness 0.15)
				)
			)
		)
		(property "License" "Apache-2.0"
			(at 0 0 90)
			(unlocked yes)
			(layer "F.Fab")
			(hide yes)
			(effects
				(font
					(size 1 1)
					(thickness 0.15)
				)
			)
		)
		(property "Author" "Antmicro"
			(at 0 0 90)
			(unlocked yes)
			(layer "F.Fab")
			(hide yes)
			(effects
				(font
					(size 1 1)
					(thickness 0.15)
				)
			)
		)
		(property "Val" "64k9"
			(at 0 0 90)
			(unlocked yes)
			(layer "F.Fab")
			(hide yes)
			(effects
				(font
					(size 1 1)
					(thickness 0.15)
				)
			)
		)
		(property "Tolerance" "1%"
			(at 0 0 90)
			(unlocked yes)
			(layer "F.Fab")
			(hide yes)
			(effects
				(font
					(size 1 1)
					(thickness 0.15)
				)
			)
		)
		(sheetname "/HDMI + SD Card/")
		(sheetfile "hdmi-sd-card.kicad_sch")
		(attr smd exclude_from_bom dnp)
		(fp_rect
			(start -0.925 -0.47)
			(end 0.925 0.47)
			(stroke
				(width 0.05)
				(type default)
			)
			(fill no)
			(layer "F.CrtYd")
		)
		(fp_rect
			(start -0.5 -0.25)
			(end 0.5 0.25)
			(stroke
				(width 0.15)
				(type solid)
			)
			(fill no)
			(layer "F.Fab")
		)
		(fp_text user "Author: Antmicro"
			(at -0.95 4.169 90)
			(layer "F.Fab")
			(effects
				(font
					(size 0.7 0.7)
					(thickness 0.15)
				)
				(justify left bottom)
			)
		)
		(fp_text user "License: Apache-2.0"
			(at -0.95 5.169 90)
			(layer "F.Fab")
			(effects
				(font
					(size 0.7 0.7)
					(thickness 0.15)
				)
				(justify left bottom)
			)
		)
		(fp_text user "${REFERENCE}"
			(at -0.95 3.168 90)
			(layer "F.Fab")
			(effects
				(font
					(size 0.7 0.7)
					(thickness 0.15)
				)
				(justify left bottom)
			)
		)
		(pad "1" smd roundrect
			(at -0.48 0 90)
			(size 0.59 0.64)
			(layers "F.Cu" "F.Mask" "F.Paste")
			(roundrect_rratio 0.25)
			(net 1 "GND")
			(pintype "passive")
		)
		(pad "2" smd roundrect
			(at 0.48 0 90)
			(size 0.59 0.64)
			(layers "F.Cu" "F.Mask" "F.Paste")
			(roundrect_rratio 0.25)
			(net 740 "/HDMI + SD Card/SLEW_CTL")
			(pintype "passive")
		)
	)
	(footprint "antmicro-footprints:SC70-3"
		(layer "F.Cu")
		(at 121.05 115.13269 90)
		(property "Reference" "Q1"
			(at -0.463539 -0.75 180)
			(layer "F.SilkS")
			(effects
				(font
					(size 0.7 0.7)
					(thickness 0.15)
				)
				(justify left bottom)
			)
		)
		(property "Value" "BSS138PW"
			(at 0 2.3 90)
			(layer "F.Fab")
			(effects
				(font
					(size 0.7 0.7)
					(thickness 0.15)
				)
				(justify left bottom)
			)
		)
		(property "Datasheet" "https://assets.nexperia.com/documents/data-sheet/BSS138PW.pdf"
			(at 0 0 90)
			(layer "F.Fab")
			(hide yes)
			(effects
				(font
					(size 1.27 1.27)
					(thickness 0.15)
				)
			)
		)
		(property "MPN" "BSS138PW"
			(at 0 0 90)
			(unlocked yes)
			(layer "F.Fab")
			(hide yes)
			(effects
				(font
					(size 1 1)
					(thickness 0.15)
				)
			)
		)
		(property "Manufacturer" "Nexperia"
			(at 0 0 90)
			(unlocked yes)
			(layer "F.Fab")
			(hide yes)
			(effects
				(font
					(size 1 1)
					(thickness 0.15)
				)
			)
		)
		(property "Author" "Antmicro"
			(at 0 0 90)
			(unlocked yes)
			(layer "F.Fab")
			(hide yes)
			(effects
				(font
					(size 1 1)
					(thickness 0.15)
				)
			)
		)
		(property "License" "Apache-2.0"
			(at 0 0 90)
			(unlocked yes)
			(layer "F.Fab")
			(hide yes)
			(effects
				(font
					(size 1 1)
					(thickness 0.15)
				)
			)
		)
		(sheetname "/FPGA Config/")
		(sheetfile "fpga-config.kicad_sch")
		(attr smd)
		(fp_line
			(start -0.3 -1)
			(end 0.627 -0.999)
			(stroke
				(width 0.15)
				(type solid)
			)
			(layer "F.SilkS")
		)
		(fp_line
			(start 0.627 -0.6)
			(end 0.627 -0.999)
			(stroke
				(width 0.15)
				(type solid)
			)
			(layer "F.SilkS")
		)
		(fp_line
			(start 0.627 0.6)
			(end 0.627 1.001)
			(stroke
				(width 0.15)
				(type solid)
			)
			(layer "F.SilkS")
		)
		(fp_line
			(start -0.3 1)
			(end 0.627 1.001)
			(stroke
				(width 0.15)
				(type solid)
			)
			(layer "F.SilkS")
		)
		(fp_line
			(start 0.9 -1.3)
			(end 0.9 -0.4)
			(stroke
				(width 0.05)
				(type solid)
			)
			(layer "F.CrtYd")
		)
		(fp_line
			(start -0.9 -1.3)
			(end 0.9 -1.3)
			(stroke
				(width 0.05)
				(type solid)
			)
			(layer "F.CrtYd")
		)
		(fp_line
			(start -0.9 -1.3)
			(end -0.9 -1)
			(stroke
				(width 0.05)
				(type solid)
			)
			(layer "F.CrtYd")
		)
		(fp_line
			(start -0.9 -1)
			(end -1.4 -1)
			(stroke
				(width 0.05)
				(type solid)
			)
			(layer "F.CrtYd")
		)
		(fp_line
			(start 1.4 -0.4)
			(end 1.4 0.4)
			(stroke
				(width 0.05)
				(type solid)
			)
			(layer "F.CrtYd")
		)
		(fp_line
			(start 0.9 -0.4)
			(end 1.4 -0.4)
			(stroke
				(width 0.05)
				(type solid)
			)
			(layer "F.CrtYd")
		)
		(fp_line
			(start 1.4 0.4)
			(end 0.9 0.4)
			(stroke
				(width 0.05)
				(type solid)
			)
			(layer "F.CrtYd")
		)
		(fp_line
			(start 0.9 0.4)
			(end 0.9 1.3)
			(stroke
				(width 0.05)
				(type solid)
			)
			(layer "F.CrtYd")
		)
		(fp_line
			(start -0.9 1)
			(end -1.4 1)
			(stroke
				(width 0.05)
				(type solid)
			)
			(layer "F.CrtYd")
		)
		(fp_line
			(start -1.4 1)
			(end -1.4 -1)
			(stroke
				(width 0.05)
				(type solid)
			)
			(layer "F.CrtYd")
		)
		(fp_line
			(start 0.9 1.3)
			(end -0.9 1.3)
			(stroke
				(width 0.05)
				(type solid)
			)
			(layer "F.CrtYd")
		)
		(fp_line
			(start -0.9 1.3)
			(end -0.9 1)
			(stroke
				(width 0.05)
				(type solid)
			)
			(layer "F.CrtYd")
		)
		(fp_rect
			(start -0.623 -0.999)
			(end 0.627 1.001)
			(stroke
				(width 0.15)
				(type solid)
			)
			(fill no)
			(layer "F.Fab")
		)
		(fp_text user "License: Apache-2.0"
			(at -1.45 6.782 90)
			(layer "F.Fab")
			(effects
				(font
					(size 0.7 0.7)
					(thickness 0.15)
				)
				(justify left bottom)
			)
		)
		(fp_text user "Author: Antmicro"
			(at -1.45 5.782 90)
			(layer "F.Fab")
			(effects
				(font
					(size 0.7 0.7)
					(thickness 0.15)
				)
				(justify left bottom)
			)
		)
		(fp_text user "${REFERENCE}"
			(at -1.45 4.783 90)
			(layer "F.Fab")
			(effects
				(font
					(size 0.7 0.7)
					(thickness 0.15)
				)
				(justify left bottom)
			)
		)
		(pad "1" smd rect
			(at -1.051 -0.65 180)
			(size 0.6 0.6)
			(layers "F.Cu" "F.Mask" "F.Paste")
			(net 183 "POWER")
			(pinfunction "G")
			(pintype "passive")
		)
		(pad "2" smd rect
			(at -1.051 0.65 180)
			(size 0.6 0.6)
			(layers "F.Cu" "F.Mask" "F.Paste")
			(net 1 "GND")
			(pinfunction "S")
			(pintype "passive")
		)
		(pad "3" smd rect
			(at 1.05 0 180)
			(size 0.6 0.6)
			(layers "F.Cu" "F.Mask" "F.Paste")
			(net 266 "Net-(Q1-D)")
			(pinfunction "D")
			(pintype "passive")
		)
	)
	(footprint "antmicro-footprints:TP_SMD_1mm"
		(layer "F.Cu")
		(at 244.124499 130.449)
		(property "Reference" "TP16"
			(at 0 -0.731898 0)
			(layer "F.SilkS")
			(hide yes)
			(effects
				(font
					(size 0.7 0.7)
					(thickness 0.15)
				)
				(justify left bottom)
			)
		)
		(property "Value" "TP_1mm_SMD"
			(at 0 1.4 0)
			(layer "F.Fab")
			(effects
				(font
					(size 0.7 0.7)
					(thickness 0.15)
				)
				(justify left bottom)
			)
		)
		(property "MPN" ""
			(at 0 0 0)
			(unlocked yes)
			(layer "F.Fab")
			(hide yes)
			(effects
				(font
					(size 1 1)
					(thickness 0.15)
				)
			)
		)
		(property "Manufacturer" ""
			(at 0 0 0)
			(unlocked yes)
			(layer "F.Fab")
			(hide yes)
			(effects
				(font
					(size 1 1)
					(thickness 0.15)
				)
			)
		)
		(property "Author" "Antmicro"
			(at 0 0 0)
			(unlocked yes)
			(layer "F.Fab")
			(hide yes)
			(effects
				(font
					(size 1 1)
					(thickness 0.15)
				)
			)
		)
		(property "License" "Apache-2.0"
			(at 0 0 0)
			(unlocked yes)
			(layer "F.Fab")
			(hide yes)
			(effects
				(font
					(size 1 1)
					(thickness 0.15)
				)
			)
		)
		(sheetname "/Supply/")
		(sheetfile "supply.kicad_sch")
		(attr exclude_from_pos_files)
		(fp_circle
			(center 0 0)
			(end 0.6 0)
			(stroke
				(width 0.05)
				(type default)
			)
			(fill no)
			(layer "F.CrtYd")
		)
		(fp_text user "License: Apache-2.0"
			(at -0.5 5.2 0)
			(layer "F.Fab")
			(effects
				(font
					(size 0.7 0.7)
					(thickness 0.15)
				)
				(justify left bottom)
			)
		)
		(fp_text user "${REFERENCE}"
			(at -0.5 2.8 0)
			(layer "F.Fab")
			(effects
				(font
					(size 0.7 0.7)
					(thickness 0.15)
				)
				(justify left bottom)
			)
		)
		(fp_text user "Author: Antmicro"
			(at -0.5 4 0)
			(layer "F.Fab")
			(effects
				(font
					(size 0.7 0.7)
					(thickness 0.15)
				)
				(justify left bottom)
			)
		)
		(pad "1" smd circle
			(at 0 0)
			(size 1 1)
			(layers "F.Cu" "F.Mask")
			(net 35 "VDC")
			(pinfunction "1")
			(pintype "passive")
		)
	)
	(footprint "antmicro-footprints:C_0402_1005Metric"
		(layer "F.Cu")
		(at 241.774499 155.3085 90)
		(descr "Capacitor SMD 0402")
		(tags "capacitor SMD 0402")
		(property "Reference" "C206"
			(at 1.1585 0.475501 90)
			(layer "F.SilkS")
			(effects
				(font
					(size 0.7 0.7)
					(thickness 0.15)
				)
				(justify left bottom)
			)
		)
		(property "Value" "C_100n_0402"
			(at -1.022927 2.155213 90)
			(layer "F.Fab")
			(effects
				(font
					(size 0.7 0.7)
					(thickness 0.15)
				)
				(justify left bottom)
			)
		)
		(property "Datasheet" "https://www.murata.com/products/productdetail?partno=GRM155R61H104KE14%23"
			(at 0 0 90)
			(layer "F.Fab")
			(hide yes)
			(effects
				(font
					(size 1.27 1.27)
					(thickness 0.15)
				)
			)
		)
		(property "Manufacturer" "Murata"
			(at 0 0 90)
			(unlocked yes)
			(layer "F.Fab")
			(hide yes)
			(effects
				(font
					(size 1 1)
					(thickness 0.15)
				)
			)
		)
		(property "MPN" "GRM155R61H104KE14D"
			(at 0 0 90)
			(unlocked yes)
			(layer "F.Fab")
			(hide yes)
			(effects
				(font
					(size 1 1)
					(thickness 0.15)
				)
			)
		)
		(property "Val" "100n"
			(at 0 0 90)
			(unlocked yes)
			(layer "F.Fab")
			(hide yes)
			(effects
				(font
					(size 1 1)
					(thickness 0.15)
				)
			)
		)
		(property "License" "Apache-2.0"
			(at 0 0 90)
			(unlocked yes)
			(layer "F.Fab")
			(hide yes)
			(effects
				(font
					(size 1 1)
					(thickness 0.15)
				)
			)
		)
		(property "Author" "Antmicro"
			(at 0 0 90)
			(unlocked yes)
			(layer "F.Fab")
			(hide yes)
			(effects
				(font
					(size 1 1)
					(thickness 0.15)
				)
			)
		)
		(property "Voltage" "50V"
			(at 0 0 90)
			(unlocked yes)
			(layer "F.Fab")
			(hide yes)
			(effects
				(font
					(size 1 1)
					(thickness 0.15)
				)
			)
		)
		(property "Dielectric" "X5R"
			(at 0 0 90)
			(unlocked yes)
			(layer "F.Fab")
			(hide yes)
			(effects
				(font
					(size 1 1)
					(thickness 0.15)
				)
			)
		)
		(sheetname "/Supply/DC-DC IO/")
		(sheetfile "dc-dc-io.kicad_sch")
		(attr smd)
		(fp_rect
			(start -0.925 -0.47)
			(end 0.925 0.47)
			(stroke
				(width 0.05)
				(type default)
			)
			(fill no)
			(layer "F.CrtYd")
		)
		(fp_line
			(start 0.504 -0.25)
			(end 0.504 0.248)
			(stroke
				(width 0.15)
				(type solid)
			)
			(layer "F.Fab")
		)
		(fp_line
			(start -0.494 -0.25)
			(end 0.504 -0.25)
			(stroke
				(width 0.15)
				(type solid)
			)
			(layer "F.Fab")
		)
		(fp_line
			(start 0.504 0.248)
			(end -0.494 0.248)
			(stroke
				(width 0.15)
				(type solid)
			)
			(layer "F.Fab")
		)
		(fp_line
			(start -0.494 0.248)
			(end -0.494 -0.25)
			(stroke
				(width 0.15)
				(type solid)
			)
			(layer "F.Fab")
		)
		(fp_text user "${REFERENCE}"
			(at -0.939 4.599 90)
			(layer "F.Fab")
			(effects
				(font
					(size 0.7 0.7)
					(thickness 0.15)
				)
				(justify left bottom)
			)
		)
		(fp_text user "License: Apache-2.0"
			(at -0.939 5.799 90)
			(layer "F.Fab")
			(effects
				(font
					(size 0.7 0.7)
					(thickness 0.15)
				)
				(justify left bottom)
			)
		)
		(fp_text user "Author: Antmicro"
			(at -0.939 3.399 90)
			(layer "F.Fab")
			(effects
				(font
					(size 0.7 0.7)
					(thickness 0.15)
				)
				(justify left bottom)
			)
		)
		(pad "1" smd roundrect
			(at -0.48 0 90)
			(size 0.59 0.64)
			(layers "F.Cu" "F.Mask" "F.Paste")
			(roundrect_rratio 0.25)
			(net 38 "+3V3_AON")
			(pintype "passive")
		)
		(pad "2" smd roundrect
			(at 0.48 0 90)
			(size 0.59 0.64)
			(layers "F.Cu" "F.Mask" "F.Paste")
			(roundrect_rratio 0.25)
			(net 1 "GND")
			(pintype "passive")
		)
	)
	(footprint "antmicro-footprints:C_Pol_EIA-D"
		(layer "F.Cu")
		(at 221.290002 160.4 90)
		(property "Reference" "C66"
			(at -6 2.434998 90)
			(layer "F.SilkS")
			(effects
				(font
					(size 0.7 0.7)
					(thickness 0.15)
				)
				(justify left bottom)
			)
		)
		(property "Value" "C_Pol_1m_2.5V_KEMET-T520-D"
			(at 0 3.4 90)
			(layer "F.Fab")
			(effects
				(font
					(size 0.7 0.7)
					(thickness 0.15)
				)
				(justify left bottom)
			)
		)
		(property "Datasheet" "https://www.kemet.com/en/us/capacitors/product/T520D108M2R5ATE030.html"
			(at 0 0 90)
			(layer "F.Fab")
			(hide yes)
			(effects
				(font
					(size 1.27 1.27)
					(thickness 0.15)
				)
			)
		)
		(property "MPN" "T520D108M2R5ATE030"
			(at 0 0 90)
			(unlocked yes)
			(layer "F.Fab")
			(hide yes)
			(effects
				(font
					(size 1 1)
					(thickness 0.15)
				)
			)
		)
		(property "Manufacturer" "KEMET"
			(at 0 0 90)
			(unlocked yes)
			(layer "F.Fab")
			(hide yes)
			(effects
				(font
					(size 1 1)
					(thickness 0.15)
				)
			)
		)
		(property "License" "Apache-2.0"
			(at 0 0 90)
			(unlocked yes)
			(layer "F.Fab")
			(hide yes)
			(effects
				(font
					(size 1 1)
					(thickness 0.15)
				)
			)
		)
		(property "Author" "Antmicro"
			(at 0 0 90)
			(unlocked yes)
			(layer "F.Fab")
			(hide yes)
			(effects
				(font
					(size 1 1)
					(thickness 0.15)
				)
			)
		)
		(property "Val" "1000u"
			(at 0 0 90)
			(unlocked yes)
			(layer "F.Fab")
			(hide yes)
			(effects
				(font
					(size 1 1)
					(thickness 0.15)
				)
			)
		)
		(property "Voltage" "2.5V"
			(at 0 0 90)
			(unlocked yes)
			(layer "F.Fab")
			(hide yes)
			(effects
				(font
					(size 1 1)
					(thickness 0.15)
				)
			)
		)
		(property "Dielectric" "template_dielectric"
			(at 0 0 90)
			(unlocked yes)
			(layer "F.Fab")
			(hide yes)
			(effects
				(font
					(size 1 1)
					(thickness 0.15)
				)
			)
		)
		(sheetname "/FPGA power/")
		(sheetfile "fpga-power.kicad_sch")
		(attr smd)
		(fp_line
			(start 3.6 -2.2)
			(end 3.6 -1.6)
			(stroke
				(width 0.15)
				(type solid)
			)
			(layer "F.SilkS")
		)
		(fp_line
			(start -3.58 -2.2)
			(end 3.6 -2.2)
			(stroke
				(width 0.15)
				(type solid)
			)
			(layer "F.SilkS")
		)
		(fp_line
			(start -4.1 -2.025)
			(end -4.1 -1.625)
			(stroke
				(width 0.12)
				(type solid)
			)
			(layer "F.SilkS")
		)
		(fp_line
			(start -4.3 -1.825)
			(end -3.9 -1.825)
			(stroke
				(width 0.12)
				(type solid)
			)
			(layer "F.SilkS")
		)
		(fp_line
			(start -3.58 -1.6)
			(end -3.58 -2.2)
			(stroke
				(width 0.15)
				(type solid)
			)
			(layer "F.SilkS")
		)
		(fp_line
			(start 3.6 1.6)
			(end 3.6 2.2)
			(stroke
				(width 0.15)
				(type solid)
			)
			(layer "F.SilkS")
		)
		(fp_line
			(start 3.6 2.2)
			(end -3.58 2.2)
			(stroke
				(width 0.15)
				(type solid)
			)
			(layer "F.SilkS")
		)
		(fp_line
			(start -3.58 2.2)
			(end -3.58 1.6)
			(stroke
				(width 0.15)
				(type solid)
			)
			(layer "F.SilkS")
		)
		(fp_line
			(start 3.77 -2.4)
			(end 3.77 -1.51)
			(stroke
				(width 0.05)
				(type solid)
			)
			(layer "F.CrtYd")
		)
		(fp_line
			(start -3.775 -2.4)
			(end 3.77 -2.4)
			(stroke
				(width 0.05)
				(type solid)
			)
			(layer "F.CrtYd")
		)
		(fp_line
			(start -3.775 -2.4)
			(end -3.775 -1.5)
			(stroke
				(width 0.05)
				(type solid)
			)
			(layer "F.CrtYd")
		)
		(fp_line
			(start 4.505 -1.51)
			(end 4.505 1.5)
			(stroke
				(width 0.05)
				(type solid)
			)
			(layer "F.CrtYd")
		)
		(fp_line
			(start 3.77 -1.51)
			(end 4.505 -1.51)
			(stroke
				(width 0.05)
				(type solid)
			)
			(layer "F.CrtYd")
		)
		(fp_line
			(start -3.775 -1.5)
			(end -4.505 -1.5)
			(stroke
				(width 0.05)
				(type solid)
			)
			(layer "F.CrtYd")
		)
		(fp_line
			(start 4.505 1.51)
			(end 3.77 1.51)
			(stroke
				(width 0.05)
				(type solid)
			)
			(layer "F.CrtYd")
		)
		(fp_line
			(start 3.77 1.51)
			(end 3.77 2.4)
			(stroke
				(width 0.05)
				(type solid)
			)
			(layer "F.CrtYd")
		)
		(fp_line
			(start -3.77 1.51)
			(end -4.505 1.51)
			(stroke
				(width 0.05)
				(type solid)
			)
			(layer "F.CrtYd")
		)
		(fp_line
			(start -4.505 1.51)
			(end -4.505 -1.5)
			(stroke
				(width 0.05)
				(type solid)
			)
			(layer "F.CrtYd")
		)
		(fp_line
			(start 3.77 2.4)
			(end -3.77 2.4)
			(stroke
				(width 0.05)
				(type solid)
			)
			(layer "F.CrtYd")
		)
		(fp_line
			(start -3.77 2.4)
			(end -3.77 1.51)
			(stroke
				(width 0.05)
				(type solid)
			)
			(layer "F.CrtYd")
		)
		(fp_rect
			(start -3.65 -2.15)
			(end 3.65 2.15)
			(stroke
				(width 0.15)
				(type solid)
			)
			(fill no)
			(layer "F.Fab")
		)
		(fp_text user "Author: Antmicro"
			(at -4.5 7.6 90)
			(layer "F.Fab")
			(effects
				(font
					(size 0.7 0.7)
					(thickness 0.15)
				)
				(justify left bottom)
			)
		)
		(fp_text user "License: Apache-2.0"
			(at -4.5 6.6 90)
			(layer "F.Fab")
			(effects
				(font
					(size 0.7 0.7)
					(thickness 0.15)
				)
				(justify left bottom)
			)
		)
		(fp_text user "${REFERENCE}"
			(at -4.5 5.6 90)
			(layer "F.Fab")
			(effects
				(font
					(size 0.7 0.7)
					(thickness 0.15)
				)
				(justify left bottom)
			)
		)
		(pad "1" smd roundrect
			(at -3.1 0 90)
			(size 2.31 2.52)
			(layers "F.Cu" "F.Mask" "F.Paste")
			(roundrect_rratio 0.1)
			(net 553 "+0V85")
			(pintype "passive")
		)
		(pad "2" smd roundrect
			(at 3.1 0 90)
			(size 2.31 2.52)
			(layers "F.Cu" "F.Mask" "F.Paste")
			(roundrect_rratio 0.1)
			(net 1 "GND")
			(pintype "passive")
		)
	)
	(footprint "antmicro-footprints:C_0603_1608Metric"
		(layer "F.Cu")
		(at 257.6055 167.5)
		(descr "Capacitor SMD 0603")
		(tags "capacitor 0603")
		(property "Reference" "C189"
			(at 1.2945 0.55 0)
			(layer "F.SilkS")
			(effects
				(font
					(size 0.7 0.7)
					(thickness 0.15)
				)
				(justify left bottom)
			)
		)
		(property "Value" "C_22u_0603"
			(at -1.42757 1.770288 0)
			(layer "F.Fab")
			(effects
				(font
					(size 0.7 0.7)
					(thickness 0.15)
				)
				(justify left bottom)
			)
		)
		(property "Datasheet" "https://www.murata.com/products/productdetail?partno=GRM188R60J226MEA0%23"
			(at 0 0 0)
			(layer "F.Fab")
			(hide yes)
			(effects
				(font
					(size 1.27 1.27)
					(thickness 0.15)
				)
			)
		)
		(property "Manufacturer" "Murata"
			(at 0 0 0)
			(unlocked yes)
			(layer "F.Fab")
			(hide yes)
			(effects
				(font
					(size 1 1)
					(thickness 0.15)
				)
			)
		)
		(property "MPN" "GRM188R60J226MEA0D"
			(at 0 0 0)
			(unlocked yes)
			(layer "F.Fab")
			(hide yes)
			(effects
				(font
					(size 1 1)
					(thickness 0.15)
				)
			)
		)
		(property "Val" "22u"
			(at 0 0 0)
			(unlocked yes)
			(layer "F.Fab")
			(hide yes)
			(effects
				(font
					(size 1 1)
					(thickness 0.15)
				)
			)
		)
		(property "License" "Apache-2.0"
			(at 0 0 0)
			(unlocked yes)
			(layer "F.Fab")
			(hide yes)
			(effects
				(font
					(size 1 1)
					(thickness 0.15)
				)
			)
		)
		(property "Author" "Antmicro"
			(at 0 0 0)
			(unlocked yes)
			(layer "F.Fab")
			(hide yes)
			(effects
				(font
					(size 1 1)
					(thickness 0.15)
				)
			)
		)
		(property "Voltage" ""
			(at 0 0 0)
			(unlocked yes)
			(layer "F.Fab")
			(hide yes)
			(effects
				(font
					(size 1 1)
					(thickness 0.15)
				)
			)
		)
		(property "Dielectric" ""
			(at 0 0 0)
			(unlocked yes)
			(layer "F.Fab")
			(hide yes)
			(effects
				(font
					(size 1 1)
					(thickness 0.15)
				)
			)
		)
		(sheetname "/Supply/DC-DC AUX, MGT/")
		(sheetfile "dc-dc-aux-mgt.kicad_sch")
		(attr smd)
		(fp_line
			(start -0.15 -0.4)
			(end 0.15 -0.4)
			(stroke
				(width 0.15)
				(type solid)
			)
			(layer "F.SilkS")
		)
		(fp_line
			(start -0.15 0.4)
			(end 0.15 0.4)
			(stroke
				(width 0.15)
				(type solid)
			)
			(layer "F.SilkS")
		)
		(fp_rect
			(start -1.25 -0.65)
			(end 1.25 0.65)
			(stroke
				(width 0.05)
				(type solid)
			)
			(fill no)
			(layer "F.CrtYd")
		)
		(fp_rect
			(start -0.8 -0.4)
			(end 0.8 0.4)
			(stroke
				(width 0.15)
				(type solid)
			)
			(fill no)
			(layer "F.Fab")
		)
		(fp_text user "License: Apache-2.0"
			(at -1.682 5.895 0)
			(layer "F.Fab")
			(effects
				(font
					(size 0.7 0.7)
					(thickness 0.15)
				)
				(justify left bottom)
			)
		)
		(fp_text user "Author: Antmicro"
			(at -1.682 4.894 0)
			(layer "F.Fab")
			(effects
				(font
					(size 0.7 0.7)
					(thickness 0.15)
				)
				(justify left bottom)
			)
		)
		(fp_text user "${REFERENCE}"
			(at -1.682 3.895 0)
			(layer "F.Fab")
			(effects
				(font
					(size 0.7 0.7)
					(thickness 0.15)
				)
				(justify left bottom)
			)
		)
		(pad "1" smd roundrect
			(at -0.7 0)
			(size 0.8 1)
			(layers "F.Cu" "F.Mask" "F.Paste")
			(roundrect_rratio 0.2)
			(net 1 "GND")
			(pintype "passive")
		)
		(pad "2" smd roundrect
			(at 0.7 0)
			(size 0.8 1)
			(layers "F.Cu" "F.Mask" "F.Paste")
			(roundrect_rratio 0.2)
			(net 47 "/Supply/DC-DC AUX, MGT/MGTAVCC_local")
			(pintype "passive")
		)
	)
	(footprint "antmicro-footprints:LED_0603_1608Metric_G"
		(layer "F.Cu")
		(at 141.024499 185.549 90)
		(descr "LED SMD 0603 Green")
		(tags "LED SMD 0603 Green")
		(property "Reference" "D13"
			(at -0.001 -0.901 90)
			(layer "F.SilkS")
			(hide yes)
			(effects
				(font
					(size 0.7 0.7)
					(thickness 0.15)
				)
				(justify left bottom)
			)
		)
		(property "Value" "LED_G_0603_KP-1608CGCK"
			(at -0.001 1.599 90)
			(layer "F.Fab")
			(effects
				(font
					(size 0.7 0.7)
					(thickness 0.15)
				)
				(justify left bottom)
			)
		)
		(property "Datasheet" "http://www.kingbright.com/attachments/file/psearch//000/00/00/KP-1608CGCK(Ver.23B).pdf"
			(at 0 0 90)
			(layer "F.Fab")
			(hide yes)
			(effects
				(font
					(size 1.27 1.27)
					(thickness 0.15)
				)
			)
		)
		(property "MPN" "KP-1608CGCK"
			(at 0 0 90)
			(unlocked yes)
			(layer "F.Fab")
			(hide yes)
			(effects
				(font
					(size 1 1)
					(thickness 0.15)
				)
			)
		)
		(property "Manufacturer" "Kingbright"
			(at 0 0 90)
			(unlocked yes)
			(layer "F.Fab")
			(hide yes)
			(effects
				(font
					(size 1 1)
					(thickness 0.15)
				)
			)
		)
		(property "Color" "Green"
			(at 0 0 90)
			(unlocked yes)
			(layer "F.Fab")
			(hide yes)
			(effects
				(font
					(size 1 1)
					(thickness 0.15)
				)
			)
		)
		(property "Author" "Antmicro"
			(at 0 0 90)
			(unlocked yes)
			(layer "F.Fab")
			(hide yes)
			(effects
				(font
					(size 1 1)
					(thickness 0.15)
				)
			)
		)
		(property "License" "Apache-2.0"
			(at 0 0 90)
			(unlocked yes)
			(layer "F.Fab")
			(hide yes)
			(effects
				(font
					(size 1 1)
					(thickness 0.15)
				)
			)
		)
		(sheetname "/Debug FTDI + VNA/")
		(sheetfile "debug-ftdi.kicad_sch")
		(attr smd)
		(fp_line
			(start 0.22 -0.35)
			(end -0.22 -0.35)
			(stroke
				(width 0.15)
				(type solid)
			)
			(layer "F.SilkS")
		)
		(fp_line
			(start -1.18 -0.319)
			(end -1.18 0.321)
			(stroke
				(width 0.15)
				(type solid)
			)
			(layer "F.SilkS")
		)
		(fp_line
			(start 0.105328 0.001008)
			(end 0.24 0.001)
			(stroke
				(width 0.1)
				(type solid)
			)
			(layer "F.SilkS")
		)
		(fp_line
			(start -0.094672 0.001008)
			(end 0.105328 -0.198992)
			(stroke
				(width 0.1)
				(type solid)
			)
			(layer "F.SilkS")
		)
		(fp_line
			(start -0.094672 0.001008)
			(end -0.24 0.001008)
			(stroke
				(width 0.1)
				(type solid)
			)
			(layer "F.SilkS")
		)
		(fp_line
			(start 0.105328 0.201008)
			(end 0.105328 -0.198992)
			(stroke
				(width 0.1)
				(type solid)
			)
			(layer "F.SilkS")
		)
		(fp_line
			(start 0.105328 0.201008)
			(end -0.094672 0.001008)
			(stroke
				(width 0.1)
				(type solid)
			)
			(layer "F.SilkS")
		)
		(fp_line
			(start -0.094672 0.201008)
			(end -0.094672 -0.198992)
			(stroke
				(width 0.1)
				(type solid)
			)
			(layer "F.SilkS")
		)
		(fp_line
			(start 0.22 0.35)
			(end -0.22 0.35)
			(stroke
				(width 0.15)
				(type solid)
			)
			(layer "F.SilkS")
		)
		(fp_rect
			(start 1.25 0.65)
			(end -1.25 -0.65)
			(stroke
				(width 0.05)
				(type solid)
			)
			(fill no)
			(layer "F.CrtYd")
		)
		(fp_line
			(start 0.201 -0.202)
			(end -0.101 0)
			(stroke
				(width 0.15)
				(type solid)
			)
			(layer "F.Fab")
		)
		(fp_line
			(start -0.199 -0.202)
			(end -0.199 0.1)
			(stroke
				(width 0.15)
				(type solid)
			)
			(layer "F.Fab")
		)
		(fp_line
			(start 0.599 0)
			(end 0.201 0)
			(stroke
				(width 0.15)
				(type solid)
			)
			(layer "F.Fab")
		)
		(fp_line
			(start 0.201 0)
			(end 0.201 -0.202)
			(stroke
				(width 0.15)
				(type solid)
			)
			(layer "F.Fab")
		)
		(fp_line
			(start -0.101 0)
			(end 0.201 0.2)
			(stroke
				(width 0.15)
				(type solid)
			)
			(layer "F.Fab")
		)
		(fp_line
			(start -0.199 0)
			(end -0.597 0)
			(stroke
				(width 0.15)
				(type solid)
			)
			(layer "F.Fab")
		)
		(fp_line
			(start 0.201 0.2)
			(end 0.201 0)
			(stroke
				(width 0.15)
				(type solid)
			)
			(layer "F.Fab")
		)
		(fp_line
			(start -0.199 0.2)
			(end -0.199 0.1)
			(stroke
				(width 0.15)
				(type solid)
			)
			(layer "F.Fab")
		)
		(fp_rect
			(start 0.848 0.4)
			(end -0.85 -0.402)
			(stroke
				(width 0.15)
				(type solid)
			)
			(fill no)
			(layer "F.Fab")
		)
		(fp_text user "Author: Antmicro"
			(at -1.4224 4.799 90)
			(layer "F.Fab")
			(effects
				(font
					(size 0.7 0.7)
					(thickness 0.15)
				)
				(justify left bottom)
			)
		)
		(fp_text user "License: Apache-2.0"
			(at -1.4224 3.599 90)
			(layer "F.Fab")
			(effects
				(font
					(size 0.7 0.7)
					(thickness 0.15)
				)
				(justify left bottom)
			)
		)
		(fp_text user "${REFERENCE}"
			(at -1.4224 5.999 90)
			(layer "F.Fab")
			(effects
				(font
					(size 0.7 0.7)
					(thickness 0.15)
				)
				(justify left bottom)
			)
		)
		(pad "1" smd roundrect
			(at -0.7 0 270)
			(size 0.8 1)
			(layers "F.Cu" "F.Mask" "F.Paste")
			(roundrect_rratio 0.2)
			(net 1 "GND")
			(pinfunction "C")
			(pintype "passive")
		)
		(pad "2" smd roundrect
			(at 0.7 0 270)
			(size 0.8 1)
			(layers "F.Cu" "F.Mask" "F.Paste")
			(roundrect_rratio 0.2)
			(net 43 "Net-(D13-A)")
			(pinfunction "A")
			(pintype "passive")
		)
	)
	(footprint "antmicro-footprints:C_0603_1608Metric"
		(layer "F.Cu")
		(at 250.35 173.972 -90)
		(descr "Capacitor SMD 0603")
		(tags "capacitor 0603")
		(property "Reference" "C183"
			(at 1.328 -0.3 90)
			(layer "F.SilkS")
			(effects
				(font
					(size 0.7 0.7)
					(thickness 0.15)
				)
				(justify right bottom)
			)
		)
		(property "Value" "C_22u_0603"
			(at -1.42757 1.770288 90)
			(layer "F.Fab")
			(effects
				(font
					(size 0.7 0.7)
					(thickness 0.15)
				)
				(justify right bottom)
			)
		)
		(property "Datasheet" "https://www.murata.com/products/productdetail?partno=GRM188R60J226MEA0%23"
			(at 0 0 270)
			(layer "F.Fab")
			(hide yes)
			(effects
				(font
					(size 1.27 1.27)
					(thickness 0.15)
				)
			)
		)
		(property "Manufacturer" "Murata"
			(at 0 0 270)
			(unlocked yes)
			(layer "F.Fab")
			(hide yes)
			(effects
				(font
					(size 1 1)
					(thickness 0.15)
				)
			)
		)
		(property "MPN" "GRM188R60J226MEA0D"
			(at 0 0 270)
			(unlocked yes)
			(layer "F.Fab")
			(hide yes)
			(effects
				(font
					(size 1 1)
					(thickness 0.15)
				)
			)
		)
		(property "Val" "22u"
			(at 0 0 270)
			(unlocked yes)
			(layer "F.Fab")
			(hide yes)
			(effects
				(font
					(size 1 1)
					(thickness 0.15)
				)
			)
		)
		(property "License" "Apache-2.0"
			(at 0 0 270)
			(unlocked yes)
			(layer "F.Fab")
			(hide yes)
			(effects
				(font
					(size 1 1)
					(thickness 0.15)
				)
			)
		)
		(property "Author" "Antmicro"
			(at 0 0 270)
			(unlocked yes)
			(layer "F.Fab")
			(hide yes)
			(effects
				(font
					(size 1 1)
					(thickness 0.15)
				)
			)
		)
		(property "Voltage" ""
			(at 0 0 270)
			(unlocked yes)
			(layer "F.Fab")
			(hide yes)
			(effects
				(font
					(size 1 1)
					(thickness 0.15)
				)
			)
		)
		(property "Dielectric" ""
			(at 0 0 270)
			(unlocked yes)
			(layer "F.Fab")
			(hide yes)
			(effects
				(font
					(size 1 1)
					(thickness 0.15)
				)
			)
		)
		(sheetname "/Supply/DC-DC AUX, MGT/")
		(sheetfile "dc-dc-aux-mgt.kicad_sch")
		(attr smd)
		(fp_line
			(start -0.15 0.4)
			(end 0.15 0.4)
			(stroke
				(width 0.15)
				(type solid)
			)
			(layer "F.SilkS")
		)
		(fp_line
			(start -0.15 -0.4)
			(end 0.15 -0.4)
			(stroke
				(width 0.15)
				(type solid)
			)
			(layer "F.SilkS")
		)
		(fp_rect
			(start -1.25 -0.65)
			(end 1.25 0.65)
			(stroke
				(width 0.05)
				(type solid)
			)
			(fill no)
			(layer "F.CrtYd")
		)
		(fp_rect
			(start -0.8 -0.4)
			(end 0.8 0.4)
			(stroke
				(width 0.15)
				(type solid)
			)
			(fill no)
			(layer "F.Fab")
		)
		(fp_text user "License: Apache-2.0"
			(at -1.682 5.895 270)
			(layer "F.Fab")
			(effects
				(font
					(size 0.7 0.7)
					(thickness 0.15)
				)
				(justify left bottom)
			)
		)
		(fp_text user "Author: Antmicro"
			(at -1.682 4.894 270)
			(layer "F.Fab")
			(effects
				(font
					(size 0.7 0.7)
					(thickness 0.15)
				)
				(justify left bottom)
			)
		)
		(fp_text user "${REFERENCE}"
			(at -1.682 3.895 270)
			(layer "F.Fab")
			(effects
				(font
					(size 0.7 0.7)
					(thickness 0.15)
				)
				(justify left bottom)
			)
		)
		(pad "1" smd roundrect
			(at -0.7 0 270)
			(size 0.8 1)
			(layers "F.Cu" "F.Mask" "F.Paste")
			(roundrect_rratio 0.2)
			(net 1 "GND")
			(pintype "passive")
		)
		(pad "2" smd roundrect
			(at 0.7 0 270)
			(size 0.8 1)
			(layers "F.Cu" "F.Mask" "F.Paste")
			(roundrect_rratio 0.2)
			(net 37 "/Supply/DC-DC AUX, MGT/1V8_local")
			(pintype "passive")
		)
	)
	(footprint "antmicro-footprints:R_0402_1005Metric"
		(layer "F.Cu")
		(at 119.15 153.61 180)
		(descr "Resistor SMD 0402")
		(tags "resistor SMD 0402")
		(property "Reference" "R32"
			(at -5.11 -0.38 0)
			(layer "F.SilkS")
			(effects
				(font
					(size 0.7 0.7)
					(thickness 0.15)
				)
				(justify right bottom)
			)
		)
		(property "Value" "R_49k9_0402"
			(at -1.011843 1.772047 0)
			(layer "F.Fab")
			(effects
				(font
					(size 0.7 0.7)
					(thickness 0.15)
				)
				(justify right bottom)
			)
		)
		(property "Datasheet" "https://www.bourns.com/docs/product-datasheets/cr.pdf"
			(at 0 0 180)
			(layer "F.Fab")
			(hide yes)
			(effects
				(font
					(size 1.27 1.27)
					(thickness 0.15)
				)
			)
		)
		(property "MPN" "CR0402-FX-4992GLF"
			(at 0 0 180)
			(unlocked yes)
			(layer "F.Fab")
			(hide yes)
			(effects
				(font
					(size 1 1)
					(thickness 0.15)
				)
			)
		)
		(property "Manufacturer" "Bourns"
			(at 0 0 180)
			(unlocked yes)
			(layer "F.Fab")
			(hide yes)
			(effects
				(font
					(size 1 1)
					(thickness 0.15)
				)
			)
		)
		(property "License" "Apache-2.0"
			(at 0 0 180)
			(unlocked yes)
			(layer "F.Fab")
			(hide yes)
			(effects
				(font
					(size 1 1)
					(thickness 0.15)
				)
			)
		)
		(property "Author" "Antmicro"
			(at 0 0 180)
			(unlocked yes)
			(layer "F.Fab")
			(hide yes)
			(effects
				(font
					(size 1 1)
					(thickness 0.15)
				)
			)
		)
		(property "Val" "49k9"
			(at 0 0 180)
			(unlocked yes)
			(layer "F.Fab")
			(hide yes)
			(effects
				(font
					(size 1 1)
					(thickness 0.15)
				)
			)
		)
		(property "Tolerance" "1%"
			(at 0 0 180)
			(unlocked yes)
			(layer "F.Fab")
			(hide yes)
			(effects
				(font
					(size 1 1)
					(thickness 0.15)
				)
			)
		)
		(sheetname "/HDMI + SD Card/")
		(sheetfile "hdmi-sd-card.kicad_sch")
		(attr smd)
		(fp_rect
			(start -0.925 -0.47)
			(end 0.925 0.47)
			(stroke
				(width 0.05)
				(type default)
			)
			(fill no)
			(layer "F.CrtYd")
		)
		(fp_rect
			(start -0.5 -0.25)
			(end 0.5 0.25)
			(stroke
				(width 0.15)
				(type solid)
			)
			(fill no)
			(layer "F.Fab")
		)
		(fp_text user "${REFERENCE}"
			(at -0.95 3.168 180)
			(layer "F.Fab")
			(effects
				(font
					(size 0.7 0.7)
					(thickness 0.15)
				)
				(justify left bottom)
			)
		)
		(fp_text user "License: Apache-2.0"
			(at -0.95 5.169 180)
			(layer "F.Fab")
			(effects
				(font
					(size 0.7 0.7)
					(thickness 0.15)
				)
				(justify left bottom)
			)
		)
		(fp_text user "Author: Antmicro"
			(at -0.95 4.169 180)
			(layer "F.Fab")
			(effects
				(font
					(size 0.7 0.7)
					(thickness 0.15)
				)
				(justify left bottom)
			)
		)
		(pad "1" smd roundrect
			(at -0.48 0 180)
			(size 0.59 0.64)
			(layers "F.Cu" "F.Mask" "F.Paste")
			(roundrect_rratio 0.25)
			(net 678 "Net-(L8-Pad2)")
			(pintype "passive")
		)
		(pad "2" smd roundrect
			(at 0.48 0 180)
			(size 0.59 0.64)
			(layers "F.Cu" "F.Mask" "F.Paste")
			(roundrect_rratio 0.25)
			(net 322 "Net-(C300-Pad2)")
			(pintype "passive")
		)
	)
	(footprint "antmicro-footprints:C_0402_1005Metric"
		(layer "F.Cu")
		(at 136.124499 178.449 90)
		(descr "Capacitor SMD 0402")
		(tags "capacitor SMD 0402")
		(property "Reference" "C128"
			(at -1.051 -0.674499 90)
			(layer "F.SilkS")
			(effects
				(font
					(size 0.7 0.7)
					(thickness 0.15)
				)
				(justify left bottom)
			)
		)
		(property "Value" "C_100n_0402"
			(at -1.022927 2.155213 90)
			(layer "F.Fab")
			(effects
				(font
					(size 0.7 0.7)
					(thickness 0.15)
				)
				(justify left bottom)
			)
		)
		(property "Datasheet" "https://www.murata.com/products/productdetail?partno=GRM155R61H104KE14%23"
			(at 0 0 90)
			(layer "F.Fab")
			(hide yes)
			(effects
				(font
					(size 1.27 1.27)
					(thickness 0.15)
				)
			)
		)
		(property "MPN" "GRM155R61H104KE14D"
			(at 0 0 90)
			(unlocked yes)
			(layer "F.Fab")
			(hide yes)
			(effects
				(font
					(size 1 1)
					(thickness 0.15)
				)
			)
		)
		(property "Manufacturer" "Murata"
			(at 0 0 90)
			(unlocked yes)
			(layer "F.Fab")
			(hide yes)
			(effects
				(font
					(size 1 1)
					(thickness 0.15)
				)
			)
		)
		(property "License" "Apache-2.0"
			(at 0 0 90)
			(unlocked yes)
			(layer "F.Fab")
			(hide yes)
			(effects
				(font
					(size 1 1)
					(thickness 0.15)
				)
			)
		)
		(property "Author" "Antmicro"
			(at 0 0 90)
			(unlocked yes)
			(layer "F.Fab")
			(hide yes)
			(effects
				(font
					(size 1 1)
					(thickness 0.15)
				)
			)
		)
		(property "Val" "100n"
			(at 0 0 90)
			(unlocked yes)
			(layer "F.Fab")
			(hide yes)
			(effects
				(font
					(size 1 1)
					(thickness 0.15)
				)
			)
		)
		(property "Voltage" "50V"
			(at 0 0 90)
			(unlocked yes)
			(layer "F.Fab")
			(hide yes)
			(effects
				(font
					(size 1 1)
					(thickness 0.15)
				)
			)
		)
		(property "Dielectric" "X5R"
			(at 0 0 90)
			(unlocked yes)
			(layer "F.Fab")
			(hide yes)
			(effects
				(font
					(size 1 1)
					(thickness 0.15)
				)
			)
		)
		(sheetname "/Debug FTDI + VNA/")
		(sheetfile "debug-ftdi.kicad_sch")
		(attr smd)
		(fp_rect
			(start -0.925 -0.47)
			(end 0.925 0.47)
			(stroke
				(width 0.05)
				(type default)
			)
			(fill no)
			(layer "F.CrtYd")
		)
		(fp_line
			(start 0.504 -0.25)
			(end 0.504 0.248)
			(stroke
				(width 0.15)
				(type solid)
			)
			(layer "F.Fab")
		)
		(fp_line
			(start -0.494 -0.25)
			(end 0.504 -0.25)
			(stroke
				(width 0.15)
				(type solid)
			)
			(layer "F.Fab")
		)
		(fp_line
			(start 0.504 0.248)
			(end -0.494 0.248)
			(stroke
				(width 0.15)
				(type solid)
			)
			(layer "F.Fab")
		)
		(fp_line
			(start -0.494 0.248)
			(end -0.494 -0.25)
			(stroke
				(width 0.15)
				(type solid)
			)
			(layer "F.Fab")
		)
		(fp_text user "License: Apache-2.0"
			(at -0.939 5.799 90)
			(layer "F.Fab")
			(effects
				(font
					(size 0.7 0.7)
					(thickness 0.15)
				)
				(justify left bottom)
			)
		)
		(fp_text user "Author: Antmicro"
			(at -0.939 3.399 90)
			(layer "F.Fab")
			(effects
				(font
					(size 0.7 0.7)
					(thickness 0.15)
				)
				(justify left bottom)
			)
		)
		(fp_text user "${REFERENCE}"
			(at -0.939 4.599 90)
			(layer "F.Fab")
			(effects
				(font
					(size 0.7 0.7)
					(thickness 0.15)
				)
				(justify left bottom)
			)
		)
		(pad "1" smd roundrect
			(at -0.48 0 90)
			(size 0.59 0.64)
			(layers "F.Cu" "F.Mask" "F.Paste")
			(roundrect_rratio 0.25)
			(net 1 "GND")
			(pintype "passive")
		)
		(pad "2" smd roundrect
			(at 0.48 0 90)
			(size 0.59 0.64)
			(layers "F.Cu" "F.Mask" "F.Paste")
			(roundrect_rratio 0.25)
			(net 6 "/Debug FTDI + VNA/FTDI_3V3")
			(pintype "passive")
		)
	)
	(footprint "antmicro-footprints:C_0603_1608Metric"
		(layer "F.Cu")
		(at 257.149499 150.171)
		(descr "Capacitor SMD 0603")
		(tags "capacitor 0603")
		(property "Reference" "C192"
			(at 1.200501 0.529 0)
			(layer "F.SilkS")
			(effects
				(font
					(size 0.7 0.7)
					(thickness 0.15)
				)
				(justify left bottom)
			)
		)
		(property "Value" "C_22u_0603"
			(at -1.42757 1.770288 0)
			(layer "F.Fab")
			(effects
				(font
					(size 0.7 0.7)
					(thickness 0.15)
				)
				(justify left bottom)
			)
		)
		(property "Datasheet" "https://www.murata.com/products/productdetail?partno=GRM188R60J226MEA0%23"
			(at 0 0 0)
			(layer "F.Fab")
			(hide yes)
			(effects
				(font
					(size 1.27 1.27)
					(thickness 0.15)
				)
			)
		)
		(property "Manufacturer" "Murata"
			(at 0 0 0)
			(unlocked yes)
			(layer "F.Fab")
			(hide yes)
			(effects
				(font
					(size 1 1)
					(thickness 0.15)
				)
			)
		)
		(property "MPN" "GRM188R60J226MEA0D"
			(at 0 0 0)
			(unlocked yes)
			(layer "F.Fab")
			(hide yes)
			(effects
				(font
					(size 1 1)
					(thickness 0.15)
				)
			)
		)
		(property "Val" "22u"
			(at 0 0 0)
			(unlocked yes)
			(layer "F.Fab")
			(hide yes)
			(effects
				(font
					(size 1 1)
					(thickness 0.15)
				)
			)
		)
		(property "License" "Apache-2.0"
			(at 0 0 0)
			(unlocked yes)
			(layer "F.Fab")
			(hide yes)
			(effects
				(font
					(size 1 1)
					(thickness 0.15)
				)
			)
		)
		(property "Author" "Antmicro"
			(at 0 0 0)
			(unlocked yes)
			(layer "F.Fab")
			(hide yes)
			(effects
				(font
					(size 1 1)
					(thickness 0.15)
				)
			)
		)
		(property "Voltage" ""
			(at 0 0 0)
			(unlocked yes)
			(layer "F.Fab")
			(hide yes)
			(effects
				(font
					(size 1 1)
					(thickness 0.15)
				)
			)
		)
		(property "Dielectric" ""
			(at 0 0 0)
			(unlocked yes)
			(layer "F.Fab")
			(hide yes)
			(effects
				(font
					(size 1 1)
					(thickness 0.15)
				)
			)
		)
		(sheetname "/Supply/DC-DC IO/")
		(sheetfile "dc-dc-io.kicad_sch")
		(attr smd)
		(fp_line
			(start -0.15 -0.4)
			(end 0.15 -0.4)
			(stroke
				(width 0.15)
				(type solid)
			)
			(layer "F.SilkS")
		)
		(fp_line
			(start -0.15 0.4)
			(end 0.15 0.4)
			(stroke
				(width 0.15)
				(type solid)
			)
			(layer "F.SilkS")
		)
		(fp_rect
			(start -1.25 -0.65)
			(end 1.25 0.65)
			(stroke
				(width 0.05)
				(type solid)
			)
			(fill no)
			(layer "F.CrtYd")
		)
		(fp_rect
			(start -0.8 -0.4)
			(end 0.8 0.4)
			(stroke
				(width 0.15)
				(type solid)
			)
			(fill no)
			(layer "F.Fab")
		)
		(fp_text user "${REFERENCE}"
			(at -1.682 3.895 0)
			(layer "F.Fab")
			(effects
				(font
					(size 0.7 0.7)
					(thickness 0.15)
				)
				(justify left bottom)
			)
		)
		(fp_text user "License: Apache-2.0"
			(at -1.682 5.895 0)
			(layer "F.Fab")
			(effects
				(font
					(size 0.7 0.7)
					(thickness 0.15)
				)
				(justify left bottom)
			)
		)
		(fp_text user "Author: Antmicro"
			(at -1.682 4.894 0)
			(layer "F.Fab")
			(effects
				(font
					(size 0.7 0.7)
					(thickness 0.15)
				)
				(justify left bottom)
			)
		)
		(pad "1" smd roundrect
			(at -0.7 0)
			(size 0.8 1)
			(layers "F.Cu" "F.Mask" "F.Paste")
			(roundrect_rratio 0.2)
			(net 1 "GND")
			(pintype "passive")
		)
		(pad "2" smd roundrect
			(at 0.7 0)
			(size 0.8 1)
			(layers "F.Cu" "F.Mask" "F.Paste")
			(roundrect_rratio 0.2)
			(net 158 "/Supply/DC-DC IO/VDDQ_local")
			(pintype "passive")
		)
	)
	(footprint "antmicro-footprints:USON-10_2.5x1mm_P0.5mm"
		(layer "F.Cu")
		(at 113.530499 179.5525 180)
		(descr "USON-10 2.5x1mm_ Pitch 0.5mm")
		(tags "USON-10 2.5x1mm Pitch 0.5mm")
		(property "Reference" "U11"
			(at -1.819501 0.7025 90)
			(layer "F.SilkS")
			(effects
				(font
					(size 0.7 0.7)
					(thickness 0.15)
				)
				(justify right bottom)
			)
		)
		(property "Value" "TPD4E05U06QDQARQ1"
			(at 0.018 2.499 0)
			(layer "F.Fab")
			(effects
				(font
					(size 0.7 0.7)
					(thickness 0.15)
				)
				(justify right bottom)
			)
		)
		(property "Datasheet" "https://www.ti.com/lit/ds/symlink/tpd4e05u06-q1.pdf?HQS=dis-mous-null-mousermode-dsf-pf-null-wwe&ts=1663591265741&ref_url=https%253A%252F%252Fwww.mouser.com%252F"
			(at 0 0 180)
			(layer "F.Fab")
			(hide yes)
			(effects
				(font
					(size 1.27 1.27)
					(thickness 0.15)
				)
			)
		)
		(property "Manufacturer" "Texas Instruments"
			(at 0 0 180)
			(unlocked yes)
			(layer "F.Fab")
			(hide yes)
			(effects
				(font
					(size 1 1)
					(thickness 0.15)
				)
			)
		)
		(property "MPN" "TPD4E05U06QDQARQ1"
			(at 0 0 180)
			(unlocked yes)
			(layer "F.Fab")
			(hide yes)
			(effects
				(font
					(size 1 1)
					(thickness 0.15)
				)
			)
		)
		(property "Author" "Antmicro"
			(at 0 0 180)
			(unlocked yes)
			(layer "F.Fab")
			(hide yes)
			(effects
				(font
					(size 1 1)
					(thickness 0.15)
				)
			)
		)
		(property "License" "Apache-2.0"
			(at 0 0 180)
			(unlocked yes)
			(layer "F.Fab")
			(hide yes)
			(effects
				(font
					(size 1 1)
					(thickness 0.15)
				)
			)
		)
		(sheetname "/HDMI + SD Card/")
		(sheetfile "hdmi-sd-card.kicad_sch")
		(attr smd)
		(fp_line
			(start 0.498 1.398)
			(end -0.5 1.398)
			(stroke
				(width 0.15)
				(type solid)
			)
			(layer "F.SilkS")
		)
		(fp_line
			(start 0.498 -1.401)
			(end -0.5 -1.401)
			(stroke
				(width 0.15)
				(type solid)
			)
			(layer "F.SilkS")
		)
		(fp_circle
			(center -0.68 -1.27)
			(end -0.63 -1.27)
			(stroke
				(width 0.15)
				(type solid)
			)
			(fill yes)
			(layer "F.SilkS")
		)
		(fp_rect
			(start -0.8 -1.5)
			(end 0.8 1.499)
			(stroke
				(width 0.05)
				(type solid)
			)
			(fill no)
			(layer "F.CrtYd")
		)
		(fp_line
			(start 0.498 -1.25)
			(end 0.498 1.249)
			(stroke
				(width 0.15)
				(type solid)
			)
			(layer "F.Fab")
		)
		(fp_line
			(start 0.498 -1.25)
			(end -0.25 -1.25)
			(stroke
				(width 0.15)
				(type solid)
			)
			(layer "F.Fab")
		)
		(fp_line
			(start -0.25 -1.25)
			(end -0.5 -1)
			(stroke
				(width 0.15)
				(type solid)
			)
			(layer "F.Fab")
		)
		(fp_line
			(start -0.5 1.249)
			(end 0.498 1.249)
			(stroke
				(width 0.15)
				(type solid)
			)
			(layer "F.Fab")
		)
		(fp_line
			(start -0.5 -1)
			(end -0.5 1.249)
			(stroke
				(width 0.15)
				(type solid)
			)
			(layer "F.Fab")
		)
		(fp_text user "License: Apache-2.0"
			(at -0.802 6.9 180)
			(layer "F.Fab")
			(effects
				(font
					(size 0.7 0.7)
					(thickness 0.15)
				)
				(justify left bottom)
			)
		)
		(fp_text user "Author: Antmicro"
			(at -0.802 5.7 180)
			(layer "F.Fab")
			(effects
				(font
					(size 0.7 0.7)
					(thickness 0.15)
				)
				(justify left bottom)
			)
		)
		(fp_text user "${REFERENCE}"
			(at -0.802 4.498 180)
			(layer "F.Fab")
			(effects
				(font
					(size 0.7 0.7)
					(thickness 0.15)
				)
				(justify left bottom)
			)
		)
		(pad "1" smd roundrect
			(at -0.387 -1 90)
			(size 0.25 0.55)
			(layers "F.Cu" "F.Mask" "F.Paste")
			(roundrect_rratio 0.25)
			(net 658 "/HDMI + SD Card/HDMI_OUT_CONN_D0_P")
			(pintype "passive")
		)
		(pad "2" smd roundrect
			(at -0.387 -0.5 90)
			(size 0.25 0.55)
			(layers "F.Cu" "F.Mask" "F.Paste")
			(roundrect_rratio 0.25)
			(net 659 "/HDMI + SD Card/HDMI_OUT_CONN_D0_N")
			(pintype "passive")
		)
		(pad "3" smd roundrect
			(at -0.387 0 90)
			(size 0.4 0.55)
			(layers "F.Cu" "F.Mask" "F.Paste")
			(roundrect_rratio 0.25)
			(net 1 "GND")
			(pintype "power_in")
		)
		(pad "4" smd roundrect
			(at -0.387 0.498 90)
			(size 0.25 0.55)
			(layers "F.Cu" "F.Mask" "F.Paste")
			(roundrect_rratio 0.25)
			(net 660 "/HDMI + SD Card/HDMI_OUT_CONN_CLK_P")
			(pintype "passive")
		)
		(pad "5" smd roundrect
			(at -0.387 0.998 90)
			(size 0.25 0.55)
			(layers "F.Cu" "F.Mask" "F.Paste")
			(roundrect_rratio 0.25)
			(net 661 "/HDMI + SD Card/HDMI_OUT_CONN_CLK_N")
			(pintype "passive")
		)
		(pad "6" smd roundrect
			(at 0.385 0.998 90)
			(size 0.25 0.55)
			(layers "F.Cu" "F.Mask" "F.Paste")
			(roundrect_rratio 0.25)
			(net 661 "/HDMI + SD Card/HDMI_OUT_CONN_CLK_N")
			(pintype "passive")
		)
		(pad "7" smd roundrect
			(at 0.385 0.498 90)
			(size 0.25 0.55)
			(layers "F.Cu" "F.Mask" "F.Paste")
			(roundrect_rratio 0.25)
			(net 660 "/HDMI + SD Card/HDMI_OUT_CONN_CLK_P")
			(pintype "passive")
		)
		(pad "8" smd roundrect
			(at 0.385 0 90)
			(size 0.4 0.55)
			(layers "F.Cu" "F.Mask" "F.Paste")
			(roundrect_rratio 0.25)
			(net 1 "GND")
			(pintype "passive")
		)
		(pad "9" smd roundrect
			(at 0.385 -0.5 90)
			(size 0.25 0.55)
			(layers "F.Cu" "F.Mask" "F.Paste")
			(roundrect_rratio 0.25)
			(net 659 "/HDMI + SD Card/HDMI_OUT_CONN_D0_N")
			(pintype "passive")
		)
		(pad "10" smd roundrect
			(at 0.385 -1 90)
			(size 0.25 0.55)
			(layers "F.Cu" "F.Mask" "F.Paste")
			(roundrect_rratio 0.25)
			(net 658 "/HDMI + SD Card/HDMI_OUT_CONN_D0_P")
			(pintype "passive")
		)
	)
	(footprint "antmicro-footprints:SC70-3"
		(layer "F.Cu")
		(at 250.274499 146)
		(property "Reference" "Q9"
			(at 0.375501 0.75 90)
			(layer "F.SilkS")
			(effects
				(font
					(size 0.7 0.7)
					(thickness 0.15)
				)
				(justify left bottom)
			)
		)
		(property "Value" "BSS138PW"
			(at 0 2.3 0)
			(layer "F.Fab")
			(effects
				(font
					(size 0.7 0.7)
					(thickness 0.15)
				)
				(justify left bottom)
			)
		)
		(property "Datasheet" "https://assets.nexperia.com/documents/data-sheet/BSS138PW.pdf"
			(at 0 0 0)
			(layer "F.Fab")
			(hide yes)
			(effects
				(font
					(size 1.27 1.27)
					(thickness 0.15)
				)
			)
		)
		(property "MPN" "BSS138PW"
			(at 0 0 0)
			(unlocked yes)
			(layer "F.Fab")
			(hide yes)
			(effects
				(font
					(size 1 1)
					(thickness 0.15)
				)
			)
		)
		(property "Manufacturer" "Nexperia"
			(at 0 0 0)
			(unlocked yes)
			(layer "F.Fab")
			(hide yes)
			(effects
				(font
					(size 1 1)
					(thickness 0.15)
				)
			)
		)
		(property "Author" "Antmicro"
			(at 0 0 0)
			(unlocked yes)
			(layer "F.Fab")
			(hide yes)
			(effects
				(font
					(size 1 1)
					(thickness 0.15)
				)
			)
		)
		(property "License" "Apache-2.0"
			(at 0 0 0)
			(unlocked yes)
			(layer "F.Fab")
			(hide yes)
			(effects
				(font
					(size 1 1)
					(thickness 0.15)
				)
			)
		)
		(sheetname "/DDR5 RDIMM/")
		(sheetfile "ddr5-rdimm.kicad_sch")
		(attr smd)
		(fp_line
			(start -0.3 -1)
			(end 0.627 -0.999)
			(stroke
				(width 0.15)
				(type solid)
			)
			(layer "F.SilkS")
		)
		(fp_line
			(start -0.3 1)
			(end 0.627 1.001)
			(stroke
				(width 0.15)
				(type solid)
			)
			(layer "F.SilkS")
		)
		(fp_line
			(start 0.627 -0.6)
			(end 0.627 -0.999)
			(stroke
				(width 0.15)
				(type solid)
			)
			(layer "F.SilkS")
		)
		(fp_line
			(start 0.627 0.6)
			(end 0.627 1.001)
			(stroke
				(width 0.15)
				(type solid)
			)
			(layer "F.SilkS")
		)
		(fp_line
			(start -1.4 1)
			(end -1.4 -1)
			(stroke
				(width 0.05)
				(type solid)
			)
			(layer "F.CrtYd")
		)
		(fp_line
			(start -0.9 -1.3)
			(end -0.9 -1)
			(stroke
				(width 0.05)
				(type solid)
			)
			(layer "F.CrtYd")
		)
		(fp_line
			(start -0.9 -1.3)
			(end 0.9 -1.3)
			(stroke
				(width 0.05)
				(type solid)
			)
			(layer "F.CrtYd")
		)
		(fp_line
			(start -0.9 -1)
			(end -1.4 -1)
			(stroke
				(width 0.05)
				(type solid)
			)
			(layer "F.CrtYd")
		)
		(fp_line
			(start -0.9 1)
			(end -1.4 1)
			(stroke
				(width 0.05)
				(type solid)
			)
			(layer "F.CrtYd")
		)
		(fp_line
			(start -0.9 1.3)
			(end -0.9 1)
			(stroke
				(width 0.05)
				(type solid)
			)
			(layer "F.CrtYd")
		)
		(fp_line
			(start 0.9 -1.3)
			(end 0.9 -0.4)
			(stroke
				(width 0.05)
				(type solid)
			)
			(layer "F.CrtYd")
		)
		(fp_line
			(start 0.9 -0.4)
			(end 1.4 -0.4)
			(stroke
				(width 0.05)
				(type solid)
			)
			(layer "F.CrtYd")
		)
		(fp_line
			(start 0.9 0.4)
			(end 0.9 1.3)
			(stroke
				(width 0.05)
				(type solid)
			)
			(layer "F.CrtYd")
		)
		(fp_line
			(start 0.9 1.3)
			(end -0.9 1.3)
			(stroke
				(width 0.05)
				(type solid)
			)
			(layer "F.CrtYd")
		)
		(fp_line
			(start 1.4 -0.4)
			(end 1.4 0.4)
			(stroke
				(width 0.05)
				(type solid)
			)
			(layer "F.CrtYd")
		)
		(fp_line
			(start 1.4 0.4)
			(end 0.9 0.4)
			(stroke
				(width 0.05)
				(type solid)
			)
			(layer "F.CrtYd")
		)
		(fp_rect
			(start -0.623 -0.999)
			(end 0.627 1.001)
			(stroke
				(width 0.15)
				(type solid)
			)
			(fill no)
			(layer "F.Fab")
		)
		(fp_text user "Author: Antmicro"
			(at -1.45 5.782 0)
			(layer "F.Fab")
			(effects
				(font
					(size 0.7 0.7)
					(thickness 0.15)
				)
				(justify left bottom)
			)
		)
		(fp_text user "License: Apache-2.0"
			(at -1.45 6.782 0)
			(layer "F.Fab")
			(effects
				(font
					(size 0.7 0.7)
					(thickness 0.15)
				)
				(justify left bottom)
			)
		)
		(fp_text user "${REFERENCE}"
			(at -1.45 4.783 0)
			(layer "F.Fab")
			(effects
				(font
					(size 0.7 0.7)
					(thickness 0.15)
				)
				(justify left bottom)
			)
		)
		(pad "1" smd rect
			(at -1.051 -0.65 90)
			(size 0.6 0.6)
			(layers "F.Cu" "F.Mask" "F.Paste")
			(net 179 "HOT_SWAP_YELLOW")
			(pinfunction "G")
			(pintype "passive")
		)
		(pad "2" smd rect
			(at -1.051 0.65 90)
			(size 0.6 0.6)
			(layers "F.Cu" "F.Mask" "F.Paste")
			(net 1 "GND")
			(pinfunction "S")
			(pintype "passive")
		)
		(pad "3" smd rect
			(at 1.05 0 90)
			(size 0.6 0.6)
			(layers "F.Cu" "F.Mask" "F.Paste")
			(net 277 "Net-(Q9-D)")
			(pinfunction "D")
			(pintype "passive")
		)
	)
	(footprint "antmicro-footprints:R_0402_1005Metric"
		(layer "F.Cu")
		(at 116.256 176.367)
		(descr "Resistor SMD 0402")
		(tags "resistor SMD 0402")
		(property "Reference" "R72"
			(at 0.9 0.45 0)
			(layer "F.SilkS")
			(effects
				(font
					(size 0.7 0.7)
					(thickness 0.15)
				)
				(justify left bottom)
			)
		)
		(property "Value" "R_2k2_0402"
			(at -1.011843 1.772047 0)
			(layer "F.Fab")
			(effects
				(font
					(size 0.7 0.7)
					(thickness 0.15)
				)
				(justify left bottom)
			)
		)
		(property "Datasheet" "https://www.bourns.com/docs/product-datasheets/cr.pdf"
			(at 0 0 0)
			(layer "F.Fab")
			(hide yes)
			(effects
				(font
					(size 1.27 1.27)
					(thickness 0.15)
				)
			)
		)
		(property "MPN" "CR0402-FX-2201GLF"
			(at 0 0 0)
			(unlocked yes)
			(layer "F.Fab")
			(hide yes)
			(effects
				(font
					(size 1 1)
					(thickness 0.15)
				)
			)
		)
		(property "Manufacturer" "Bourns"
			(at 0 0 0)
			(unlocked yes)
			(layer "F.Fab")
			(hide yes)
			(effects
				(font
					(size 1 1)
					(thickness 0.15)
				)
			)
		)
		(property "License" "Apache-2.0"
			(at 0 0 0)
			(unlocked yes)
			(layer "F.Fab")
			(hide yes)
			(effects
				(font
					(size 1 1)
					(thickness 0.15)
				)
			)
		)
		(property "Author" "Antmicro"
			(at 0 0 0)
			(unlocked yes)
			(layer "F.Fab")
			(hide yes)
			(effects
				(font
					(size 1 1)
					(thickness 0.15)
				)
			)
		)
		(property "Val" "2k2"
			(at 0 0 0)
			(unlocked yes)
			(layer "F.Fab")
			(hide yes)
			(effects
				(font
					(size 1 1)
					(thickness 0.15)
				)
			)
		)
		(property "Tolerance" "1%"
			(at 0 0 0)
			(unlocked yes)
			(layer "F.Fab")
			(hide yes)
			(effects
				(font
					(size 1 1)
					(thickness 0.15)
				)
			)
		)
		(property "Public" ""
			(at 0 0 0)
			(unlocked yes)
			(layer "F.Fab")
			(hide yes)
			(effects
				(font
					(size 1 1)
					(thickness 0.15)
				)
			)
		)
		(sheetname "/HDMI + SD Card/")
		(sheetfile "hdmi-sd-card.kicad_sch")
		(attr smd)
		(fp_rect
			(start -0.925 -0.47)
			(end 0.925 0.47)
			(stroke
				(width 0.05)
				(type default)
			)
			(fill no)
			(layer "F.CrtYd")
		)
		(fp_rect
			(start -0.5 -0.25)
			(end 0.5 0.25)
			(stroke
				(width 0.15)
				(type solid)
			)
			(fill no)
			(layer "F.Fab")
		)
		(fp_text user "Author: Antmicro"
			(at -0.95 4.169 0)
			(layer "F.Fab")
			(effects
				(font
					(size 0.7 0.7)
					(thickness 0.15)
				)
				(justify left bottom)
			)
		)
		(fp_text user "${REFERENCE}"
			(at -0.95 3.168 0)
			(layer "F.Fab")
			(effects
				(font
					(size 0.7 0.7)
					(thickness 0.15)
				)
				(justify left bottom)
			)
		)
		(fp_text user "License: Apache-2.0"
			(at -0.95 5.169 0)
			(layer "F.Fab")
			(effects
				(font
					(size 0.7 0.7)
					(thickness 0.15)
				)
				(justify left bottom)
			)
		)
		(pad "1" smd roundrect
			(at -0.48 0)
			(size 0.59 0.64)
			(layers "F.Cu" "F.Mask" "F.Paste")
			(roundrect_rratio 0.25)
			(net 468 "/HDMI + SD Card/HDMI_OUT_C.SDA")
			(pintype "passive")
		)
		(pad "2" smd roundrect
			(at 0.48 0)
			(size 0.59 0.64)
			(layers "F.Cu" "F.Mask" "F.Paste")
			(roundrect_rratio 0.25)
			(net 8 "/HDMI + SD Card/HDMI_CONN_5V")
			(pintype "passive")
		)
	)
	(footprint "antmicro-footprints:R_0402_1005Metric"
		(layer "F.Cu")
		(at 143.724499 169.899 90)
		(descr "Resistor SMD 0402")
		(tags "resistor SMD 0402")
		(property "Reference" "R88"
			(at -3.301 -0.874499 90)
			(layer "F.SilkS")
			(effects
				(font
					(size 0.7 0.7)
					(thickness 0.15)
				)
				(justify left bottom)
			)
		)
		(property "Value" "R_0R_0402"
			(at -1.011843 1.772047 90)
			(layer "F.Fab")
			(effects
				(font
					(size 0.7 0.7)
					(thickness 0.15)
				)
				(justify left bottom)
			)
		)
		(property "Datasheet" "https://industrial.panasonic.com/cdbs/www-data/pdf/RDA0000/AOA0000C301.pdf"
			(at 0 0 90)
			(layer "F.Fab")
			(hide yes)
			(effects
				(font
					(size 1.27 1.27)
					(thickness 0.15)
				)
			)
		)
		(property "Manufacturer" "Panasonic"
			(at 0 0 90)
			(unlocked yes)
			(layer "F.Fab")
			(hide yes)
			(effects
				(font
					(size 1 1)
					(thickness 0.15)
				)
			)
		)
		(property "MPN" "ERJ2GE0R00X"
			(at 0 0 90)
			(unlocked yes)
			(layer "F.Fab")
			(hide yes)
			(effects
				(font
					(size 1 1)
					(thickness 0.15)
				)
			)
		)
		(property "Val" "0R"
			(at 0 0 90)
			(unlocked yes)
			(layer "F.Fab")
			(hide yes)
			(effects
				(font
					(size 1 1)
					(thickness 0.15)
				)
			)
		)
		(property "License" "Apache-2.0"
			(at 0 0 90)
			(unlocked yes)
			(layer "F.Fab")
			(hide yes)
			(effects
				(font
					(size 1 1)
					(thickness 0.15)
				)
			)
		)
		(property "Author" "Antmicro"
			(at 0 0 90)
			(unlocked yes)
			(layer "F.Fab")
			(hide yes)
			(effects
				(font
					(size 1 1)
					(thickness 0.15)
				)
			)
		)
		(property "Tolerance" "~"
			(at 0 0 90)
			(unlocked yes)
			(layer "F.Fab")
			(hide yes)
			(effects
				(font
					(size 1 1)
					(thickness 0.15)
				)
			)
		)
		(property "Current" "1A"
			(at 0 0 90)
			(unlocked yes)
			(layer "F.Fab")
			(hide yes)
			(effects
				(font
					(size 1 1)
					(thickness 0.15)
				)
			)
		)
		(sheetname "/Debug FTDI + VNA/")
		(sheetfile "debug-ftdi.kicad_sch")
		(attr smd)
		(fp_rect
			(start -0.925 -0.47)
			(end 0.925 0.47)
			(stroke
				(width 0.05)
				(type default)
			)
			(fill no)
			(layer "F.CrtYd")
		)
		(fp_rect
			(start -0.5 -0.25)
			(end 0.5 0.25)
			(stroke
				(width 0.15)
				(type solid)
			)
			(fill no)
			(layer "F.Fab")
		)
		(fp_text user "License: Apache-2.0"
			(at -0.95 5.169 90)
			(layer "F.Fab")
			(effects
				(font
					(size 0.7 0.7)
					(thickness 0.15)
				)
				(justify left bottom)
			)
		)
		(fp_text user "${REFERENCE}"
			(at -0.95 3.168 90)
			(layer "F.Fab")
			(effects
				(font
					(size 0.7 0.7)
					(thickness 0.15)
				)
				(justify left bottom)
			)
		)
		(fp_text user "Author: Antmicro"
			(at -0.95 4.169 90)
			(layer "F.Fab")
			(effects
				(font
					(size 0.7 0.7)
					(thickness 0.15)
				)
				(justify left bottom)
			)
		)
		(pad "1" smd roundrect
			(at -0.48 0 90)
			(size 0.59 0.64)
			(layers "F.Cu" "F.Mask" "F.Paste")
			(roundrect_rratio 0.25)
			(net 301 "Net-(U13-OE)")
			(pintype "passive")
		)
		(pad "2" smd roundrect
			(at 0.48 0 90)
			(size 0.59 0.64)
			(layers "F.Cu" "F.Mask" "F.Paste")
			(roundrect_rratio 0.25)
			(net 407 "/Debug FTDI + VNA/BDBUS3")
			(pintype "passive")
		)
	)
	(footprint "antmicro-footprints:F_0603_1608Metric"
		(layer "F.Cu")
		(at 243.4 119.6 90)
		(property "Reference" "F3"
			(at -0.3 -1.63 90)
			(layer "F.SilkS")
			(effects
				(font
					(size 0.7 0.7)
					(thickness 0.15)
				)
				(justify left top)
			)
		)
		(property "Value" "F_1.25A_0603"
			(at 0 1.7 90)
			(layer "F.Fab")
			(effects
				(font
					(size 0.7 0.7)
					(thickness 0.15)
				)
				(justify left top)
			)
		)
		(property "Datasheet" "https://www.littelfuse.com/~/media/electronics/datasheets/fuses/littelfuse_fuse_467_datasheet.pdf.pdf"
			(at 0 0 90)
			(layer "F.Fab")
			(hide yes)
			(effects
				(font
					(size 1.27 1.27)
					(thickness 0.15)
				)
			)
		)
		(property "MPN" "04671.25NR"
			(at 0 0 90)
			(unlocked yes)
			(layer "F.Fab")
			(hide yes)
			(effects
				(font
					(size 1 1)
					(thickness 0.15)
				)
			)
		)
		(property "Manufacturer" "Littelfuse"
			(at 0 0 90)
			(unlocked yes)
			(layer "F.Fab")
			(hide yes)
			(effects
				(font
					(size 1 1)
					(thickness 0.15)
				)
			)
		)
		(property "Author" "Antmicro"
			(at 0 0 90)
			(unlocked yes)
			(layer "F.Fab")
			(hide yes)
			(effects
				(font
					(size 1 1)
					(thickness 0.15)
				)
			)
		)
		(property "License" "Apache-2.0"
			(at 0 0 90)
			(unlocked yes)
			(layer "F.Fab")
			(hide yes)
			(effects
				(font
					(size 1 1)
					(thickness 0.15)
				)
			)
		)
		(sheetname "/Supply/")
		(sheetfile "supply.kicad_sch")
		(attr smd)
		(fp_line
			(start -0.15 -0.4)
			(end 0.15 -0.4)
			(stroke
				(width 0.15)
				(type solid)
			)
			(layer "F.SilkS")
		)
		(fp_line
			(start -0.15 0.4)
			(end 0.15 0.4)
			(stroke
				(width 0.15)
				(type solid)
			)
			(layer "F.SilkS")
		)
		(fp_rect
			(start -1.25 -0.65)
			(end 1.25 0.65)
			(stroke
				(width 0.05)
				(type solid)
			)
			(fill no)
			(layer "F.CrtYd")
		)
		(fp_line
			(start 0.8 -0.408)
			(end -0.803 -0.408)
			(stroke
				(width 0.15)
				(type solid)
			)
			(layer "F.Fab")
		)
		(fp_line
			(start 0.8 -0.408)
			(end 0.8 0.406)
			(stroke
				(width 0.15)
				(type solid)
			)
			(layer "F.Fab")
		)
		(fp_line
			(start 0.8 0.406)
			(end -0.803 0.406)
			(stroke
				(width 0.15)
				(type solid)
			)
			(layer "F.Fab")
		)
		(fp_line
			(start -0.803 0.406)
			(end -0.803 -0.408)
			(stroke
				(width 0.15)
				(type solid)
			)
			(layer "F.Fab")
		)
		(fp_text user "License: Apache-2.0"
			(at -1.653 5.9 90)
			(layer "F.Fab")
			(effects
				(font
					(size 0.7 0.7)
					(thickness 0.15)
				)
				(justify left bottom)
			)
		)
		(fp_text user "${REFERENCE}"
			(at -1.653 4.6 90)
			(layer "F.Fab")
			(effects
				(font
					(size 0.7 0.7)
					(thickness 0.15)
				)
				(justify left bottom)
			)
		)
		(fp_text user "Author: Antmicro"
			(at -1.653 3.162 90)
			(layer "F.Fab")
			(effects
				(font
					(size 0.7 0.7)
					(thickness 0.15)
				)
				(justify left bottom)
			)
		)
		(pad "1" smd roundrect
			(at -0.7 0 90)
			(size 0.8 1)
			(layers "F.Cu" "F.Mask" "F.Paste")
			(roundrect_rratio 0.2)
			(net 814 "Net-(Q29-D)")
			(pintype "passive")
		)
		(pad "2" smd roundrect
			(at 0.7 0 90)
			(size 0.8 1)
			(layers "F.Cu" "F.Mask" "F.Paste")
			(roundrect_rratio 0.2)
			(net 811 "/Supply/heater")
			(pintype "passive")
		)
	)
	(footprint "antmicro-footprints:L_0402_1005Metric"
		(layer "F.Cu")
		(at 121.025 148.61 180)
		(descr "Inductor SMD 0402")
		(tags "Inductor SMD 0402")
		(property "Reference" "L4"
			(at -5.385 -0.465 0)
			(layer "F.SilkS")
			(effects
				(font
					(size 0.7 0.7)
					(thickness 0.15)
				)
				(justify right bottom)
			)
		)
		(property "Value" "L_20n_0.35A_0402"
			(at 0 1.4 0)
			(layer "F.Fab")
			(effects
				(font
					(size 0.7 0.7)
					(thickness 0.15)
				)
				(justify right bottom)
			)
		)
		(property "Datasheet" "https://product.tdk.com/system/files/dam/doc/product/inductor/inductor/smd/catalog/inductor_automotive_high-frequency_mlg1005s_en.pdf?ref_disty=mouser"
			(at 0 0 180)
			(layer "F.Fab")
			(hide yes)
			(effects
				(font
					(size 1.27 1.27)
					(thickness 0.15)
				)
			)
		)
		(property "Val" "20n/0.35A"
			(at 0 0 180)
			(unlocked yes)
			(layer "F.Fab")
			(hide yes)
			(effects
				(font
					(size 1 1)
					(thickness 0.15)
				)
			)
		)
		(property "Manufacturer" "TDK"
			(at 0 0 180)
			(unlocked yes)
			(layer "F.Fab")
			(hide yes)
			(effects
				(font
					(size 1 1)
					(thickness 0.15)
				)
			)
		)
		(property "MPN" "MLG1005S20NJTD25"
			(at 0 0 180)
			(unlocked yes)
			(layer "F.Fab")
			(hide yes)
			(effects
				(font
					(size 1 1)
					(thickness 0.15)
				)
			)
		)
		(property "ISat" ""
			(at 0 0 180)
			(unlocked yes)
			(layer "F.Fab")
			(hide yes)
			(effects
				(font
					(size 1 1)
					(thickness 0.15)
				)
			)
		)
		(property "IMax" "0.35 A"
			(at 0 0 180)
			(unlocked yes)
			(layer "F.Fab")
			(hide yes)
			(effects
				(font
					(size 1 1)
					(thickness 0.15)
				)
			)
		)
		(property "Size" "1.0x0.5"
			(at 0 0 180)
			(unlocked yes)
			(layer "F.Fab")
			(hide yes)
			(effects
				(font
					(size 1 1)
					(thickness 0.15)
				)
			)
		)
		(property "Author" "Antmicro"
			(at 0 0 180)
			(unlocked yes)
			(layer "F.Fab")
			(hide yes)
			(effects
				(font
					(size 1 1)
					(thickness 0.15)
				)
			)
		)
		(property "License" "Apache-2.0"
			(at 0 0 180)
			(unlocked yes)
			(layer "F.Fab")
			(hide yes)
			(effects
				(font
					(size 1 1)
					(thickness 0.15)
				)
			)
		)
		(sheetname "/HDMI + SD Card/")
		(sheetfile "hdmi-sd-card.kicad_sch")
		(attr smd)
		(fp_rect
			(start -0.925 -0.47)
			(end 0.925 0.47)
			(stroke
				(width 0.05)
				(type default)
			)
			(fill no)
			(layer "F.CrtYd")
		)
		(fp_rect
			(start -0.499 -0.249)
			(end 0.499 0.249)
			(stroke
				(width 0.15)
				(type solid)
			)
			(fill no)
			(layer "F.Fab")
		)
		(fp_text user "${REFERENCE}"
			(at -0.932 3.168 180)
			(layer "F.Fab")
			(effects
				(font
					(size 0.7 0.7)
					(thickness 0.15)
				)
				(justify left bottom)
			)
		)
		(fp_text user "Author: Antmicro"
			(at -0.932 4.17 180)
			(layer "F.Fab")
			(effects
				(font
					(size 0.7 0.7)
					(thickness 0.15)
				)
				(justify left bottom)
			)
		)
		(fp_text user "License: Apache-2.0"
			(at -0.932 5.17 180)
			(layer "F.Fab")
			(effects
				(font
					(size 0.7 0.7)
					(thickness 0.15)
				)
				(justify left bottom)
			)
		)
		(pad "1" smd roundrect
			(at -0.48 0 180)
			(size 0.59 0.64)
			(layers "F.Cu" "F.Mask" "F.Paste")
			(roundrect_rratio 0.25)
			(net 342 "/FPGA MGT Interface/HDMI_IN.D2_N")
			(pintype "passive")
		)
		(pad "2" smd roundrect
			(at 0.48 0 180)
			(size 0.59 0.64)
			(layers "F.Cu" "F.Mask" "F.Paste")
			(roundrect_rratio 0.25)
			(net 674 "Net-(L4-Pad2)")
			(pintype "passive")
		)
	)
	(footprint "antmicro-footprints:R_0402_1005Metric"
		(layer "F.Cu")
		(at 253.5055 150.371 180)
		(descr "Resistor SMD 0402")
		(tags "resistor SMD 0402")
		(property "Reference" "R157"
			(at 0.8055 0.471 0)
			(layer "F.SilkS")
			(effects
				(font
					(size 0.7 0.7)
					(thickness 0.15)
				)
				(justify right bottom)
			)
		)
		(property "Value" "R_0R_0402"
			(at -1.011843 1.772047 0)
			(layer "F.Fab")
			(effects
				(font
					(size 0.7 0.7)
					(thickness 0.15)
				)
				(justify right bottom)
			)
		)
		(property "Datasheet" "https://industrial.panasonic.com/cdbs/www-data/pdf/RDA0000/AOA0000C301.pdf"
			(at 0 0 180)
			(layer "F.Fab")
			(hide yes)
			(effects
				(font
					(size 1.27 1.27)
					(thickness 0.15)
				)
			)
		)
		(property "Manufacturer" "Panasonic"
			(at 0 0 180)
			(unlocked yes)
			(layer "F.Fab")
			(hide yes)
			(effects
				(font
					(size 1 1)
					(thickness 0.15)
				)
			)
		)
		(property "MPN" "ERJ2GE0R00X"
			(at 0 0 180)
			(unlocked yes)
			(layer "F.Fab")
			(hide yes)
			(effects
				(font
					(size 1 1)
					(thickness 0.15)
				)
			)
		)
		(property "Val" "0R"
			(at 0 0 180)
			(unlocked yes)
			(layer "F.Fab")
			(hide yes)
			(effects
				(font
					(size 1 1)
					(thickness 0.15)
				)
			)
		)
		(property "License" "Apache-2.0"
			(at 0 0 180)
			(unlocked yes)
			(layer "F.Fab")
			(hide yes)
			(effects
				(font
					(size 1 1)
					(thickness 0.15)
				)
			)
		)
		(property "Author" "Antmicro"
			(at 0 0 180)
			(unlocked yes)
			(layer "F.Fab")
			(hide yes)
			(effects
				(font
					(size 1 1)
					(thickness 0.15)
				)
			)
		)
		(property "Tolerance" "~"
			(at 0 0 180)
			(unlocked yes)
			(layer "F.Fab")
			(hide yes)
			(effects
				(font
					(size 1 1)
					(thickness 0.15)
				)
			)
		)
		(property "Current" "1A"
			(at 0 0 180)
			(unlocked yes)
			(layer "F.Fab")
			(hide yes)
			(effects
				(font
					(size 1 1)
					(thickness 0.15)
				)
			)
		)
		(sheetname "/Supply/DC-DC IO/")
		(sheetfile "dc-dc-io.kicad_sch")
		(attr smd)
		(fp_rect
			(start -0.925 -0.47)
			(end 0.925 0.47)
			(stroke
				(width 0.05)
				(type default)
			)
			(fill no)
			(layer "F.CrtYd")
		)
		(fp_rect
			(start -0.5 -0.25)
			(end 0.5 0.25)
			(stroke
				(width 0.15)
				(type solid)
			)
			(fill no)
			(layer "F.Fab")
		)
		(fp_text user "${REFERENCE}"
			(at -0.95 3.168 180)
			(layer "F.Fab")
			(effects
				(font
					(size 0.7 0.7)
					(thickness 0.15)
				)
				(justify left bottom)
			)
		)
		(fp_text user "Author: Antmicro"
			(at -0.95 4.169 180)
			(layer "F.Fab")
			(effects
				(font
					(size 0.7 0.7)
					(thickness 0.15)
				)
				(justify left bottom)
			)
		)
		(fp_text user "License: Apache-2.0"
			(at -0.95 5.169 180)
			(layer "F.Fab")
			(effects
				(font
					(size 0.7 0.7)
					(thickness 0.15)
				)
				(justify left bottom)
			)
		)
		(pad "1" smd roundrect
			(at -0.48 0 180)
			(size 0.59 0.64)
			(layers "F.Cu" "F.Mask" "F.Paste")
			(roundrect_rratio 0.25)
			(net 715 "/Supply/DC-DC IO/FB6")
			(pintype "passive")
		)
		(pad "2" smd roundrect
			(at 0.48 0 180)
			(size 0.59 0.64)
			(layers "F.Cu" "F.Mask" "F.Paste")
			(roundrect_rratio 0.25)
			(net 46 "/Supply/DC-DC IO/5V_local")
			(pintype "passive")
		)
	)
	(footprint "antmicro-footprints:FB_0402_1005Metric"
		(layer "F.Cu")
		(at 120.1 145.61 180)
		(descr "Ferrite Bead SMD 0402")
		(tags "ferrite bead SMD 0402")
		(property "Reference" "FB7"
			(at -2.9 -0.365 0)
			(layer "F.SilkS")
			(effects
				(font
					(size 0.7 0.7)
					(thickness 0.15)
				)
				(justify right bottom)
			)
		)
		(property "Value" "FB_120Z_1.3A_Murata-BLM15PD_0402"
			(at 0 1.4 0)
			(layer "F.Fab")
			(effects
				(font
					(size 0.7 0.7)
					(thickness 0.15)
				)
				(justify right bottom)
			)
		)
		(property "Datasheet" "https://www.murata.com/en-us/products/productdata/8796740059166/ENFA0018.pdf"
			(at 0 0 180)
			(layer "F.Fab")
			(hide yes)
			(effects
				(font
					(size 1.27 1.27)
					(thickness 0.15)
				)
			)
		)
		(property "Val" "120Z/1.3A"
			(at 0 0 180)
			(unlocked yes)
			(layer "F.Fab")
			(hide yes)
			(effects
				(font
					(size 1 1)
					(thickness 0.15)
				)
			)
		)
		(property "MPN" "BLM15PD121SN1D"
			(at 0 0 180)
			(unlocked yes)
			(layer "F.Fab")
			(hide yes)
			(effects
				(font
					(size 1 1)
					(thickness 0.15)
				)
			)
		)
		(property "Manufacturer" "Murata"
			(at 0 0 180)
			(unlocked yes)
			(layer "F.Fab")
			(hide yes)
			(effects
				(font
					(size 1 1)
					(thickness 0.15)
				)
			)
		)
		(property "Current" ""
			(at 0 0 180)
			(unlocked yes)
			(layer "F.Fab")
			(hide yes)
			(effects
				(font
					(size 1 1)
					(thickness 0.15)
				)
			)
		)
		(property "Author" "Antmicro"
			(at 0 0 180)
			(unlocked yes)
			(layer "F.Fab")
			(hide yes)
			(effects
				(font
					(size 1 1)
					(thickness 0.15)
				)
			)
		)
		(property "License" "Apache-2.0"
			(at 0 0 180)
			(unlocked yes)
			(layer "F.Fab")
			(hide yes)
			(effects
				(font
					(size 1 1)
					(thickness 0.15)
				)
			)
		)
		(sheetname "/HDMI + SD Card/")
		(sheetfile "hdmi-sd-card.kicad_sch")
		(attr smd)
		(fp_rect
			(start -0.925 -0.47)
			(end 0.925 0.47)
			(stroke
				(width 0.05)
				(type default)
			)
			(fill no)
			(layer "F.CrtYd")
		)
		(fp_rect
			(start -0.5 -0.25)
			(end 0.5 0.25)
			(stroke
				(width 0.15)
				(type solid)
			)
			(fill no)
			(layer "F.Fab")
		)
		(fp_text user "License: Apache-2.0"
			(at -0.95 5.169 180)
			(layer "F.Fab")
			(effects
				(font
					(size 0.7 0.7)
					(thickness 0.15)
				)
				(justify left bottom)
			)
		)
		(fp_text user "Author: Antmicro"
			(at -0.95 4.169 180)
			(layer "F.Fab")
			(effects
				(font
					(size 0.7 0.7)
					(thickness 0.15)
				)
				(justify left bottom)
			)
		)
		(fp_text user "${REFERENCE}"
			(at -0.95 3.168 180)
			(layer "F.Fab")
			(effects
				(font
					(size 0.7 0.7)
					(thickness 0.15)
				)
				(justify left bottom)
			)
		)
		(pad "1" smd roundrect
			(at -0.48 0 180)
			(size 0.59 0.64)
			(layers "F.Cu" "F.Mask" "F.Paste")
			(roundrect_rratio 0.25)
			(net 151 "+3V3")
			(pintype "passive")
		)
		(pad "2" smd roundrect
			(at 0.48 0 180)
			(size 0.59 0.64)
			(layers "F.Cu" "F.Mask" "F.Paste")
			(roundrect_rratio 0.25)
			(net 322 "Net-(C300-Pad2)")
			(pintype "passive")
		)
	)
	(footprint "antmicro-footprints:R_0402_1005Metric"
		(layer "F.Cu")
		(at 145.124499 173.249 -90)
		(descr "Resistor SMD 0402")
		(tags "resistor SMD 0402")
		(property "Reference" "R95"
			(at 0.931 -0.465501 90)
			(layer "F.SilkS")
			(effects
				(font
					(size 0.7 0.7)
					(thickness 0.15)
				)
				(justify right bottom)
			)
		)
		(property "Value" "R_4k7_0402"
			(at -1.011843 1.772047 90)
			(layer "F.Fab")
			(effects
				(font
					(size 0.7 0.7)
					(thickness 0.15)
				)
				(justify right bottom)
			)
		)
		(property "Datasheet" "https://www.bourns.com/docs/product-datasheets/cr.pdf"
			(at 0 0 270)
			(layer "F.Fab")
			(hide yes)
			(effects
				(font
					(size 1.27 1.27)
					(thickness 0.15)
				)
			)
		)
		(property "Manufacturer" "Bourns"
			(at 0 0 270)
			(unlocked yes)
			(layer "F.Fab")
			(hide yes)
			(effects
				(font
					(size 1 1)
					(thickness 0.15)
				)
			)
		)
		(property "MPN" "CR0402-FX-4701GLF"
			(at 0 0 270)
			(unlocked yes)
			(layer "F.Fab")
			(hide yes)
			(effects
				(font
					(size 1 1)
					(thickness 0.15)
				)
			)
		)
		(property "Val" "4k7"
			(at 0 0 270)
			(unlocked yes)
			(layer "F.Fab")
			(hide yes)
			(effects
				(font
					(size 1 1)
					(thickness 0.15)
				)
			)
		)
		(property "License" "Apache-2.0"
			(at 0 0 270)
			(unlocked yes)
			(layer "F.Fab")
			(hide yes)
			(effects
				(font
					(size 1 1)
					(thickness 0.15)
				)
			)
		)
		(property "Author" "Antmicro"
			(at 0 0 270)
			(unlocked yes)
			(layer "F.Fab")
			(hide yes)
			(effects
				(font
					(size 1 1)
					(thickness 0.15)
				)
			)
		)
		(property "Tolerance" "1%"
			(at 0 0 270)
			(unlocked yes)
			(layer "F.Fab")
			(hide yes)
			(effects
				(font
					(size 1 1)
					(thickness 0.15)
				)
			)
		)
		(sheetname "/Debug FTDI + VNA/")
		(sheetfile "debug-ftdi.kicad_sch")
		(attr smd)
		(fp_rect
			(start -0.925 -0.47)
			(end 0.925 0.47)
			(stroke
				(width 0.05)
				(type default)
			)
			(fill no)
			(layer "F.CrtYd")
		)
		(fp_rect
			(start -0.5 -0.25)
			(end 0.5 0.25)
			(stroke
				(width 0.15)
				(type solid)
			)
			(fill no)
			(layer "F.Fab")
		)
		(fp_text user "${REFERENCE}"
			(at -0.95 3.168 270)
			(layer "F.Fab")
			(effects
				(font
					(size 0.7 0.7)
					(thickness 0.15)
				)
				(justify left bottom)
			)
		)
		(fp_text user "License: Apache-2.0"
			(at -0.95 5.169 270)
			(layer "F.Fab")
			(effects
				(font
					(size 0.7 0.7)
					(thickness 0.15)
				)
				(justify left bottom)
			)
		)
		(fp_text user "Author: Antmicro"
			(at -0.95 4.169 270)
			(layer "F.Fab")
			(effects
				(font
					(size 0.7 0.7)
					(thickness 0.15)
				)
				(justify left bottom)
			)
		)
		(pad "1" smd roundrect
			(at -0.48 0 270)
			(size 0.59 0.64)
			(layers "F.Cu" "F.Mask" "F.Paste")
			(roundrect_rratio 0.25)
			(net 38 "+3V3_AON")
			(pintype "passive")
		)
		(pad "2" smd roundrect
			(at 0.48 0 270)
			(size 0.59 0.64)
			(layers "F.Cu" "F.Mask" "F.Paste")
			(roundrect_rratio 0.25)
			(net 527 "/Debug FTDI + VNA/FTDI.SDA")
			(pintype "passive")
		)
	)
	(footprint "antmicro-footprints:NetTie-2_SMD_Pad0.127mm"
		(layer "F.Cu")
		(at 246.877 160.15)
		(descr "Net tie, 2 pin, 0.127mm  SMD pads")
		(tags "net tie")
		(property "Reference" "NT5"
			(at -0.128 -1.345 0)
			(layer "F.SilkS")
			(hide yes)
			(effects
				(font
					(size 0.7 0.7)
					(thickness 0.15)
				)
				(justify left bottom)
			)
		)
		(property "Value" "Net-Tie_P0.127mm"
			(at 0 1.199 0)
			(layer "F.Fab")
			(effects
				(font
					(size 0.7 0.7)
					(thickness 0.15)
				)
				(justify left bottom)
			)
		)
		(property "MPN" ""
			(at 0 0 0)
			(unlocked yes)
			(layer "F.Fab")
			(hide yes)
			(effects
				(font
					(size 1 1)
					(thickness 0.15)
				)
			)
		)
		(property "Manufacturer" ""
			(at 0 0 0)
			(unlocked yes)
			(layer "F.Fab")
			(hide yes)
			(effects
				(font
					(size 1 1)
					(thickness 0.15)
				)
			)
		)
		(property "Author" "Antmicro"
			(at 0 0 0)
			(unlocked yes)
			(layer "F.Fab")
			(hide yes)
			(effects
				(font
					(size 1 1)
					(thickness 0.15)
				)
			)
		)
		(property "License" "Apache-2.0"
			(at 0 0 0)
			(unlocked yes)
			(layer "F.Fab")
			(hide yes)
			(effects
				(font
					(size 1 1)
					(thickness 0.15)
				)
			)
		)
		(property ki_fp_filters "Net*Tie*")
		(sheetname "/Supply/DC-DC IO/")
		(sheetfile "dc-dc-io.kicad_sch")
		(attr through_hole exclude_from_pos_files exclude_from_bom)
		(net_tie_pad_groups "1, 2")
		(fp_poly
			(pts
				(xy -0.0635 -0.0635) (xy 0.0625 -0.0635) (xy 0.0625 0.0635) (xy -0.0635 0.0635)
			)
			(stroke
				(width 0)
				(type solid)
			)
			(fill yes)
			(layer "F.Cu")
		)
		(fp_poly
			(pts
				(xy 0.2 -0.16) (xy 0.29 -0.07) (xy 0.29 0.07) (xy 0.2 0.16) (xy -0.2 0.16) (xy -0.29 0.07) (xy -0.29 -0.06)
				(xy -0.19 -0.16)
			)
			(stroke
				(width 0.05)
				(type solid)
			)
			(fill no)
			(layer "F.CrtYd")
		)
		(fp_text user "${REFERENCE}"
			(at -0.128 3.2 0)
			(layer "F.Fab")
			(effects
				(font
					(size 0.7 0.7)
					(thickness 0.15)
				)
				(justify left bottom)
			)
		)
		(fp_text user "Author: Antmicro"
			(at -0.128 4.4 0)
			(layer "F.Fab")
			(effects
				(font
					(size 0.7 0.7)
					(thickness 0.15)
				)
				(justify left bottom)
			)
		)
		(fp_text user "License: Apache-2.0"
			(at -0.128 5.6 0)
			(layer "F.Fab")
			(effects
				(font
					(size 0.7 0.7)
					(thickness 0.15)
				)
				(justify left bottom)
			)
		)
		(pad "1" smd roundrect
			(at -0.127 0 180)
			(size 0.127 0.127)
			(layers "F.Cu")
			(roundrect_rratio 0.5)
			(chamfer_ratio 0)
			(chamfer top_left bottom_left)
			(net 685 "/Supply/DC-DC IO/3V3_SEN_+")
			(pinfunction "1")
			(pintype "passive")
		)
		(pad "2" smd roundrect
			(at 0.126 0)
			(size 0.127 0.127)
			(layers "F.Cu")
			(roundrect_rratio 0.5)
			(chamfer_ratio 0)
			(chamfer top_left bottom_left)
			(net 45 "/Supply/DC-DC IO/3V3_local")
			(pinfunction "2")
			(pintype "passive")
		)
	)
	(footprint "antmicro-footprints:RJ45_ARJM11B1-502-AB-EW2_Horizontal"
		(layer "F.Cu")
		(at 118.114999 120.247487 -90)
		(descr "ARJM11B1-502-AB-EW2 RJ45 JACK")
		(property "Reference" "J6"
			(at -2.35 -2.3 270)
			(layer "F.SilkS")
			(effects
				(font
					(size 0.7 0.7)
					(thickness 0.15)
				)
				(justify left bottom)
			)
		)
		(property "Value" "RJ45_Abracon_ARJM11B1-502-AB-EW2"
			(at -4.3 22.78 270)
			(layer "F.Fab")
			(effects
				(font
					(size 0.7 0.7)
					(thickness 0.15)
				)
				(justify left bottom)
			)
		)
		(property "Datasheet" "https://www.mouser.com/datasheet/3/184/1/ARJM11.pdf"
			(at -0.035 -0.01 270)
			(layer "F.Fab")
			(effects
				(font
					(size 0.7 0.7)
					(thickness 0.15)
				)
				(justify left bottom)
			)
		)
		(property "Description" "Modular Connectors / Ethernet Connectors RJ45 JACK W/MAG 1X1 1000BASE-T"
			(at -0.035 -0.01 270)
			(layer "F.Fab")
			(effects
				(font
					(size 0.7 0.7)
					(thickness 0.15)
				)
				(justify left bottom)
			)
		)
		(property "MPN" "ARJM11B1-502-AB-EW2"
			(at 0 0 270)
			(unlocked yes)
			(layer "F.Fab")
			(hide yes)
			(effects
				(font
					(size 1 1)
					(thickness 0.15)
				)
			)
		)
		(property "Manufacturer" "Abracon"
			(at 0 0 270)
			(unlocked yes)
			(layer "F.Fab")
			(hide yes)
			(effects
				(font
					(size 1 1)
					(thickness 0.15)
				)
			)
		)
		(property "Author" "Antmicro"
			(at 0 0 270)
			(unlocked yes)
			(layer "F.Fab")
			(hide yes)
			(effects
				(font
					(size 1 1)
					(thickness 0.15)
				)
			)
		)
		(property "License" "Apache-2.0"
			(at 0 0 270)
			(unlocked yes)
			(layer "F.Fab")
			(hide yes)
			(effects
				(font
					(size 1 1)
					(thickness 0.15)
				)
			)
		)
		(sheetname "/Ethernet/")
		(sheetfile "ethernet.kicad_sch")
		(attr through_hole)
		(fp_line
			(start -2.235 19.69)
			(end 13.665 19.69)
			(stroke
				(width 0.15)
				(type solid)
			)
			(layer "F.SilkS")
		)
		(fp_line
			(start -2.235 19.69)
			(end -2.235 7.48)
			(stroke
				(width 0.15)
				(type solid)
			)
			(layer "F.SilkS")
		)
		(fp_line
			(start 13.665 19.69)
			(end 13.665 7.48)
			(stroke
				(width 0.15)
				(type solid)
			)
			(layer "F.SilkS")
		)
		(fp_line
			(start 13.665 4.19)
			(end 13.665 -1.51)
			(stroke
				(width 0.15)
				(type solid)
			)
			(layer "F.SilkS")
		)
		(fp_line
			(start -2.235 -1.51)
			(end -2.235 4.19)
			(stroke
				(width 0.15)
				(type solid)
			)
			(layer "F.SilkS")
		)
		(fp_line
			(start 13.665 -1.51)
			(end -2.235 -1.51)
			(stroke
				(width 0.15)
				(type solid)
			)
			(layer "F.SilkS")
		)
		(fp_line
			(start -3.7 19.94)
			(end 15.12 19.94)
			(stroke
				(width 0.05)
				(type solid)
			)
			(layer "F.CrtYd")
		)
		(fp_line
			(start 15.12 19.94)
			(end 15.12 -1.76)
			(stroke
				(width 0.05)
				(type solid)
			)
			(layer "F.CrtYd")
		)
		(fp_line
			(start -3.7 -1.76)
			(end -3.7 19.94)
			(stroke
				(width 0.05)
				(type solid)
			)
			(layer "F.CrtYd")
		)
		(fp_line
			(start 15.12 -1.76)
			(end -3.7 -1.76)
			(stroke
				(width 0.05)
				(type solid)
			)
			(layer "F.CrtYd")
		)
		(fp_line
			(start -2.235 19.69)
			(end 13.665 19.69)
			(stroke
				(width 0.15)
				(type solid)
			)
			(layer "F.Fab")
		)
		(fp_line
			(start 13.665 19.69)
			(end 13.665 -1.51)
			(stroke
				(width 0.15)
				(type solid)
			)
			(layer "F.Fab")
		)
		(fp_line
			(start -2.235 -1.51)
			(end -2.235 19.69)
			(stroke
				(width 0.15)
				(type solid)
			)
			(layer "F.Fab")
		)
		(fp_line
			(start 13.665 -1.51)
			(end -2.235 -1.51)
			(stroke
				(width 0.15)
				(type solid)
			)
			(layer "F.Fab")
		)
		(fp_text user "Author: Antmicro"
			(at -4.3 23.98 270)
			(layer "F.Fab")
			(effects
				(font
					(size 0.7 0.7)
					(thickness 0.15)
				)
				(justify left bottom)
			)
		)
		(fp_text user "License: Apache-2.0"
			(at -4.3 25.18 270)
			(layer "F.Fab")
			(effects
				(font
					(size 0.7 0.7)
					(thickness 0.15)
				)
				(justify left bottom)
			)
		)
		(fp_text user "${REFERENCE}"
			(at -4.26 21.29 270)
			(layer "F.Fab")
			(effects
				(font
					(size 0.7 0.7)
					(thickness 0.15)
				)
				(justify left bottom)
			)
		)
		(pad "" np_thru_hole circle
			(at 0 8.89 270)
			(size 3.2 3.2)
			(drill 3.25)
			(layers "*.Cu" "*.Mask")
		)
		(pad "" np_thru_hole circle
			(at 11.43 8.89 270)
			(size 3.2 3.2)
			(drill 3.25)
			(layers "*.Cu" "*.Mask")
		)
		(pad "1" thru_hole circle
			(at 0 0 270)
			(size 1.458 1.458)
			(drill 0.9)
			(layers "*.Cu" "*.Mask")
			(remove_unused_layers no)
			(net 88 "/Ethernet/ETH1_P")
			(pinfunction "1")
			(pintype "bidirectional")
			(solder_mask_margin 0)
		)
		(pad "2" thru_hole circle
			(at 1.27 2.54 270)
			(size 1.458 1.458)
			(drill 0.9)
			(layers "*.Cu" "*.Mask")
			(remove_unused_layers no)
			(net 91 "/Ethernet/ETH1_N")
			(pinfunction "2")
			(pintype "bidirectional")
			(solder_mask_margin 0)
		)
		(pad "3" thru_hole circle
			(at 2.54 0 270)
			(size 1.458 1.458)
			(drill 0.9)
			(layers "*.Cu" "*.Mask")
			(remove_unused_layers no)
			(net 87 "/Ethernet/ETH2_P")
			(pinfunction "3")
			(pintype "bidirectional")
			(solder_mask_margin 0)
		)
		(pad "4" thru_hole circle
			(at 3.81 2.54 270)
			(size 1.458 1.458)
			(drill 0.9)
			(layers "*.Cu" "*.Mask")
			(remove_unused_layers no)
			(net 90 "/Ethernet/ETH2_N")
			(pinfunction "4")
			(pintype "bidirectional")
			(solder_mask_margin 0)
		)
		(pad "5" thru_hole circle
			(at 5.08 0 270)
			(size 1.458 1.458)
			(drill 0.9)
			(layers "*.Cu" "*.Mask")
			(remove_unused_layers no)
			(net 821 "Net-(C135-Pad2)")
			(pinfunction "5")
			(pintype "passive")
			(solder_mask_margin 0)
		)
		(pad "6" thru_hole circle
			(at 6.35 2.54 270)
			(size 1.458 1.458)
			(drill 0.9)
			(layers "*.Cu" "*.Mask")
			(remove_unused_layers no)
			(net 822 "Net-(C137-Pad2)")
			(pinfunction "6")
			(pintype "passive")
			(solder_mask_margin 0)
		)
		(pad "7" thru_hole circle
			(at 7.62 0 270)
			(size 1.458 1.458)
			(drill 0.9)
			(layers "*.Cu" "*.Mask")
			(remove_unused_layers no)
			(net 86 "/Ethernet/ETH3_P")
			(pinfunction "7")
			(pintype "bidirectional")
			(solder_mask_margin 0)
		)
		(pad "8" thru_hole circle
			(at 8.89 2.54 270)
			(size 1.458 1.458)
			(drill 0.9)
			(layers "*.Cu" "*.Mask")
			(remove_unused_layers no)
			(net 92 "/Ethernet/ETH3_N")
			(pinfunction "8")
			(pintype "bidirectional")
			(solder_mask_margin 0)
		)
		(pad "9" thru_hole circle
			(at 10.16 0 270)
			(size 1.458 1.458)
			(drill 0.9)
			(layers "*.Cu" "*.Mask")
			(remove_unused_layers no)
			(net 89 "/Ethernet/ETH4_P")
			(pinfunction "9")
			(pintype "bidirectional")
			(solder_mask_margin 0)
		)
		(pad "10" thru_hole circle
			(at 11.43 2.54 270)
			(size 1.458 1.458)
			(drill 0.9)
			(layers "*.Cu" "*.Mask")
			(remove_unused_layers no)
			(net 93 "/Ethernet/ETH4_N")
			(pinfunction "10")
			(pintype "bidirectional")
			(solder_mask_margin 0)
		)
		(pad "11" thru_hole circle
			(at -0.96 12.95 270)
			(size 1.605 1.605)
			(drill 1.02)
			(layers "*.Cu" "*.Mask")
			(remove_unused_layers no)
			(net 823 "Net-(J6-LED_G+)")
			(pinfunction "LED_G+")
			(pintype "passive")
			(solder_mask_margin 0)
		)
		(pad "12" thru_hole circle
			(at 1.58 12.95 270)
			(size 1.605 1.605)
			(drill 1.02)
			(layers "*.Cu" "*.Mask")
			(remove_unused_layers no)
			(net 330 "/Ethernet/LED_SPD")
			(pinfunction "LED_G-")
			(pintype "passive")
			(solder_mask_margin 0)
		)
		(pad "13" thru_hole circle
			(at 9.85 12.95 270)
			(size 1.605 1.605)
			(drill 1.02)
			(layers "*.Cu" "*.Mask")
			(remove_unused_layers no)
			(net 824 "Net-(J6-LED_Y+)")
			(pinfunction "LED_Y+")
			(pintype "passive")
			(solder_mask_margin 0)
		)
		(pad "14" thru_hole circle
			(at 12.39 12.95 270)
			(size 1.605 1.605)
			(drill 1.02)
			(layers "*.Cu" "*.Mask")
			(remove_unused_layers no)
			(net 331 "/Ethernet/LED_LINK")
			(pinfunction "LED_Y-")
			(pintype "passive")
			(solder_mask_margin 0)
		)
		(pad "SH" thru_hole circle
			(at -2.135 5.84 270)
			(size 2.625 2.625)
			(drill 1.7)
			(layers "*.Cu" "*.Mask")
			(remove_unused_layers no)
			(net 31 "Net-(C234-Pad1)")
			(pinfunction "SH")
			(pintype "passive")
			(solder_mask_margin 0)
		)
		(pad "SH" thru_hole circle
			(at 13.565 5.84 270)
			(size 2.625 2.625)
			(drill 1.7)
			(layers "*.Cu" "*.Mask")
			(remove_unused_layers no)
			(net 31 "Net-(C234-Pad1)")
			(pinfunction "SH")
			(pintype "passive")
			(solder_mask_margin 0)
		)
	)
	(footprint "antmicro-footprints:L_0402_1005Metric"
		(layer "F.Cu")
		(at 121.025 149.61 180)
		(descr "Inductor SMD 0402")
		(tags "Inductor SMD 0402")
		(property "Reference" "L3"
			(at -5.375 -0.435 0)
			(layer "F.SilkS")
			(effects
				(font
					(size 0.7 0.7)
					(thickness 0.15)
				)
				(justify right bottom)
			)
		)
		(property "Value" "L_20n_0.35A_0402"
			(at 0 1.4 0)
			(layer "F.Fab")
			(effects
				(font
					(size 0.7 0.7)
					(thickness 0.15)
				)
				(justify right bottom)
			)
		)
		(property "Datasheet" "https://product.tdk.com/system/files/dam/doc/product/inductor/inductor/smd/catalog/inductor_automotive_high-frequency_mlg1005s_en.pdf?ref_disty=mouser"
			(at 0 0 180)
			(layer "F.Fab")
			(hide yes)
			(effects
				(font
					(size 1.27 1.27)
					(thickness 0.15)
				)
			)
		)
		(property "Val" "20n/0.35A"
			(at 0 0 180)
			(unlocked yes)
			(layer "F.Fab")
			(hide yes)
			(effects
				(font
					(size 1 1)
					(thickness 0.15)
				)
			)
		)
		(property "Manufacturer" "TDK"
			(at 0 0 180)
			(unlocked yes)
			(layer "F.Fab")
			(hide yes)
			(effects
				(font
					(size 1 1)
					(thickness 0.15)
				)
			)
		)
		(property "MPN" "MLG1005S20NJTD25"
			(at 0 0 180)
			(unlocked yes)
			(layer "F.Fab")
			(hide yes)
			(effects
				(font
					(size 1 1)
					(thickness 0.15)
				)
			)
		)
		(property "ISat" ""
			(at 0 0 180)
			(unlocked yes)
			(layer "F.Fab")
			(hide yes)
			(effects
				(font
					(size 1 1)
					(thickness 0.15)
				)
			)
		)
		(property "IMax" "0.35 A"
			(at 0 0 180)
			(unlocked yes)
			(layer "F.Fab")
			(hide yes)
			(effects
				(font
					(size 1 1)
					(thickness 0.15)
				)
			)
		)
		(property "Size" "1.0x0.5"
			(at 0 0 180)
			(unlocked yes)
			(layer "F.Fab")
			(hide yes)
			(effects
				(font
					(size 1 1)
					(thickness 0.15)
				)
			)
		)
		(property "Author" "Antmicro"
			(at 0 0 180)
			(unlocked yes)
			(layer "F.Fab")
			(hide yes)
			(effects
				(font
					(size 1 1)
					(thickness 0.15)
				)
			)
		)
		(property "License" "Apache-2.0"
			(at 0 0 180)
			(unlocked yes)
			(layer "F.Fab")
			(hide yes)
			(effects
				(font
					(size 1 1)
					(thickness 0.15)
				)
			)
		)
		(sheetname "/HDMI + SD Card/")
		(sheetfile "hdmi-sd-card.kicad_sch")
		(attr smd)
		(fp_rect
			(start -0.925 -0.47)
			(end 0.925 0.47)
			(stroke
				(width 0.05)
				(type default)
			)
			(fill no)
			(layer "F.CrtYd")
		)
		(fp_rect
			(start -0.499 -0.249)
			(end 0.499 0.249)
			(stroke
				(width 0.15)
				(type solid)
			)
			(fill no)
			(layer "F.Fab")
		)
		(fp_text user "${REFERENCE}"
			(at -0.932 3.168 180)
			(layer "F.Fab")
			(effects
				(font
					(size 0.7 0.7)
					(thickness 0.15)
				)
				(justify left bottom)
			)
		)
		(fp_text user "License: Apache-2.0"
			(at -0.932 5.17 180)
			(layer "F.Fab")
			(effects
				(font
					(size 0.7 0.7)
					(thickness 0.15)
				)
				(justify left bottom)
			)
		)
		(fp_text user "Author: Antmicro"
			(at -0.932 4.17 180)
			(layer "F.Fab")
			(effects
				(font
					(size 0.7 0.7)
					(thickness 0.15)
				)
				(justify left bottom)
			)
		)
		(pad "1" smd roundrect
			(at -0.48 0 180)
			(size 0.59 0.64)
			(layers "F.Cu" "F.Mask" "F.Paste")
			(roundrect_rratio 0.25)
			(net 348 "/FPGA MGT Interface/HDMI_IN.D1_P")
			(pintype "passive")
		)
		(pad "2" smd roundrect
			(at 0.48 0 180)
			(size 0.59 0.64)
			(layers "F.Cu" "F.Mask" "F.Paste")
			(roundrect_rratio 0.25)
			(net 673 "Net-(L3-Pad2)")
			(pintype "passive")
		)
	)
	(footprint "antmicro-footprints:C_0603_1608Metric"
		(layer "F.Cu")
		(at 248.793 153.921 90)
		(descr "Capacitor SMD 0603")
		(tags "capacitor 0603")
		(property "Reference" "C191"
			(at -1.104 -0.993 90)
			(layer "F.SilkS")
			(effects
				(font
					(size 0.7 0.7)
					(thickness 0.15)
				)
				(justify left bottom)
			)
		)
		(property "Value" "C_22u_0603"
			(at -1.42757 1.770288 90)
			(layer "F.Fab")
			(effects
				(font
					(size 0.7 0.7)
					(thickness 0.15)
				)
				(justify left bottom)
			)
		)
		(property "Datasheet" "https://www.murata.com/products/productdetail?partno=GRM188R60J226MEA0%23"
			(at 0 0 90)
			(layer "F.Fab")
			(hide yes)
			(effects
				(font
					(size 1.27 1.27)
					(thickness 0.15)
				)
			)
		)
		(property "Manufacturer" "Murata"
			(at 0 0 90)
			(unlocked yes)
			(layer "F.Fab")
			(hide yes)
			(effects
				(font
					(size 1 1)
					(thickness 0.15)
				)
			)
		)
		(property "MPN" "GRM188R60J226MEA0D"
			(at 0 0 90)
			(unlocked yes)
			(layer "F.Fab")
			(hide yes)
			(effects
				(font
					(size 1 1)
					(thickness 0.15)
				)
			)
		)
		(property "Val" "22u"
			(at 0 0 90)
			(unlocked yes)
			(layer "F.Fab")
			(hide yes)
			(effects
				(font
					(size 1 1)
					(thickness 0.15)
				)
			)
		)
		(property "License" "Apache-2.0"
			(at 0 0 90)
			(unlocked yes)
			(layer "F.Fab")
			(hide yes)
			(effects
				(font
					(size 1 1)
					(thickness 0.15)
				)
			)
		)
		(property "Author" "Antmicro"
			(at 0 0 90)
			(unlocked yes)
			(layer "F.Fab")
			(hide yes)
			(effects
				(font
					(size 1 1)
					(thickness 0.15)
				)
			)
		)
		(property "Voltage" ""
			(at 0 0 90)
			(unlocked yes)
			(layer "F.Fab")
			(hide yes)
			(effects
				(font
					(size 1 1)
					(thickness 0.15)
				)
			)
		)
		(property "Dielectric" ""
			(at 0 0 90)
			(unlocked yes)
			(layer "F.Fab")
			(hide yes)
			(effects
				(font
					(size 1 1)
					(thickness 0.15)
				)
			)
		)
		(sheetname "/Supply/DC-DC IO/")
		(sheetfile "dc-dc-io.kicad_sch")
		(attr smd)
		(fp_line
			(start -0.15 -0.4)
			(end 0.15 -0.4)
			(stroke
				(width 0.15)
				(type solid)
			)
			(layer "F.SilkS")
		)
		(fp_line
			(start -0.15 0.4)
			(end 0.15 0.4)
			(stroke
				(width 0.15)
				(type solid)
			)
			(layer "F.SilkS")
		)
		(fp_rect
			(start -1.25 -0.65)
			(end 1.25 0.65)
			(stroke
				(width 0.05)
				(type solid)
			)
			(fill no)
			(layer "F.CrtYd")
		)
		(fp_rect
			(start -0.8 -0.4)
			(end 0.8 0.4)
			(stroke
				(width 0.15)
				(type solid)
			)
			(fill no)
			(layer "F.Fab")
		)
		(fp_text user "License: Apache-2.0"
			(at -1.682 5.895 90)
			(layer "F.Fab")
			(effects
				(font
					(size 0.7 0.7)
					(thickness 0.15)
				)
				(justify left bottom)
			)
		)
		(fp_text user "Author: Antmicro"
			(at -1.682 4.894 90)
			(layer "F.Fab")
			(effects
				(font
					(size 0.7 0.7)
					(thickness 0.15)
				)
				(justify left bottom)
			)
		)
		(fp_text user "${REFERENCE}"
			(at -1.682 3.895 90)
			(layer "F.Fab")
			(effects
				(font
					(size 0.7 0.7)
					(thickness 0.15)
				)
				(justify left bottom)
			)
		)
		(pad "1" smd roundrect
			(at -0.7 0 90)
			(size 0.8 1)
			(layers "F.Cu" "F.Mask" "F.Paste")
			(roundrect_rratio 0.2)
			(net 1 "GND")
			(pintype "passive")
		)
		(pad "2" smd roundrect
			(at 0.7 0 90)
			(size 0.8 1)
			(layers "F.Cu" "F.Mask" "F.Paste")
			(roundrect_rratio 0.2)
			(net 46 "/Supply/DC-DC IO/5V_local")
			(pintype "passive")
		)
	)
	(footprint "antmicro-footprints:C_0402_1005Metric"
		(layer "F.Cu")
		(at 164.94 161.154999 -90)
		(descr "Capacitor SMD 0402")
		(tags "capacitor SMD 0402")
		(property "Reference" "C288"
			(at -4.105 -0.43 90)
			(layer "F.SilkS")
			(effects
				(font
					(size 0.7 0.7)
					(thickness 0.15)
				)
				(justify right bottom)
			)
		)
		(property "Value" "C_10u_10V_0402"
			(at -1.022927 2.155213 90)
			(layer "F.Fab")
			(effects
				(font
					(size 0.7 0.7)
					(thickness 0.15)
				)
				(justify right bottom)
			)
		)
		(property "Datasheet" "https://www.murata.com/products/productdetail?partno=GRM155R61A106ME11%23"
			(at 0 0 270)
			(layer "F.Fab")
			(hide yes)
			(effects
				(font
					(size 1.27 1.27)
					(thickness 0.15)
				)
			)
		)
		(property "MPN" "GRM155R61A106ME11D"
			(at 0 0 270)
			(unlocked yes)
			(layer "F.Fab")
			(hide yes)
			(effects
				(font
					(size 1 1)
					(thickness 0.15)
				)
			)
		)
		(property "Manufacturer" "Murata"
			(at 0 0 270)
			(unlocked yes)
			(layer "F.Fab")
			(hide yes)
			(effects
				(font
					(size 1 1)
					(thickness 0.15)
				)
			)
		)
		(property "License" "Apache-2.0"
			(at 0 0 270)
			(unlocked yes)
			(layer "F.Fab")
			(hide yes)
			(effects
				(font
					(size 1 1)
					(thickness 0.15)
				)
			)
		)
		(property "Author" "Antmicro"
			(at 0 0 270)
			(unlocked yes)
			(layer "F.Fab")
			(hide yes)
			(effects
				(font
					(size 1 1)
					(thickness 0.15)
				)
			)
		)
		(property "Val" "10u"
			(at 0 0 270)
			(unlocked yes)
			(layer "F.Fab")
			(hide yes)
			(effects
				(font
					(size 1 1)
					(thickness 0.15)
				)
			)
		)
		(property "Voltage" "10V"
			(at 0 0 270)
			(unlocked yes)
			(layer "F.Fab")
			(hide yes)
			(effects
				(font
					(size 1 1)
					(thickness 0.15)
				)
			)
		)
		(property "Dielectric" "X5R"
			(at 0 0 270)
			(unlocked yes)
			(layer "F.Fab")
			(hide yes)
			(effects
				(font
					(size 1 1)
					(thickness 0.15)
				)
			)
		)
		(property "Public" ""
			(at 0 0 270)
			(unlocked yes)
			(layer "F.Fab")
			(hide yes)
			(effects
				(font
					(size 1 1)
					(thickness 0.15)
				)
			)
		)
		(sheetname "/FPGA MGT Interface/")
		(sheetfile "fpga-mgt.kicad_sch")
		(attr smd)
		(fp_rect
			(start -0.925 -0.47)
			(end 0.925 0.47)
			(stroke
				(width 0.05)
				(type default)
			)
			(fill no)
			(layer "F.CrtYd")
		)
		(fp_line
			(start -0.494 0.248)
			(end -0.494 -0.25)
			(stroke
				(width 0.15)
				(type solid)
			)
			(layer "F.Fab")
		)
		(fp_line
			(start 0.504 0.248)
			(end -0.494 0.248)
			(stroke
				(width 0.15)
				(type solid)
			)
			(layer "F.Fab")
		)
		(fp_line
			(start -0.494 -0.25)
			(end 0.504 -0.25)
			(stroke
				(width 0.15)
				(type solid)
			)
			(layer "F.Fab")
		)
		(fp_line
			(start 0.504 -0.25)
			(end 0.504 0.248)
			(stroke
				(width 0.15)
				(type solid)
			)
			(layer "F.Fab")
		)
		(fp_text user "License: Apache-2.0"
			(at -0.939 5.799 270)
			(layer "F.Fab")
			(effects
				(font
					(size 0.7 0.7)
					(thickness 0.15)
				)
				(justify left bottom)
			)
		)
		(fp_text user "${REFERENCE}"
			(at -0.939 4.599 270)
			(layer "F.Fab")
			(effects
				(font
					(size 0.7 0.7)
					(thickness 0.15)
				)
				(justify left bottom)
			)
		)
		(fp_text user "Author: Antmicro"
			(at -0.939 3.399 270)
			(layer "F.Fab")
			(effects
				(font
					(size 0.7 0.7)
					(thickness 0.15)
				)
				(justify left bottom)
			)
		)
		(pad "1" smd roundrect
			(at -0.48 0 270)
			(size 0.59 0.64)
			(layers "F.Cu" "F.Mask" "F.Paste")
			(roundrect_rratio 0.25)
			(net 1 "GND")
			(pintype "passive")
		)
		(pad "2" smd roundrect
			(at 0.48 0 270)
			(size 0.59 0.64)
			(layers "F.Cu" "F.Mask" "F.Paste")
			(roundrect_rratio 0.25)
			(net 151 "+3V3")
			(pintype "passive")
		)
	)
	(footprint "antmicro-footprints:C_0402_1005Metric"
		(layer "F.Cu")
		(at 221.29 179.18 180)
		(descr "Capacitor SMD 0402")
		(tags "capacitor SMD 0402")
		(property "Reference" "C211"
			(at 0.95 -0.42 0)
			(layer "F.SilkS")
			(effects
				(font
					(size 0.7 0.7)
					(thickness 0.15)
				)
				(justify right bottom)
			)
		)
		(property "Value" "C_1u_25V_0402"
			(at -1.022927 2.155213 0)
			(layer "F.Fab")
			(effects
				(font
					(size 0.7 0.7)
					(thickness 0.15)
				)
				(justify right bottom)
			)
		)
		(property "Datasheet" "https://www.murata.com/products/productdetail?partno=GRM155R61E105KE11%23"
			(at 0 0 180)
			(layer "F.Fab")
			(hide yes)
			(effects
				(font
					(size 1.27 1.27)
					(thickness 0.15)
				)
			)
		)
		(property "MPN" "GRM155R61E105KE11J"
			(at 0 0 180)
			(unlocked yes)
			(layer "F.Fab")
			(hide yes)
			(effects
				(font
					(size 1 1)
					(thickness 0.15)
				)
			)
		)
		(property "Manufacturer" "Murata"
			(at 0 0 180)
			(unlocked yes)
			(layer "F.Fab")
			(hide yes)
			(effects
				(font
					(size 1 1)
					(thickness 0.15)
				)
			)
		)
		(property "License" "Apache-2.0"
			(at 0 0 180)
			(unlocked yes)
			(layer "F.Fab")
			(hide yes)
			(effects
				(font
					(size 1 1)
					(thickness 0.15)
				)
			)
		)
		(property "Author" "Antmicro"
			(at 0 0 180)
			(unlocked yes)
			(layer "F.Fab")
			(hide yes)
			(effects
				(font
					(size 1 1)
					(thickness 0.15)
				)
			)
		)
		(property "Val" "1u"
			(at 0 0 180)
			(unlocked yes)
			(layer "F.Fab")
			(hide yes)
			(effects
				(font
					(size 1 1)
					(thickness 0.15)
				)
			)
		)
		(property "Voltage" "25V"
			(at 0 0 180)
			(unlocked yes)
			(layer "F.Fab")
			(hide yes)
			(effects
				(font
					(size 1 1)
					(thickness 0.15)
				)
			)
		)
		(property "Dielectric" "X5R"
			(at 0 0 180)
			(unlocked yes)
			(layer "F.Fab")
			(hide yes)
			(effects
				(font
					(size 1 1)
					(thickness 0.15)
				)
			)
		)
		(sheetname "/Supply/DC-DC VCCINT/")
		(sheetfile "dc-dc-vccint.kicad_sch")
		(attr smd)
		(fp_rect
			(start -0.925 -0.47)
			(end 0.925 0.47)
			(stroke
				(width 0.05)
				(type default)
			)
			(fill no)
			(layer "F.CrtYd")
		)
		(fp_line
			(start 0.504 0.248)
			(end -0.494 0.248)
			(stroke
				(width 0.15)
				(type solid)
			)
			(layer "F.Fab")
		)
		(fp_line
			(start 0.504 -0.25)
			(end 0.504 0.248)
			(stroke
				(width 0.15)
				(type solid)
			)
			(layer "F.Fab")
		)
		(fp_line
			(start -0.494 0.248)
			(end -0.494 -0.25)
			(stroke
				(width 0.15)
				(type solid)
			)
			(layer "F.Fab")
		)
		(fp_line
			(start -0.494 -0.25)
			(end 0.504 -0.25)
			(stroke
				(width 0.15)
				(type solid)
			)
			(layer "F.Fab")
		)
		(fp_text user "${REFERENCE}"
			(at -0.939 4.599 180)
			(layer "F.Fab")
			(effects
				(font
					(size 0.7 0.7)
					(thickness 0.15)
				)
				(justify left bottom)
			)
		)
		(fp_text user "License: Apache-2.0"
			(at -0.939 5.799 180)
			(layer "F.Fab")
			(effects
				(font
					(size 0.7 0.7)
					(thickness 0.15)
				)
				(justify left bottom)
			)
		)
		(fp_text user "Author: Antmicro"
			(at -0.939 3.399 180)
			(layer "F.Fab")
			(effects
				(font
					(size 0.7 0.7)
					(thickness 0.15)
				)
				(justify left bottom)
			)
		)
		(pad "1" smd roundrect
			(at -0.48 0 180)
			(size 0.59 0.64)
			(layers "F.Cu" "F.Mask" "F.Paste")
			(roundrect_rratio 0.25)
			(net 1 "GND")
			(pintype "passive")
		)
		(pad "2" smd roundrect
			(at 0.48 0 180)
			(size 0.59 0.64)
			(layers "F.Cu" "F.Mask" "F.Paste")
			(roundrect_rratio 0.25)
			(net 35 "VDC")
			(pintype "passive")
		)
	)
	(footprint "antmicro-footprints:R_0402_1005Metric"
		(layer "F.Cu")
		(at 114.098 112.732921 -90)
		(descr "Resistor SMD 0402")
		(tags "resistor SMD 0402")
		(property "Reference" "R16"
			(at -3.07 -0.452 90)
			(layer "F.SilkS")
			(effects
				(font
					(size 0.7 0.7)
					(thickness 0.15)
				)
				(justify right bottom)
			)
		)
		(property "Value" "R_4k7_0402"
			(at -1.011843 1.772047 90)
			(layer "F.Fab")
			(effects
				(font
					(size 0.7 0.7)
					(thickness 0.15)
				)
				(justify right bottom)
			)
		)
		(property "Datasheet" "https://www.bourns.com/docs/product-datasheets/cr.pdf"
			(at 0 0 270)
			(layer "F.Fab")
			(hide yes)
			(effects
				(font
					(size 1.27 1.27)
					(thickness 0.15)
				)
			)
		)
		(property "Manufacturer" "Bourns"
			(at 0 0 270)
			(unlocked yes)
			(layer "F.Fab")
			(hide yes)
			(effects
				(font
					(size 1 1)
					(thickness 0.15)
				)
			)
		)
		(property "MPN" "CR0402-FX-4701GLF"
			(at 0 0 270)
			(unlocked yes)
			(layer "F.Fab")
			(hide yes)
			(effects
				(font
					(size 1 1)
					(thickness 0.15)
				)
			)
		)
		(property "Val" "4k7"
			(at 0 0 270)
			(unlocked yes)
			(layer "F.Fab")
			(hide yes)
			(effects
				(font
					(size 1 1)
					(thickness 0.15)
				)
			)
		)
		(property "License" "Apache-2.0"
			(at 0 0 270)
			(unlocked yes)
			(layer "F.Fab")
			(hide yes)
			(effects
				(font
					(size 1 1)
					(thickness 0.15)
				)
			)
		)
		(property "Author" "Antmicro"
			(at 0 0 270)
			(unlocked yes)
			(layer "F.Fab")
			(hide yes)
			(effects
				(font
					(size 1 1)
					(thickness 0.15)
				)
			)
		)
		(property "Tolerance" "1%"
			(at 0 0 270)
			(unlocked yes)
			(layer "F.Fab")
			(hide yes)
			(effects
				(font
					(size 1 1)
					(thickness 0.15)
				)
			)
		)
		(sheetname "/FPGA Config/")
		(sheetfile "fpga-config.kicad_sch")
		(attr smd)
		(fp_rect
			(start -0.925 -0.47)
			(end 0.925 0.47)
			(stroke
				(width 0.05)
				(type default)
			)
			(fill no)
			(layer "F.CrtYd")
		)
		(fp_rect
			(start -0.5 -0.25)
			(end 0.5 0.25)
			(stroke
				(width 0.15)
				(type solid)
			)
			(fill no)
			(layer "F.Fab")
		)
		(fp_text user "${REFERENCE}"
			(at -0.95 3.168 270)
			(layer "F.Fab")
			(effects
				(font
					(size 0.7 0.7)
					(thickness 0.15)
				)
				(justify left bottom)
			)
		)
		(fp_text user "Author: Antmicro"
			(at -0.95 4.169 270)
			(layer "F.Fab")
			(effects
				(font
					(size 0.7 0.7)
					(thickness 0.15)
				)
				(justify left bottom)
			)
		)
		(fp_text user "License: Apache-2.0"
			(at -0.95 5.169 270)
			(layer "F.Fab")
			(effects
				(font
					(size 0.7 0.7)
					(thickness 0.15)
				)
				(justify left bottom)
			)
		)
		(pad "1" smd roundrect
			(at -0.48 0 270)
			(size 0.59 0.64)
			(layers "F.Cu" "F.Mask" "F.Paste")
			(roundrect_rratio 0.25)
			(net 797 "+1V8")
			(pintype "passive")
		)
		(pad "2" smd roundrect
			(at 0.48 0 270)
			(size 0.59 0.64)
			(layers "F.Cu" "F.Mask" "F.Paste")
			(roundrect_rratio 0.25)
			(net 341 "/FPGA Config/INIT_B")
			(pintype "passive")
		)
	)
	(footprint "antmicro-footprints:C_0402_1005Metric"
		(layer "F.Cu")
		(at 131.726 170.552 180)
		(descr "Capacitor SMD 0402")
		(tags "capacitor SMD 0402")
		(property "Reference" "C29"
			(at -0.724 0.552 0)
			(layer "F.SilkS")
			(effects
				(font
					(size 0.7 0.7)
					(thickness 0.15)
				)
				(justify right bottom)
			)
		)
		(property "Value" "C_100n_0402"
			(at -1.022927 2.155213 0)
			(layer "F.Fab")
			(effects
				(font
					(size 0.7 0.7)
					(thickness 0.15)
				)
				(justify right bottom)
			)
		)
		(property "Datasheet" "https://www.murata.com/products/productdetail?partno=GRM155R61H104KE14%23"
			(at 0 0 180)
			(layer "F.Fab")
			(hide yes)
			(effects
				(font
					(size 1.27 1.27)
					(thickness 0.15)
				)
			)
		)
		(property "MPN" "GRM155R61H104KE14D"
			(at 0 0 180)
			(unlocked yes)
			(layer "F.Fab")
			(hide yes)
			(effects
				(font
					(size 1 1)
					(thickness 0.15)
				)
			)
		)
		(property "Manufacturer" "Murata"
			(at 0 0 180)
			(unlocked yes)
			(layer "F.Fab")
			(hide yes)
			(effects
				(font
					(size 1 1)
					(thickness 0.15)
				)
			)
		)
		(property "License" "Apache-2.0"
			(at 0 0 180)
			(unlocked yes)
			(layer "F.Fab")
			(hide yes)
			(effects
				(font
					(size 1 1)
					(thickness 0.15)
				)
			)
		)
		(property "Author" "Antmicro"
			(at 0 0 180)
			(unlocked yes)
			(layer "F.Fab")
			(hide yes)
			(effects
				(font
					(size 1 1)
					(thickness 0.15)
				)
			)
		)
		(property "Val" "100n"
			(at 0 0 180)
			(unlocked yes)
			(layer "F.Fab")
			(hide yes)
			(effects
				(font
					(size 1 1)
					(thickness 0.15)
				)
			)
		)
		(property "Voltage" "50V"
			(at 0 0 180)
			(unlocked yes)
			(layer "F.Fab")
			(hide yes)
			(effects
				(font
					(size 1 1)
					(thickness 0.15)
				)
			)
		)
		(property "Dielectric" "X5R"
			(at 0 0 180)
			(unlocked yes)
			(layer "F.Fab")
			(hide yes)
			(effects
				(font
					(size 1 1)
					(thickness 0.15)
				)
			)
		)
		(property "Public" ""
			(at 0 0 180)
			(unlocked yes)
			(layer "F.Fab")
			(hide yes)
			(effects
				(font
					(size 1 1)
					(thickness 0.15)
				)
			)
		)
		(sheetname "/HDMI + SD Card/")
		(sheetfile "hdmi-sd-card.kicad_sch")
		(attr smd)
		(fp_rect
			(start -0.925 -0.47)
			(end 0.925 0.47)
			(stroke
				(width 0.05)
				(type default)
			)
			(fill no)
			(layer "F.CrtYd")
		)
		(fp_line
			(start 0.504 0.248)
			(end -0.494 0.248)
			(stroke
				(width 0.15)
				(type solid)
			)
			(layer "F.Fab")
		)
		(fp_line
			(start 0.504 -0.25)
			(end 0.504 0.248)
			(stroke
				(width 0.15)
				(type solid)
			)
			(layer "F.Fab")
		)
		(fp_line
			(start -0.494 0.248)
			(end -0.494 -0.25)
			(stroke
				(width 0.15)
				(type solid)
			)
			(layer "F.Fab")
		)
		(fp_line
			(start -0.494 -0.25)
			(end 0.504 -0.25)
			(stroke
				(width 0.15)
				(type solid)
			)
			(layer "F.Fab")
		)
		(fp_text user "${REFERENCE}"
			(at -0.939 4.599 180)
			(layer "F.Fab")
			(effects
				(font
					(size 0.7 0.7)
					(thickness 0.15)
				)
				(justify left bottom)
			)
		)
		(fp_text user "License: Apache-2.0"
			(at -0.939 5.799 180)
			(layer "F.Fab")
			(effects
				(font
					(size 0.7 0.7)
					(thickness 0.15)
				)
				(justify left bottom)
			)
		)
		(fp_text user "Author: Antmicro"
			(at -0.939 3.399 180)
			(layer "F.Fab")
			(effects
				(font
					(size 0.7 0.7)
					(thickness 0.15)
				)
				(justify left bottom)
			)
		)
		(pad "1" smd roundrect
			(at -0.48 0 180)
			(size 0.59 0.64)
			(layers "F.Cu" "F.Mask" "F.Paste")
			(roundrect_rratio 0.25)
			(net 151 "+3V3")
			(pintype "passive")
		)
		(pad "2" smd roundrect
			(at 0.48 0 180)
			(size 0.59 0.64)
			(layers "F.Cu" "F.Mask" "F.Paste")
			(roundrect_rratio 0.25)
			(net 1 "GND")
			(pintype "passive")
		)
	)
	(footprint "antmicro-footprints:C_0402_1005Metric"
		(layer "F.Cu")
		(at 257.79 145.385 -90)
		(descr "Capacitor SMD 0402")
		(tags "capacitor SMD 0402")
		(property "Reference" "C127"
			(at -0.985 0.54 90)
			(layer "F.SilkS")
			(effects
				(font
					(size 0.7 0.7)
					(thickness 0.15)
				)
				(justify right bottom)
			)
		)
		(property "Value" "C_1u_0402"
			(at -1.022927 2.155213 90)
			(layer "F.Fab")
			(effects
				(font
					(size 0.7 0.7)
					(thickness 0.15)
				)
				(justify right bottom)
			)
		)
		(property "Datasheet" "https://product.tdk.com/en/search/capacitor/ceramic/mlcc/info?part_no=C1005X6S1A105K050BC"
			(at 0 0 90)
			(layer "F.Fab")
			(hide yes)
			(effects
				(font
					(size 1.27 1.27)
					(thickness 0.15)
				)
			)
		)
		(property "Manufacturer" "TDK"
			(at 0 0 270)
			(unlocked yes)
			(layer "F.Fab")
			(hide yes)
			(effects
				(font
					(size 1 1)
					(thickness 0.15)
				)
			)
		)
		(property "MPN" "C1005X6S1A105K050BC"
			(at 0 0 270)
			(unlocked yes)
			(layer "F.Fab")
			(hide yes)
			(effects
				(font
					(size 1 1)
					(thickness 0.15)
				)
			)
		)
		(property "Val" "1u"
			(at 0 0 270)
			(unlocked yes)
			(layer "F.Fab")
			(hide yes)
			(effects
				(font
					(size 1 1)
					(thickness 0.15)
				)
			)
		)
		(property "License" "Apache-2.0"
			(at 0 0 270)
			(unlocked yes)
			(layer "F.Fab")
			(hide yes)
			(effects
				(font
					(size 1 1)
					(thickness 0.15)
				)
			)
		)
		(property "Author" "Antmicro"
			(at 0 0 270)
			(unlocked yes)
			(layer "F.Fab")
			(hide yes)
			(effects
				(font
					(size 1 1)
					(thickness 0.15)
				)
			)
		)
		(property "Voltage" ""
			(at 0 0 270)
			(unlocked yes)
			(layer "F.Fab")
			(hide yes)
			(effects
				(font
					(size 1 1)
					(thickness 0.15)
				)
			)
		)
		(property "Dielectric" ""
			(at 0 0 270)
			(unlocked yes)
			(layer "F.Fab")
			(hide yes)
			(effects
				(font
					(size 1 1)
					(thickness 0.15)
				)
			)
		)
		(sheetname "/DDR5 RDIMM/")
		(sheetfile "ddr5-rdimm.kicad_sch")
		(attr smd exclude_from_bom dnp)
		(fp_rect
			(start -0.925 -0.47)
			(end 0.925 0.47)
			(stroke
				(width 0.05)
				(type default)
			)
			(fill no)
			(layer "F.CrtYd")
		)
		(fp_line
			(start -0.494 0.248)
			(end -0.494 -0.25)
			(stroke
				(width 0.15)
				(type solid)
			)
			(layer "F.Fab")
		)
		(fp_line
			(start 0.504 0.248)
			(end -0.494 0.248)
			(stroke
				(width 0.15)
				(type solid)
			)
			(layer "F.Fab")
		)
		(fp_line
			(start -0.494 -0.25)
			(end 0.504 -0.25)
			(stroke
				(width 0.15)
				(type solid)
			)
			(layer "F.Fab")
		)
		(fp_line
			(start 0.504 -0.25)
			(end 0.504 0.248)
			(stroke
				(width 0.15)
				(type solid)
			)
			(layer "F.Fab")
		)
		(fp_text user "Author: Antmicro"
			(at -0.939 3.399 270)
			(layer "F.Fab")
			(effects
				(font
					(size 0.7 0.7)
					(thickness 0.15)
				)
				(justify left bottom)
			)
		)
		(fp_text user "License: Apache-2.0"
			(at -0.939 5.799 270)
			(layer "F.Fab")
			(effects
				(font
					(size 0.7 0.7)
					(thickness 0.15)
				)
				(justify left bottom)
			)
		)
		(fp_text user "${REFERENCE}"
			(at -0.939 4.599 270)
			(layer "F.Fab")
			(effects
				(font
					(size 0.7 0.7)
					(thickness 0.15)
				)
				(justify left bottom)
			)
		)
		(pad "1" smd roundrect
			(at -0.48 0 270)
			(size 0.59 0.64)
			(layers "F.Cu" "F.Mask" "F.Paste")
			(roundrect_rratio 0.25)
			(net 69 "HOT_SWAP_BUTTON")
			(pintype "passive")
		)
		(pad "2" smd roundrect
			(at 0.48 0 270)
			(size 0.59 0.64)
			(layers "F.Cu" "F.Mask" "F.Paste")
			(roundrect_rratio 0.25)
			(net 1 "GND")
			(pintype "passive")
		)
	)
	(footprint "antmicro-footprints:F_1206_3216Metric"
		(layer "F.Cu")
		(at 250.4 124.4 -90)
		(property "Reference" "F1"
			(at -0.6 -2.25 90)
			(layer "F.SilkS")
			(effects
				(font
					(size 0.7 0.7)
					(thickness 0.15)
				)
				(justify right bottom)
			)
		)
		(property "Value" "F_4A_1206"
			(at 0 2 90)
			(layer "F.Fab")
			(effects
				(font
					(size 0.7 0.7)
					(thickness 0.15)
				)
				(justify right bottom)
			)
		)
		(property "Datasheet" "https://www.littelfuse.com/media?resourcetype=datasheets&itemid=dbe9bcd7-6072-4adf-bf5b-d33e52a6b90f&filename=littelfuse-fuse-466-datasheet"
			(at 0 0 90)
			(layer "F.Fab")
			(hide yes)
			(effects
				(font
					(size 1.27 1.27)
					(thickness 0.15)
				)
			)
		)
		(property "Manufacturer" "Littelfuse"
			(at 0 0 270)
			(unlocked yes)
			(layer "F.Fab")
			(hide yes)
			(effects
				(font
					(size 1 1)
					(thickness 0.15)
				)
			)
		)
		(property "MPN" "0466004.NR "
			(at 0 0 270)
			(unlocked yes)
			(layer "F.Fab")
			(hide yes)
			(effects
				(font
					(size 1 1)
					(thickness 0.15)
				)
			)
		)
		(property "Author" "Antmicro"
			(at 0 0 270)
			(unlocked yes)
			(layer "F.Fab")
			(hide yes)
			(effects
				(font
					(size 1 1)
					(thickness 0.15)
				)
			)
		)
		(property "License" "Apache-2.0"
			(at 0 0 270)
			(unlocked yes)
			(layer "F.Fab")
			(hide yes)
			(effects
				(font
					(size 1 1)
					(thickness 0.15)
				)
			)
		)
		(sheetname "/Supply/")
		(sheetfile "supply.kicad_sch")
		(attr smd)
		(fp_line
			(start 0.8 0.901)
			(end -0.8 0.901)
			(stroke
				(width 0.15)
				(type solid)
			)
			(layer "F.SilkS")
		)
		(fp_line
			(start 0.8 -0.899)
			(end -0.8 -0.899)
			(stroke
				(width 0.15)
				(type solid)
			)
			(layer "F.SilkS")
		)
		(fp_rect
			(start -2.325 -1.15)
			(end 2.325 1.15)
			(stroke
				(width 0.05)
				(type default)
			)
			(fill no)
			(layer "F.CrtYd")
		)
		(fp_line
			(start -1.677 0.792)
			(end -1.677 -0.861)
			(stroke
				(width 0.15)
				(type solid)
			)
			(layer "F.Fab")
		)
		(fp_line
			(start 1.624 0.792)
			(end -1.677 0.792)
			(stroke
				(width 0.15)
				(type solid)
			)
			(layer "F.Fab")
		)
		(fp_line
			(start -1.677 -0.861)
			(end 1.624 -0.861)
			(stroke
				(width 0.15)
				(type solid)
			)
			(layer "F.Fab")
		)
		(fp_line
			(start 1.624 -0.861)
			(end 1.624 0.792)
			(stroke
				(width 0.15)
				(type solid)
			)
			(layer "F.Fab")
		)
		(fp_text user "Author: Antmicro"
			(at -1.95 6.4 270)
			(layer "F.Fab")
			(effects
				(font
					(size 0.7 0.7)
					(thickness 0.15)
				)
				(justify left bottom)
			)
		)
		(fp_text user "${REFERENCE}"
			(at -1.95 4 270)
			(layer "F.Fab")
			(effects
				(font
					(size 0.7 0.7)
					(thickness 0.15)
				)
				(justify left bottom)
			)
		)
		(fp_text user "License: Apache-2.0"
			(at -1.95 5.2 270)
			(layer "F.Fab")
			(effects
				(font
					(size 0.7 0.7)
					(thickness 0.15)
				)
				(justify left bottom)
			)
		)
		(pad "1" smd roundrect
			(at -1.5 0.001 270)
			(size 1.15 1.8)
			(layers "F.Cu" "F.Mask" "F.Paste")
			(roundrect_rratio 0.25)
			(net 325 "/Supply/12V_aux")
			(pintype "passive")
		)
		(pad "2" smd roundrect
			(at 1.5 0.001 270)
			(size 1.15 1.8)
			(layers "F.Cu" "F.Mask" "F.Paste")
			(roundrect_rratio 0.25)
			(net 323 "/Supply/12V_aux_fused")
			(pintype "passive")
		)
	)
	(footprint "antmicro-footprints:C_0402_1005Metric"
		(layer "F.Cu")
		(at 243.047 124.356099)
		(descr "Capacitor SMD 0402")
		(tags "capacitor SMD 0402")
		(property "Reference" "C175"
			(at -3.826258 0.453901 0)
			(layer "F.SilkS")
			(effects
				(font
					(size 0.7 0.7)
					(thickness 0.15)
				)
				(justify left bottom)
			)
		)
		(property "Value" "C_100n_0402"
			(at -1.022927 2.155213 0)
			(layer "F.Fab")
			(effects
				(font
					(size 0.7 0.7)
					(thickness 0.15)
				)
				(justify left bottom)
			)
		)
		(property "Datasheet" "https://www.murata.com/products/productdetail?partno=GRM155R61H104KE14%23"
			(at 0 0 0)
			(layer "F.Fab")
			(hide yes)
			(effects
				(font
					(size 1.27 1.27)
					(thickness 0.15)
				)
			)
		)
		(property "Manufacturer" "Murata"
			(at 0 0 0)
			(unlocked yes)
			(layer "F.Fab")
			(hide yes)
			(effects
				(font
					(size 1 1)
					(thickness 0.15)
				)
			)
		)
		(property "MPN" "GRM155R61H104KE14D"
			(at 0 0 0)
			(unlocked yes)
			(layer "F.Fab")
			(hide yes)
			(effects
				(font
					(size 1 1)
					(thickness 0.15)
				)
			)
		)
		(property "Val" "100n"
			(at 0 0 0)
			(unlocked yes)
			(layer "F.Fab")
			(hide yes)
			(effects
				(font
					(size 1 1)
					(thickness 0.15)
				)
			)
		)
		(property "License" "Apache-2.0"
			(at 0 0 0)
			(unlocked yes)
			(layer "F.Fab")
			(hide yes)
			(effects
				(font
					(size 1 1)
					(thickness 0.15)
				)
			)
		)
		(property "Author" "Antmicro"
			(at 0 0 0)
			(unlocked yes)
			(layer "F.Fab")
			(hide yes)
			(effects
				(font
					(size 1 1)
					(thickness 0.15)
				)
			)
		)
		(property "Voltage" "50V"
			(at 0 0 0)
			(unlocked yes)
			(layer "F.Fab")
			(hide yes)
			(effects
				(font
					(size 1 1)
					(thickness 0.15)
				)
			)
		)
		(property "Dielectric" "X5R"
			(at 0 0 0)
			(unlocked yes)
			(layer "F.Fab")
			(hide yes)
			(effects
				(font
					(size 1 1)
					(thickness 0.15)
				)
			)
		)
		(sheetname "/Supply/")
		(sheetfile "supply.kicad_sch")
		(attr smd)
		(fp_rect
			(start -0.925 -0.47)
			(end 0.925 0.47)
			(stroke
				(width 0.05)
				(type default)
			)
			(fill no)
			(layer "F.CrtYd")
		)
		(fp_line
			(start -0.494 -0.25)
			(end 0.504 -0.25)
			(stroke
				(width 0.15)
				(type solid)
			)
			(layer "F.Fab")
		)
		(fp_line
			(start -0.494 0.248)
			(end -0.494 -0.25)
			(stroke
				(width 0.15)
				(type solid)
			)
			(layer "F.Fab")
		)
		(fp_line
			(start 0.504 -0.25)
			(end 0.504 0.248)
			(stroke
				(width 0.15)
				(type solid)
			)
			(layer "F.Fab")
		)
		(fp_line
			(start 0.504 0.248)
			(end -0.494 0.248)
			(stroke
				(width 0.15)
				(type solid)
			)
			(layer "F.Fab")
		)
		(fp_text user "Author: Antmicro"
			(at -0.939 3.399 0)
			(layer "F.Fab")
			(effects
				(font
					(size 0.7 0.7)
					(thickness 0.15)
				)
				(justify left bottom)
			)
		)
		(fp_text user "License: Apache-2.0"
			(at -0.939 5.799 0)
			(layer "F.Fab")
			(effects
				(font
					(size 0.7 0.7)
					(thickness 0.15)
				)
				(justify left bottom)
			)
		)
		(fp_text user "${REFERENCE}"
			(at -0.939 4.599 0)
			(layer "F.Fab")
			(effects
				(font
					(size 0.7 0.7)
					(thickness 0.15)
				)
				(justify left bottom)
			)
		)
		(pad "1" smd roundrect
			(at -0.48 0)
			(size 0.59 0.64)
			(layers "F.Cu" "F.Mask" "F.Paste")
			(roundrect_rratio 0.25)
			(net 1 "GND")
			(pintype "passive")
		)
		(pad "2" smd roundrect
			(at 0.48 0)
			(size 0.59 0.64)
			(layers "F.Cu" "F.Mask" "F.Paste")
			(roundrect_rratio 0.25)
			(net 323 "/Supply/12V_aux_fused")
			(pintype "passive")
		)
	)
	(footprint "antmicro-footprints:C_0603_1608Metric"
		(layer "F.Cu")
		(at 250.35 171.372001 90)
		(descr "Capacitor SMD 0603")
		(tags "capacitor 0603")
		(property "Reference" "C188"
			(at 1.272001 0.35 90)
			(layer "F.SilkS")
			(effects
				(font
					(size 0.7 0.7)
					(thickness 0.15)
				)
				(justify left bottom)
			)
		)
		(property "Value" "C_22u_0603"
			(at -1.42757 1.770288 90)
			(layer "F.Fab")
			(effects
				(font
					(size 0.7 0.7)
					(thickness 0.15)
				)
				(justify left bottom)
			)
		)
		(property "Datasheet" "https://www.murata.com/products/productdetail?partno=GRM188R60J226MEA0%23"
			(at 0 0 90)
			(layer "F.Fab")
			(hide yes)
			(effects
				(font
					(size 1.27 1.27)
					(thickness 0.15)
				)
			)
		)
		(property "Manufacturer" "Murata"
			(at 0 0 90)
			(unlocked yes)
			(layer "F.Fab")
			(hide yes)
			(effects
				(font
					(size 1 1)
					(thickness 0.15)
				)
			)
		)
		(property "MPN" "GRM188R60J226MEA0D"
			(at 0 0 90)
			(unlocked yes)
			(layer "F.Fab")
			(hide yes)
			(effects
				(font
					(size 1 1)
					(thickness 0.15)
				)
			)
		)
		(property "Val" "22u"
			(at 0 0 90)
			(unlocked yes)
			(layer "F.Fab")
			(hide yes)
			(effects
				(font
					(size 1 1)
					(thickness 0.15)
				)
			)
		)
		(property "License" "Apache-2.0"
			(at 0 0 90)
			(unlocked yes)
			(layer "F.Fab")
			(hide yes)
			(effects
				(font
					(size 1 1)
					(thickness 0.15)
				)
			)
		)
		(property "Author" "Antmicro"
			(at 0 0 90)
			(unlocked yes)
			(layer "F.Fab")
			(hide yes)
			(effects
				(font
					(size 1 1)
					(thickness 0.15)
				)
			)
		)
		(property "Voltage" ""
			(at 0 0 90)
			(unlocked yes)
			(layer "F.Fab")
			(hide yes)
			(effects
				(font
					(size 1 1)
					(thickness 0.15)
				)
			)
		)
		(property "Dielectric" ""
			(at 0 0 90)
			(unlocked yes)
			(layer "F.Fab")
			(hide yes)
			(effects
				(font
					(size 1 1)
					(thickness 0.15)
				)
			)
		)
		(sheetname "/Supply/DC-DC AUX, MGT/")
		(sheetfile "dc-dc-aux-mgt.kicad_sch")
		(attr smd)
		(fp_line
			(start -0.15 -0.4)
			(end 0.15 -0.4)
			(stroke
				(width 0.15)
				(type solid)
			)
			(layer "F.SilkS")
		)
		(fp_line
			(start -0.15 0.4)
			(end 0.15 0.4)
			(stroke
				(width 0.15)
				(type solid)
			)
			(layer "F.SilkS")
		)
		(fp_rect
			(start -1.25 -0.65)
			(end 1.25 0.65)
			(stroke
				(width 0.05)
				(type solid)
			)
			(fill no)
			(layer "F.CrtYd")
		)
		(fp_rect
			(start -0.8 -0.4)
			(end 0.8 0.4)
			(stroke
				(width 0.15)
				(type solid)
			)
			(fill no)
			(layer "F.Fab")
		)
		(fp_text user "${REFERENCE}"
			(at -1.682 3.895 90)
			(layer "F.Fab")
			(effects
				(font
					(size 0.7 0.7)
					(thickness 0.15)
				)
				(justify left bottom)
			)
		)
		(fp_text user "License: Apache-2.0"
			(at -1.682 5.895 90)
			(layer "F.Fab")
			(effects
				(font
					(size 0.7 0.7)
					(thickness 0.15)
				)
				(justify left bottom)
			)
		)
		(fp_text user "Author: Antmicro"
			(at -1.682 4.894 90)
			(layer "F.Fab")
			(effects
				(font
					(size 0.7 0.7)
					(thickness 0.15)
				)
				(justify left bottom)
			)
		)
		(pad "1" smd roundrect
			(at -0.7 0 90)
			(size 0.8 1)
			(layers "F.Cu" "F.Mask" "F.Paste")
			(roundrect_rratio 0.2)
			(net 1 "GND")
			(pintype "passive")
		)
		(pad "2" smd roundrect
			(at 0.7 0 90)
			(size 0.8 1)
			(layers "F.Cu" "F.Mask" "F.Paste")
			(roundrect_rratio 0.2)
			(net 48 "/Supply/DC-DC AUX, MGT/MGTAVTT_local")
			(pintype "passive")
		)
	)
	(footprint "antmicro-footprints:TP_SMD_1mm"
		(layer "F.Cu")
		(at 244.025 161.95)
		(property "Reference" "TP11"
			(at 0 -0.731898 0)
			(layer "F.SilkS")
			(hide yes)
			(effects
				(font
					(size 0.7 0.7)
					(thickness 0.15)
				)
				(justify left bottom)
			)
		)
		(property "Value" "TP_1mm_SMD"
			(at 0 1.4 0)
			(layer "F.Fab")
			(effects
				(font
					(size 0.7 0.7)
					(thickness 0.15)
				)
				(justify left bottom)
			)
		)
		(property "MPN" ""
			(at 0 0 0)
			(unlocked yes)
			(layer "F.Fab")
			(hide yes)
			(effects
				(font
					(size 1 1)
					(thickness 0.15)
				)
			)
		)
		(property "Manufacturer" ""
			(at 0 0 0)
			(unlocked yes)
			(layer "F.Fab")
			(hide yes)
			(effects
				(font
					(size 1 1)
					(thickness 0.15)
				)
			)
		)
		(property "Author" "Antmicro"
			(at 0 0 0)
			(unlocked yes)
			(layer "F.Fab")
			(hide yes)
			(effects
				(font
					(size 1 1)
					(thickness 0.15)
				)
			)
		)
		(property "License" "Apache-2.0"
			(at 0 0 0)
			(unlocked yes)
			(layer "F.Fab")
			(hide yes)
			(effects
				(font
					(size 1 1)
					(thickness 0.15)
				)
			)
		)
		(sheetname "/Supply/DC-DC IO/")
		(sheetfile "dc-dc-io.kicad_sch")
		(attr exclude_from_pos_files)
		(fp_circle
			(center 0 0)
			(end 0.6 0)
			(stroke
				(width 0.05)
				(type default)
			)
			(fill no)
			(layer "F.CrtYd")
		)
		(fp_text user "Author: Antmicro"
			(at -0.5 4 0)
			(layer "F.Fab")
			(effects
				(font
					(size 0.7 0.7)
					(thickness 0.15)
				)
				(justify left bottom)
			)
		)
		(fp_text user "License: Apache-2.0"
			(at -0.5 5.2 0)
			(layer "F.Fab")
			(effects
				(font
					(size 0.7 0.7)
					(thickness 0.15)
				)
				(justify left bottom)
			)
		)
		(fp_text user "${REFERENCE}"
			(at -0.5 2.8 0)
			(layer "F.Fab")
			(effects
				(font
					(size 0.7 0.7)
					(thickness 0.15)
				)
				(justify left bottom)
			)
		)
		(pad "1" smd circle
			(at 0 0)
			(size 1 1)
			(layers "F.Cu" "F.Mask")
			(net 150 "+1V2")
			(pinfunction "1")
			(pintype "passive")
		)
	)
	(footprint "antmicro-footprints:R_0402_1005Metric"
		(layer "F.Cu")
		(at 225.881 180.65 -90)
		(descr "Resistor SMD 0402")
		(tags "resistor SMD 0402")
		(property "Reference" "R198"
			(at 1.25 -0.399 90)
			(layer "F.SilkS")
			(effects
				(font
					(size 0.7 0.7)
					(thickness 0.15)
				)
				(justify right bottom)
			)
		)
		(property "Value" "R_10R_0402"
			(at -1.011843 1.772047 90)
			(layer "F.Fab")
			(effects
				(font
					(size 0.7 0.7)
					(thickness 0.15)
				)
				(justify right bottom)
			)
		)
		(property "Datasheet" "https://www.bourns.com/docs/product-datasheets/cr.pdf"
			(at 0 0 270)
			(layer "F.Fab")
			(hide yes)
			(effects
				(font
					(size 1.27 1.27)
					(thickness 0.15)
				)
			)
		)
		(property "MPN" "CR0402-FX-10R0GLF"
			(at 0 0 270)
			(unlocked yes)
			(layer "F.Fab")
			(hide yes)
			(effects
				(font
					(size 1 1)
					(thickness 0.15)
				)
			)
		)
		(property "Manufacturer" "Bourns"
			(at 0 0 270)
			(unlocked yes)
			(layer "F.Fab")
			(hide yes)
			(effects
				(font
					(size 1 1)
					(thickness 0.15)
				)
			)
		)
		(property "License" "Apache-2.0"
			(at 0 0 270)
			(unlocked yes)
			(layer "F.Fab")
			(hide yes)
			(effects
				(font
					(size 1 1)
					(thickness 0.15)
				)
			)
		)
		(property "Author" "Antmicro"
			(at 0 0 270)
			(unlocked yes)
			(layer "F.Fab")
			(hide yes)
			(effects
				(font
					(size 1 1)
					(thickness 0.15)
				)
			)
		)
		(property "Val" "10R"
			(at 0 0 270)
			(unlocked yes)
			(layer "F.Fab")
			(hide yes)
			(effects
				(font
					(size 1 1)
					(thickness 0.15)
				)
			)
		)
		(property "Tolerance" "1%"
			(at 0 0 270)
			(unlocked yes)
			(layer "F.Fab")
			(hide yes)
			(effects
				(font
					(size 1 1)
					(thickness 0.15)
				)
			)
		)
		(sheetname "/Supply/DC-DC VCCINT/")
		(sheetfile "dc-dc-vccint.kicad_sch")
		(attr smd)
		(fp_rect
			(start -0.925 -0.47)
			(end 0.925 0.47)
			(stroke
				(width 0.05)
				(type default)
			)
			(fill no)
			(layer "F.CrtYd")
		)
		(fp_rect
			(start -0.5 -0.25)
			(end 0.5 0.25)
			(stroke
				(width 0.15)
				(type solid)
			)
			(fill no)
			(layer "F.Fab")
		)
		(fp_text user "Author: Antmicro"
			(at -0.95 4.169 270)
			(layer "F.Fab")
			(effects
				(font
					(size 0.7 0.7)
					(thickness 0.15)
				)
				(justify left bottom)
			)
		)
		(fp_text user "${REFERENCE}"
			(at -0.95 3.168 270)
			(layer "F.Fab")
			(effects
				(font
					(size 0.7 0.7)
					(thickness 0.15)
				)
				(justify left bottom)
			)
		)
		(fp_text user "License: Apache-2.0"
			(at -0.95 5.169 270)
			(layer "F.Fab")
			(effects
				(font
					(size 0.7 0.7)
					(thickness 0.15)
				)
				(justify left bottom)
			)
		)
		(pad "1" smd roundrect
			(at -0.48 0 270)
			(size 0.59 0.64)
			(layers "F.Cu" "F.Mask" "F.Paste")
			(roundrect_rratio 0.25)
			(net 49 "Net-(U36-V_{DRV})")
			(pintype "passive")
		)
		(pad "2" smd roundrect
			(at 0.48 0 270)
			(size 0.59 0.64)
			(layers "F.Cu" "F.Mask" "F.Paste")
			(roundrect_rratio 0.25)
			(net 163 "/Supply/DC-DC VCCINT/V_{CC}")
			(pintype "passive")
		)
	)
	(footprint "antmicro-footprints:R_0402_1005Metric"
		(layer "F.Cu")
		(at 124.681 166.1125 90)
		(descr "Resistor SMD 0402")
		(tags "resistor SMD 0402")
		(property "Reference" "R227"
			(at 0.9125 3.969 90)
			(layer "F.SilkS")
			(effects
				(font
					(size 0.7 0.7)
					(thickness 0.15)
				)
				(justify left bottom)
			)
		)
		(property "Value" "R_64k9_0402"
			(at -1.011843 1.772047 90)
			(layer "F.Fab")
			(effects
				(font
					(size 0.7 0.7)
					(thickness 0.15)
				)
				(justify left bottom)
			)
		)
		(property "Datasheet" "https://www.bourns.com/docs/product-datasheets/cr.pdf"
			(at 0 0 90)
			(layer "F.Fab")
			(hide yes)
			(effects
				(font
					(size 1.27 1.27)
					(thickness 0.15)
				)
			)
		)
		(property "MPN" "CR0402-FX-6492GLF"
			(at 0 0 90)
			(unlocked yes)
			(layer "F.Fab")
			(hide yes)
			(effects
				(font
					(size 1 1)
					(thickness 0.15)
				)
			)
		)
		(property "Manufacturer" "Bourns"
			(at 0 0 90)
			(unlocked yes)
			(layer "F.Fab")
			(hide yes)
			(effects
				(font
					(size 1 1)
					(thickness 0.15)
				)
			)
		)
		(property "License" "Apache-2.0"
			(at 0 0 90)
			(unlocked yes)
			(layer "F.Fab")
			(hide yes)
			(effects
				(font
					(size 1 1)
					(thickness 0.15)
				)
			)
		)
		(property "Author" "Antmicro"
			(at 0 0 90)
			(unlocked yes)
			(layer "F.Fab")
			(hide yes)
			(effects
				(font
					(size 1 1)
					(thickness 0.15)
				)
			)
		)
		(property "Val" "64k9"
			(at 0 0 90)
			(unlocked yes)
			(layer "F.Fab")
			(hide yes)
			(effects
				(font
					(size 1 1)
					(thickness 0.15)
				)
			)
		)
		(property "Tolerance" "1%"
			(at 0 0 90)
			(unlocked yes)
			(layer "F.Fab")
			(hide yes)
			(effects
				(font
					(size 1 1)
					(thickness 0.15)
				)
			)
		)
		(sheetname "/HDMI + SD Card/")
		(sheetfile "hdmi-sd-card.kicad_sch")
		(attr smd exclude_from_bom dnp)
		(fp_rect
			(start -0.925 -0.47)
			(end 0.925 0.47)
			(stroke
				(width 0.05)
				(type default)
			)
			(fill no)
			(layer "F.CrtYd")
		)
		(fp_rect
			(start -0.5 -0.25)
			(end 0.5 0.25)
			(stroke
				(width 0.15)
				(type solid)
			)
			(fill no)
			(layer "F.Fab")
		)
		(fp_text user "${REFERENCE}"
			(at -0.95 3.168 90)
			(layer "F.Fab")
			(effects
				(font
					(size 0.7 0.7)
					(thickness 0.15)
				)
				(justify left bottom)
			)
		)
		(fp_text user "License: Apache-2.0"
			(at -0.95 5.169 90)
			(layer "F.Fab")
			(effects
				(font
					(size 0.7 0.7)
					(thickness 0.15)
				)
				(justify left bottom)
			)
		)
		(fp_text user "Author: Antmicro"
			(at -0.95 4.169 90)
			(layer "F.Fab")
			(effects
				(font
					(size 0.7 0.7)
					(thickness 0.15)
				)
				(justify left bottom)
			)
		)
		(pad "1" smd roundrect
			(at -0.48 0 90)
			(size 0.59 0.64)
			(layers "F.Cu" "F.Mask" "F.Paste")
			(roundrect_rratio 0.25)
			(net 737 "/HDMI + SD Card/EQ_SEL")
			(pintype "passive")
		)
		(pad "2" smd roundrect
			(at 0.48 0 90)
			(size 0.59 0.64)
			(layers "F.Cu" "F.Mask" "F.Paste")
			(roundrect_rratio 0.25)
			(net 151 "+3V3")
			(pintype "passive")
		)
	)
	(footprint "antmicro-footprints:C_0402_1005Metric"
		(layer "F.Cu")
		(at 250.4 120.7 -90)
		(descr "Capacitor SMD 0402")
		(tags "capacitor SMD 0402")
		(property "Reference" "C169"
			(at -1.375501 -0.649 90)
			(layer "F.SilkS")
			(effects
				(font
					(size 0.7 0.7)
					(thickness 0.15)
				)
				(justify right top)
			)
		)
		(property "Value" "C_100n_0402"
			(at -1.022927 2.155213 90)
			(layer "F.Fab")
			(effects
				(font
					(size 0.7 0.7)
					(thickness 0.15)
				)
				(justify right top)
			)
		)
		(property "Datasheet" "https://www.murata.com/products/productdetail?partno=GRM155R61H104KE14%23"
			(at 0 0 90)
			(layer "F.Fab")
			(hide yes)
			(effects
				(font
					(size 1.27 1.27)
					(thickness 0.15)
				)
			)
		)
		(property "Manufacturer" "Murata"
			(at 0 0 270)
			(unlocked yes)
			(layer "F.Fab")
			(hide yes)
			(effects
				(font
					(size 1 1)
					(thickness 0.15)
				)
			)
		)
		(property "MPN" "GRM155R61H104KE14D"
			(at 0 0 270)
			(unlocked yes)
			(layer "F.Fab")
			(hide yes)
			(effects
				(font
					(size 1 1)
					(thickness 0.15)
				)
			)
		)
		(property "Val" "100n"
			(at 0 0 270)
			(unlocked yes)
			(layer "F.Fab")
			(hide yes)
			(effects
				(font
					(size 1 1)
					(thickness 0.15)
				)
			)
		)
		(property "License" "Apache-2.0"
			(at 0 0 270)
			(unlocked yes)
			(layer "F.Fab")
			(hide yes)
			(effects
				(font
					(size 1 1)
					(thickness 0.15)
				)
			)
		)
		(property "Author" "Antmicro"
			(at 0 0 270)
			(unlocked yes)
			(layer "F.Fab")
			(hide yes)
			(effects
				(font
					(size 1 1)
					(thickness 0.15)
				)
			)
		)
		(property "Voltage" "50V"
			(at 0 0 270)
			(unlocked yes)
			(layer "F.Fab")
			(hide yes)
			(effects
				(font
					(size 1 1)
					(thickness 0.15)
				)
			)
		)
		(property "Dielectric" "X5R"
			(at 0 0 270)
			(unlocked yes)
			(layer "F.Fab")
			(hide yes)
			(effects
				(font
					(size 1 1)
					(thickness 0.15)
				)
			)
		)
		(sheetname "/Supply/")
		(sheetfile "supply.kicad_sch")
		(attr smd)
		(fp_rect
			(start -0.925 -0.47)
			(end 0.925 0.47)
			(stroke
				(width 0.05)
				(type default)
			)
			(fill no)
			(layer "F.CrtYd")
		)
		(fp_line
			(start -0.494 0.248)
			(end -0.494 -0.25)
			(stroke
				(width 0.15)
				(type solid)
			)
			(layer "F.Fab")
		)
		(fp_line
			(start 0.504 0.248)
			(end -0.494 0.248)
			(stroke
				(width 0.15)
				(type solid)
			)
			(layer "F.Fab")
		)
		(fp_line
			(start -0.494 -0.25)
			(end 0.504 -0.25)
			(stroke
				(width 0.15)
				(type solid)
			)
			(layer "F.Fab")
		)
		(fp_line
			(start 0.504 -0.25)
			(end 0.504 0.248)
			(stroke
				(width 0.15)
				(type solid)
			)
			(layer "F.Fab")
		)
		(fp_text user "Author: Antmicro"
			(at -0.939 3.399 270)
			(layer "F.Fab")
			(effects
				(font
					(size 0.7 0.7)
					(thickness 0.15)
				)
				(justify left bottom)
			)
		)
		(fp_text user "${REFERENCE}"
			(at -0.939 4.599 270)
			(layer "F.Fab")
			(effects
				(font
					(size 0.7 0.7)
					(thickness 0.15)
				)
				(justify left bottom)
			)
		)
		(fp_text user "License: Apache-2.0"
			(at -0.939 5.799 270)
			(layer "F.Fab")
			(effects
				(font
					(size 0.7 0.7)
					(thickness 0.15)
				)
				(justify left bottom)
			)
		)
		(pad "1" smd roundrect
			(at -0.48 0 270)
			(size 0.59 0.64)
			(layers "F.Cu" "F.Mask" "F.Paste")
			(roundrect_rratio 0.25)
			(net 1 "GND")
			(pintype "passive")
		)
		(pad "2" smd roundrect
			(at 0.48 0 270)
			(size 0.59 0.64)
			(layers "F.Cu" "F.Mask" "F.Paste")
			(roundrect_rratio 0.25)
			(net 325 "/Supply/12V_aux")
			(pintype "passive")
		)
	)
	(footprint "antmicro-footprints:R_0805_2012Metric"
		(layer "F.Cu")
		(at 257.125 165.621 180)
		(property "Reference" "R144"
			(at 5.375 -0.029 180)
			(layer "F.SilkS")
			(effects
				(font
					(size 0.7 0.7)
					(thickness 0.15)
				)
				(justify left bottom)
			)
		)
		(property "Value" "R_0R002_0805"
			(at 0 1.8 180)
			(layer "F.Fab")
			(effects
				(font
					(size 0.7 0.7)
					(thickness 0.15)
				)
				(justify left bottom)
			)
		)
		(property "Datasheet" "https://www2.mouser.com/datasheet/2/447/PYu_PA0100_2512_51_RoHS_2-2604383.pdf"
			(at 0 0 180)
			(layer "F.Fab")
			(hide yes)
			(effects
				(font
					(size 1.27 1.27)
					(thickness 0.15)
				)
			)
		)
		(property "MPN" "PA0805FRE470R002L"
			(at 0 0 180)
			(unlocked yes)
			(layer "F.Fab")
			(hide yes)
			(effects
				(font
					(size 1 1)
					(thickness 0.15)
				)
			)
		)
		(property "Manufacturer" "YAGEO"
			(at 0 0 180)
			(unlocked yes)
			(layer "F.Fab")
			(hide yes)
			(effects
				(font
					(size 1 1)
					(thickness 0.15)
				)
			)
		)
		(property "License" "Apache-2.0"
			(at 0 0 180)
			(unlocked yes)
			(layer "F.Fab")
			(hide yes)
			(effects
				(font
					(size 1 1)
					(thickness 0.15)
				)
			)
		)
		(property "Author" "Antmicro"
			(at 0 0 180)
			(unlocked yes)
			(layer "F.Fab")
			(hide yes)
			(effects
				(font
					(size 1 1)
					(thickness 0.15)
				)
			)
		)
		(property "Val" "0R002"
			(at 0 0 180)
			(unlocked yes)
			(layer "F.Fab")
			(hide yes)
			(effects
				(font
					(size 1 1)
					(thickness 0.15)
				)
			)
		)
		(property "Tolerance" "1%"
			(at 0 0 180)
			(unlocked yes)
			(layer "F.Fab")
			(hide yes)
			(effects
				(font
					(size 1 1)
					(thickness 0.15)
				)
			)
		)
		(sheetname "/Supply/DC-DC AUX, MGT/")
		(sheetfile "dc-dc-aux-mgt.kicad_sch")
		(attr smd)
		(fp_line
			(start -0.3 -0.701)
			(end 0.298 -0.701)
			(stroke
				(width 0.15)
				(type solid)
			)
			(layer "F.SilkS")
		)
		(fp_line
			(start -0.32 0.699)
			(end 0.28 0.699)
			(stroke
				(width 0.15)
				(type solid)
			)
			(layer "F.SilkS")
		)
		(fp_rect
			(start 1.95 -0.9)
			(end -1.95 0.9)
			(stroke
				(width 0.05)
				(type default)
			)
			(fill no)
			(layer "F.CrtYd")
		)
		(fp_line
			(start 0.949 -0.677)
			(end 0.949 0.675)
			(stroke
				(width 0.15)
				(type solid)
			)
			(layer "F.Fab")
		)
		(fp_line
			(start -0.951 0.68)
			(end 0.949 0.68)
			(stroke
				(width 0.15)
				(type solid)
			)
			(layer "F.Fab")
		)
		(fp_line
			(start -0.951 -0.677)
			(end -0.951 0.675)
			(stroke
				(width 0.15)
				(type solid)
			)
			(layer "F.Fab")
		)
		(fp_line
			(start -0.951 -0.682)
			(end 0.949 -0.682)
			(stroke
				(width 0.15)
				(type solid)
			)
			(layer "F.Fab")
		)
		(fp_text user "Author: Antmicro"
			(at -1.9 4.4 180)
			(layer "F.Fab")
			(effects
				(font
					(size 0.7 0.7)
					(thickness 0.15)
				)
				(justify left bottom)
			)
		)
		(fp_text user "${REFERENCE}"
			(at -1.9 3.1 180)
			(layer "F.Fab")
			(effects
				(font
					(size 0.7 0.7)
					(thickness 0.15)
				)
				(justify left bottom)
			)
		)
		(fp_text user "License: Apache-2.0"
			(at -1.9 5.75 180)
			(layer "F.Fab")
			(effects
				(font
					(size 0.7 0.7)
					(thickness 0.15)
				)
				(justify left bottom)
			)
		)
		(pad "1" smd roundrect
			(at -1.1 0 180)
			(size 1.2 1.3)
			(layers "F.Cu" "F.Mask" "F.Paste")
			(roundrect_rratio 0.25)
			(net 47 "/Supply/DC-DC AUX, MGT/MGTAVCC_local")
			(pintype "passive")
		)
		(pad "2" smd roundrect
			(at 1.1 0 180)
			(size 1.2 1.3)
			(layers "F.Cu" "F.Mask" "F.Paste")
			(roundrect_rratio 0.25)
			(net 820 "+0V9_MGTAVCC")
			(pintype "passive")
		)
	)
	(footprint "antmicro-footprints:SW_KMR211NGLFS_SMD"
		(layer "F.Cu")
		(at 260.573 130.551499 -90)
		(property "Reference" "SW5"
			(at 1.1 2.05 90)
			(layer "F.SilkS")
			(hide yes)
			(effects
				(font
					(size 0.7 0.7)
					(thickness 0.15)
				)
				(justify right bottom)
			)
		)
		(property "Value" "SW_KMR211NGLFS_SMD"
			(at 0 2.8 90)
			(layer "F.Fab")
			(effects
				(font
					(size 0.7 0.7)
					(thickness 0.15)
				)
				(justify right bottom)
			)
		)
		(property "Datasheet" "http://www.farnell.com/datasheets/2631211.pdf"
			(at 0 0 270)
			(layer "F.Fab")
			(hide yes)
			(effects
				(font
					(size 1.27 1.27)
					(thickness 0.15)
				)
			)
		)
		(property "MPN" "KMR211NGLFS"
			(at 0 0 270)
			(unlocked yes)
			(layer "F.Fab")
			(hide yes)
			(effects
				(font
					(size 1 1)
					(thickness 0.15)
				)
			)
		)
		(property "Manufacturer" "C&K"
			(at 0 0 270)
			(unlocked yes)
			(layer "F.Fab")
			(hide yes)
			(effects
				(font
					(size 1 1)
					(thickness 0.15)
				)
			)
		)
		(property "Author" "Antmicro"
			(at 0 0 270)
			(unlocked yes)
			(layer "F.Fab")
			(hide yes)
			(effects
				(font
					(size 1 1)
					(thickness 0.15)
				)
			)
		)
		(property "License" "Apache-2.0"
			(at 0 0 270)
			(unlocked yes)
			(layer "F.Fab")
			(hide yes)
			(effects
				(font
					(size 1 1)
					(thickness 0.15)
				)
			)
		)
		(sheetname "/Supply/")
		(sheetfile "supply.kicad_sch")
		(attr smd)
		(fp_line
			(start -2.1 1.601)
			(end -2.1 1.48)
			(stroke
				(width 0.15)
				(type solid)
			)
			(layer "F.SilkS")
		)
		(fp_line
			(start 2.101 1.601)
			(end -2.1 1.601)
			(stroke
				(width 0.15)
				(type solid)
			)
			(layer "F.SilkS")
		)
		(fp_line
			(start 2.101 1.601)
			(end 2.101 1.48)
			(stroke
				(width 0.15)
				(type solid)
			)
			(layer "F.SilkS")
		)
		(fp_line
			(start 2.101 -1.58)
			(end 2.101 -1.459)
			(stroke
				(width 0.15)
				(type solid)
			)
			(layer "F.SilkS")
		)
		(fp_line
			(start -2.1 -1.6)
			(end -2.1 -1.499)
			(stroke
				(width 0.15)
				(type solid)
			)
			(layer "F.SilkS")
		)
		(fp_line
			(start 2.101 -1.6)
			(end -2.1 -1.6)
			(stroke
				(width 0.15)
				(type solid)
			)
			(layer "F.SilkS")
		)
		(fp_rect
			(start 2.751 1.75)
			(end -2.748 -1.749)
			(stroke
				(width 0.05)
				(type solid)
			)
			(fill no)
			(layer "F.CrtYd")
		)
		(fp_line
			(start -2.1 1.601)
			(end 2.101 1.601)
			(stroke
				(width 0.15)
				(type solid)
			)
			(layer "F.Fab")
		)
		(fp_line
			(start 2.101 1.601)
			(end 2.101 -1.6)
			(stroke
				(width 0.15)
				(type solid)
			)
			(layer "F.Fab")
		)
		(fp_line
			(start 0.25 0.802)
			(end -0.248 0.802)
			(stroke
				(width 0.15)
				(type solid)
			)
			(layer "F.Fab")
		)
		(fp_line
			(start -0.248 -0.8)
			(end 0.25 -0.8)
			(stroke
				(width 0.15)
				(type solid)
			)
			(layer "F.Fab")
		)
		(fp_line
			(start -2.1 -1.6)
			(end -2.1 1.601)
			(stroke
				(width 0.15)
				(type solid)
			)
			(layer "F.Fab")
		)
		(fp_line
			(start 2.101 -1.6)
			(end -2.1 -1.6)
			(stroke
				(width 0.15)
				(type solid)
			)
			(layer "F.Fab")
		)
		(fp_arc
			(start -0.248 0.802)
			(mid -1.050001 0.001)
			(end -0.248 -0.8)
			(stroke
				(width 0.15)
				(type solid)
			)
			(layer "F.Fab")
		)
		(fp_arc
			(start 0.25 -0.8)
			(mid 1.051001 0.001)
			(end 0.25 0.802)
			(stroke
				(width 0.15)
				(type solid)
			)
			(layer "F.Fab")
		)
		(fp_text user "${REFERENCE}"
			(at -3 4.25 270)
			(layer "F.Fab")
			(effects
				(font
					(size 0.7 0.7)
					(thickness 0.15)
				)
				(justify left bottom)
			)
		)
		(fp_text user "Author: Antmicro"
			(at -3 5.5 270)
			(layer "F.Fab")
			(effects
				(font
					(size 0.7 0.7)
					(thickness 0.15)
				)
				(justify left bottom)
			)
		)
		(fp_text user "License: Apache-2.0"
			(at -3 6.75 270)
			(layer "F.Fab")
			(effects
				(font
					(size 0.7 0.7)
					(thickness 0.15)
				)
				(justify left bottom)
			)
		)
		(pad "1" smd rect
			(at -2.048 -0.8 90)
			(size 0.9 1)
			(layers "F.Cu" "F.Mask" "F.Paste")
			(net 1 "GND")
			(pinfunction "1")
			(pintype "passive")
		)
		(pad "2" smd rect
			(at 2.05 -0.8 90)
			(size 0.9 1)
			(layers "F.Cu" "F.Mask" "F.Paste")
			(net 1 "GND")
			(pinfunction "2")
			(pintype "passive")
		)
		(pad "3" smd rect
			(at -2.048 0.802 90)
			(size 0.9 1)
			(layers "F.Cu" "F.Mask" "F.Paste")
			(net 189 "/Supply/~{PB_CTRL_IN}")
			(pinfunction "3")
			(pintype "passive")
		)
		(pad "4" smd rect
			(at 2.05 0.802 90)
			(size 0.9 1)
			(layers "F.Cu" "F.Mask" "F.Paste")
			(net 189 "/Supply/~{PB_CTRL_IN}")
			(pinfunction "4")
			(pintype "passive")
		)
	)
	(footprint "antmicro-footprints:R_1206_3216Metric"
		(layer "F.Cu")
		(at 257.124499 162.424 180)
		(property "Reference" "R148"
			(at 2.524499 -0.426 0)
			(layer "F.SilkS")
			(effects
				(font
					(size 0.7 0.7)
					(thickness 0.15)
				)
				(justify right bottom)
			)
		)
		(property "Value" "R_0R01_1206"
			(at -2.422356 2.103591 0)
			(layer "F.Fab")
			(effects
				(font
					(size 0.7 0.7)
					(thickness 0.15)
				)
				(justify right bottom)
			)
		)
		(property "Datasheet" "https://www.yageo.com/upload/media/product/productsearch/datasheet/rchip/PYu-RL_Group_521_RoHS_L_2.pdf"
			(at 0 0 180)
			(layer "F.Fab")
			(hide yes)
			(effects
				(font
					(size 1.27 1.27)
					(thickness 0.15)
				)
			)
		)
		(property "Manufacturer" "YAGEO"
			(at 0 0 180)
			(unlocked yes)
			(layer "F.Fab")
			(hide yes)
			(effects
				(font
					(size 1 1)
					(thickness 0.15)
				)
			)
		)
		(property "MPN" "RL1206FR-7W0R01L"
			(at 0 0 180)
			(unlocked yes)
			(layer "F.Fab")
			(hide yes)
			(effects
				(font
					(size 1 1)
					(thickness 0.15)
				)
			)
		)
		(property "Val" "0R01"
			(at 0 0 180)
			(unlocked yes)
			(layer "F.Fab")
			(hide yes)
			(effects
				(font
					(size 1 1)
					(thickness 0.15)
				)
			)
		)
		(property "License" "Apache-2.0"
			(at 0 0 180)
			(unlocked yes)
			(layer "F.Fab")
			(hide yes)
			(effects
				(font
					(size 1 1)
					(thickness 0.15)
				)
			)
		)
		(property "Author" "Antmicro"
			(at 0 0 180)
			(unlocked yes)
			(layer "F.Fab")
			(hide yes)
			(effects
				(font
					(size 1 1)
					(thickness 0.15)
				)
			)
		)
		(property "Tolerance" "1%"
			(at 0 0 180)
			(unlocked yes)
			(layer "F.Fab")
			(hide yes)
			(effects
				(font
					(size 1 1)
					(thickness 0.15)
				)
			)
		)
		(sheetname "/Supply/DC-DC IO/")
		(sheetfile "dc-dc-io.kicad_sch")
		(attr smd)
		(fp_line
			(start 0.8 0.901)
			(end -0.8 0.901)
			(stroke
				(width 0.15)
				(type solid)
			)
			(layer "F.SilkS")
		)
		(fp_line
			(start 0.8 -0.899)
			(end -0.8 -0.899)
			(stroke
				(width 0.15)
				(type solid)
			)
			(layer "F.SilkS")
		)
		(fp_rect
			(start -2.325 -1.15)
			(end 2.325 1.15)
			(stroke
				(width 0.05)
				(type default)
			)
			(fill no)
			(layer "F.CrtYd")
		)
		(fp_line
			(start 1.6 -0.802)
			(end 1.6 0.8)
			(stroke
				(width 0.15)
				(type solid)
			)
			(layer "F.Fab")
		)
		(fp_line
			(start -1.601 0.8)
			(end 1.6 0.8)
			(stroke
				(width 0.15)
				(type solid)
			)
			(layer "F.Fab")
		)
		(fp_line
			(start -1.601 -0.802)
			(end 1.6 -0.802)
			(stroke
				(width 0.15)
				(type solid)
			)
			(layer "F.Fab")
		)
		(fp_line
			(start -1.601 -0.802)
			(end -1.601 0.8)
			(stroke
				(width 0.15)
				(type solid)
			)
			(layer "F.Fab")
		)
		(fp_text user "${REFERENCE}"
			(at -2.401 3.5 180)
			(layer "F.Fab")
			(effects
				(font
					(size 0.7 0.7)
					(thickness 0.15)
				)
				(justify left bottom)
			)
		)
		(fp_text user "License: Apache-2.0"
			(at -2.401 6.3 180)
			(layer "F.Fab")
			(effects
				(font
					(size 0.7 0.7)
					(thickness 0.15)
				)
				(justify left bottom)
			)
		)
		(fp_text user "Author: Antmicro"
			(at -2.401 4.899 180)
			(layer "F.Fab")
			(effects
				(font
					(size 0.7 0.7)
					(thickness 0.15)
				)
				(justify left bottom)
			)
		)
		(pad "1" smd roundrect
			(at -1.5 0.001 180)
			(size 1.15 1.8)
			(layers "F.Cu" "F.Mask" "F.Paste")
			(roundrect_rratio 0.25)
			(net 159 "/Supply/DC-DC IO/1V2_local")
			(pintype "passive")
		)
		(pad "2" smd roundrect
			(at 1.5 0.001 180)
			(size 1.15 1.8)
			(layers "F.Cu" "F.Mask" "F.Paste")
			(roundrect_rratio 0.25)
			(net 150 "+1V2")
			(pintype "passive")
		)
	)
	(footprint "antmicro-footprints:NetTie-2_SMD_Pad0.127mm"
		(layer "F.Cu")
		(at 245.723 160.15 180)
		(descr "Net tie, 2 pin, 0.127mm  SMD pads")
		(tags "net tie")
		(property "Reference" "NT13"
			(at -0.128 -1.345 0)
			(layer "F.SilkS")
			(hide yes)
			(effects
				(font
					(size 0.7 0.7)
					(thickness 0.15)
				)
				(justify right bottom)
			)
		)
		(property "Value" "Net-Tie_P0.127mm"
			(at 0 1.199 0)
			(layer "F.Fab")
			(effects
				(font
					(size 0.7 0.7)
					(thickness 0.15)
				)
				(justify right bottom)
			)
		)
		(property "MPN" ""
			(at 0 0 180)
			(unlocked yes)
			(layer "F.Fab")
			(hide yes)
			(effects
				(font
					(size 1 1)
					(thickness 0.15)
				)
			)
		)
		(property "Manufacturer" ""
			(at 0 0 180)
			(unlocked yes)
			(layer "F.Fab")
			(hide yes)
			(effects
				(font
					(size 1 1)
					(thickness 0.15)
				)
			)
		)
		(property "Author" "Antmicro"
			(at 0 0 180)
			(unlocked yes)
			(layer "F.Fab")
			(hide yes)
			(effects
				(font
					(size 1 1)
					(thickness 0.15)
				)
			)
		)
		(property "License" "Apache-2.0"
			(at 0 0 180)
			(unlocked yes)
			(layer "F.Fab")
			(hide yes)
			(effects
				(font
					(size 1 1)
					(thickness 0.15)
				)
			)
		)
		(property ki_fp_filters "Net*Tie*")
		(sheetname "/Supply/DC-DC IO/")
		(sheetfile "dc-dc-io.kicad_sch")
		(attr through_hole exclude_from_pos_files exclude_from_bom)
		(net_tie_pad_groups "1, 2")
		(fp_poly
			(pts
				(xy -0.0635 -0.0635) (xy 0.0625 -0.0635) (xy 0.0625 0.0635) (xy -0.0635 0.0635)
			)
			(stroke
				(width 0)
				(type solid)
			)
			(fill yes)
			(layer "F.Cu")
		)
		(fp_poly
			(pts
				(xy 0.2 -0.16) (xy 0.29 -0.07) (xy 0.29 0.07) (xy 0.2 0.16) (xy -0.2 0.16) (xy -0.29 0.07) (xy -0.29 -0.06)
				(xy -0.19 -0.16)
			)
			(stroke
				(width 0.05)
				(type solid)
			)
			(fill no)
			(layer "F.CrtYd")
		)
		(fp_text user "Author: Antmicro"
			(at -0.128 4.4 180)
			(layer "F.Fab")
			(effects
				(font
					(size 0.7 0.7)
					(thickness 0.15)
				)
				(justify left bottom)
			)
		)
		(fp_text user "${REFERENCE}"
			(at -0.128 3.2 180)
			(layer "F.Fab")
			(effects
				(font
					(size 0.7 0.7)
					(thickness 0.15)
				)
				(justify left bottom)
			)
		)
		(fp_text user "License: Apache-2.0"
			(at -0.128 5.6 180)
			(layer "F.Fab")
			(effects
				(font
					(size 0.7 0.7)
					(thickness 0.15)
				)
				(justify left bottom)
			)
		)
		(pad "1" smd roundrect
			(at -0.127 0)
			(size 0.127 0.127)
			(layers "F.Cu")
			(roundrect_rratio 0.5)
			(chamfer_ratio 0)
			(chamfer top_left bottom_left)
			(net 693 "/Supply/DC-DC IO/3V3_SEN_-")
			(pinfunction "1")
			(pintype "passive")
		)
		(pad "2" smd roundrect
			(at 0.126 0 180)
			(size 0.127 0.127)
			(layers "F.Cu")
			(roundrect_rratio 0.5)
			(chamfer_ratio 0)
			(chamfer top_left bottom_left)
			(net 151 "+3V3")
			(pinfunction "2")
			(pintype "passive")
		)
	)
	(footprint "antmicro-footprints:C_0402_1005Metric"
		(layer "F.Cu")
		(at 118.19 145.61)
		(descr "Capacitor SMD 0402")
		(tags "capacitor SMD 0402")
		(property "Reference" "C300"
			(at -3.815 0.44 0)
			(layer "F.SilkS")
			(effects
				(font
					(size 0.7 0.7)
					(thickness 0.15)
				)
				(justify left bottom)
			)
		)
		(property "Value" "C_100n_0402"
			(at -1.022927 2.155213 0)
			(layer "F.Fab")
			(effects
				(font
					(size 0.7 0.7)
					(thickness 0.15)
				)
				(justify left bottom)
			)
		)
		(property "Datasheet" "https://www.murata.com/products/productdetail?partno=GRM155R61H104KE14%23"
			(at 0 0 0)
			(layer "F.Fab")
			(hide yes)
			(effects
				(font
					(size 1.27 1.27)
					(thickness 0.15)
				)
			)
		)
		(property "Manufacturer" "Murata"
			(at 0 0 0)
			(unlocked yes)
			(layer "F.Fab")
			(hide yes)
			(effects
				(font
					(size 1 1)
					(thickness 0.15)
				)
			)
		)
		(property "MPN" "GRM155R61H104KE14D"
			(at 0 0 0)
			(unlocked yes)
			(layer "F.Fab")
			(hide yes)
			(effects
				(font
					(size 1 1)
					(thickness 0.15)
				)
			)
		)
		(property "Val" "100n"
			(at 0 0 0)
			(unlocked yes)
			(layer "F.Fab")
			(hide yes)
			(effects
				(font
					(size 1 1)
					(thickness 0.15)
				)
			)
		)
		(property "License" "Apache-2.0"
			(at 0 0 0)
			(unlocked yes)
			(layer "F.Fab")
			(hide yes)
			(effects
				(font
					(size 1 1)
					(thickness 0.15)
				)
			)
		)
		(property "Author" "Antmicro"
			(at 0 0 0)
			(unlocked yes)
			(layer "F.Fab")
			(hide yes)
			(effects
				(font
					(size 1 1)
					(thickness 0.15)
				)
			)
		)
		(property "Voltage" "50V"
			(at 0 0 0)
			(unlocked yes)
			(layer "F.Fab")
			(hide yes)
			(effects
				(font
					(size 1 1)
					(thickness 0.15)
				)
			)
		)
		(property "Dielectric" "X5R"
			(at 0 0 0)
			(unlocked yes)
			(layer "F.Fab")
			(hide yes)
			(effects
				(font
					(size 1 1)
					(thickness 0.15)
				)
			)
		)
		(sheetname "/HDMI + SD Card/")
		(sheetfile "hdmi-sd-card.kicad_sch")
		(attr smd)
		(fp_rect
			(start -0.925 -0.47)
			(end 0.925 0.47)
			(stroke
				(width 0.05)
				(type default)
			)
			(fill no)
			(layer "F.CrtYd")
		)
		(fp_line
			(start -0.494 -0.25)
			(end 0.504 -0.25)
			(stroke
				(width 0.15)
				(type solid)
			)
			(layer "F.Fab")
		)
		(fp_line
			(start -0.494 0.248)
			(end -0.494 -0.25)
			(stroke
				(width 0.15)
				(type solid)
			)
			(layer "F.Fab")
		)
		(fp_line
			(start 0.504 -0.25)
			(end 0.504 0.248)
			(stroke
				(width 0.15)
				(type solid)
			)
			(layer "F.Fab")
		)
		(fp_line
			(start 0.504 0.248)
			(end -0.494 0.248)
			(stroke
				(width 0.15)
				(type solid)
			)
			(layer "F.Fab")
		)
		(fp_text user "License: Apache-2.0"
			(at -0.939 5.799 0)
			(layer "F.Fab")
			(effects
				(font
					(size 0.7 0.7)
					(thickness 0.15)
				)
				(justify left bottom)
			)
		)
		(fp_text user "${REFERENCE}"
			(at -0.939 4.599 0)
			(layer "F.Fab")
			(effects
				(font
					(size 0.7 0.7)
					(thickness 0.15)
				)
				(justify left bottom)
			)
		)
		(fp_text user "Author: Antmicro"
			(at -0.939 3.399 0)
			(layer "F.Fab")
			(effects
				(font
					(size 0.7 0.7)
					(thickness 0.15)
				)
				(justify left bottom)
			)
		)
		(pad "1" smd roundrect
			(at -0.48 0)
			(size 0.59 0.64)
			(layers "F.Cu" "F.Mask" "F.Paste")
			(roundrect_rratio 0.25)
			(net 1 "GND")
			(pintype "passive")
		)
		(pad "2" smd roundrect
			(at 0.48 0)
			(size 0.59 0.64)
			(layers "F.Cu" "F.Mask" "F.Paste")
			(roundrect_rratio 0.25)
			(net 322 "Net-(C300-Pad2)")
			(pintype "passive")
		)
	)
	(footprint "antmicro-footprints:R_1206_3216Metric"
		(layer "F.Cu")
		(at 246.279999 150.45 180)
		(property "Reference" "R146"
			(at -3.530001 1.38 0)
			(layer "F.SilkS")
			(effects
				(font
					(size 0.7 0.7)
					(thickness 0.15)
				)
				(justify right bottom)
			)
		)
		(property "Value" "R_0R01_1206"
			(at -2.422356 2.103591 0)
			(layer "F.Fab")
			(effects
				(font
					(size 0.7 0.7)
					(thickness 0.15)
				)
				(justify right bottom)
			)
		)
		(property "Datasheet" "https://www.yageo.com/upload/media/product/productsearch/datasheet/rchip/PYu-RL_Group_521_RoHS_L_2.pdf"
			(at 0 0 180)
			(layer "F.Fab")
			(hide yes)
			(effects
				(font
					(size 1.27 1.27)
					(thickness 0.15)
				)
			)
		)
		(property "Manufacturer" "YAGEO"
			(at 0 0 180)
			(unlocked yes)
			(layer "F.Fab")
			(hide yes)
			(effects
				(font
					(size 1 1)
					(thickness 0.15)
				)
			)
		)
		(property "MPN" "RL1206FR-7W0R01L"
			(at 0 0 180)
			(unlocked yes)
			(layer "F.Fab")
			(hide yes)
			(effects
				(font
					(size 1 1)
					(thickness 0.15)
				)
			)
		)
		(property "Val" "0R01"
			(at 0 0 180)
			(unlocked yes)
			(layer "F.Fab")
			(hide yes)
			(effects
				(font
					(size 1 1)
					(thickness 0.15)
				)
			)
		)
		(property "License" "Apache-2.0"
			(at 0 0 180)
			(unlocked yes)
			(layer "F.Fab")
			(hide yes)
			(effects
				(font
					(size 1 1)
					(thickness 0.15)
				)
			)
		)
		(property "Author" "Antmicro"
			(at 0 0 180)
			(unlocked yes)
			(layer "F.Fab")
			(hide yes)
			(effects
				(font
					(size 1 1)
					(thickness 0.15)
				)
			)
		)
		(property "Tolerance" "1%"
			(at 0 0 180)
			(unlocked yes)
			(layer "F.Fab")
			(hide yes)
			(effects
				(font
					(size 1 1)
					(thickness 0.15)
				)
			)
		)
		(sheetname "/Supply/DC-DC IO/")
		(sheetfile "dc-dc-io.kicad_sch")
		(attr smd)
		(fp_line
			(start 0.8 0.901)
			(end -0.8 0.901)
			(stroke
				(width 0.15)
				(type solid)
			)
			(layer "F.SilkS")
		)
		(fp_line
			(start 0.8 -0.899)
			(end -0.8 -0.899)
			(stroke
				(width 0.15)
				(type solid)
			)
			(layer "F.SilkS")
		)
		(fp_rect
			(start -2.325 -1.15)
			(end 2.325 1.15)
			(stroke
				(width 0.05)
				(type default)
			)
			(fill no)
			(layer "F.CrtYd")
		)
		(fp_line
			(start 1.6 -0.802)
			(end 1.6 0.8)
			(stroke
				(width 0.15)
				(type solid)
			)
			(layer "F.Fab")
		)
		(fp_line
			(start -1.601 0.8)
			(end 1.6 0.8)
			(stroke
				(width 0.15)
				(type solid)
			)
			(layer "F.Fab")
		)
		(fp_line
			(start -1.601 -0.802)
			(end 1.6 -0.802)
			(stroke
				(width 0.15)
				(type solid)
			)
			(layer "F.Fab")
		)
		(fp_line
			(start -1.601 -0.802)
			(end -1.601 0.8)
			(stroke
				(width 0.15)
				(type solid)
			)
			(layer "F.Fab")
		)
		(fp_text user "License: Apache-2.0"
			(at -2.401 6.3 180)
			(layer "F.Fab")
			(effects
				(font
					(size 0.7 0.7)
					(thickness 0.15)
				)
				(justify left bottom)
			)
		)
		(fp_text user "${REFERENCE}"
			(at -2.401 3.5 180)
			(layer "F.Fab")
			(effects
				(font
					(size 0.7 0.7)
					(thickness 0.15)
				)
				(justify left bottom)
			)
		)
		(fp_text user "Author: Antmicro"
			(at -2.401 4.899 180)
			(layer "F.Fab")
			(effects
				(font
					(size 0.7 0.7)
					(thickness 0.15)
				)
				(justify left bottom)
			)
		)
		(pad "1" smd roundrect
			(at -1.5 0.001 180)
			(size 1.15 1.8)
			(layers "F.Cu" "F.Mask" "F.Paste")
			(roundrect_rratio 0.25)
			(net 46 "/Supply/DC-DC IO/5V_local")
			(pintype "passive")
		)
		(pad "2" smd roundrect
			(at 1.5 0.001 180)
			(size 1.15 1.8)
			(layers "F.Cu" "F.Mask" "F.Paste")
			(roundrect_rratio 0.25)
			(net 152 "+5V")
			(pintype "passive")
		)
	)
	(footprint "antmicro-footprints:NetTie-2_SMD_Pad0.127mm"
		(layer "F.Cu")
		(at 246.687 167.948)
		(descr "Net tie, 2 pin, 0.127mm  SMD pads")
		(tags "net tie")
		(property "Reference" "NT2"
			(at -0.128 -1.345 0)
			(layer "F.SilkS")
			(hide yes)
			(effects
				(font
					(size 0.7 0.7)
					(thickness 0.15)
				)
				(justify left bottom)
			)
		)
		(property "Value" "Net-Tie_P0.127mm"
			(at 0 1.199 0)
			(layer "F.Fab")
			(effects
				(font
					(size 0.7 0.7)
					(thickness 0.15)
				)
				(justify left bottom)
			)
		)
		(property "MPN" ""
			(at 0 0 0)
			(unlocked yes)
			(layer "F.Fab")
			(hide yes)
			(effects
				(font
					(size 1 1)
					(thickness 0.15)
				)
			)
		)
		(property "Manufacturer" ""
			(at 0 0 0)
			(unlocked yes)
			(layer "F.Fab")
			(hide yes)
			(effects
				(font
					(size 1 1)
					(thickness 0.15)
				)
			)
		)
		(property "Author" "Antmicro"
			(at 0 0 0)
			(unlocked yes)
			(layer "F.Fab")
			(hide yes)
			(effects
				(font
					(size 1 1)
					(thickness 0.15)
				)
			)
		)
		(property "License" "Apache-2.0"
			(at 0 0 0)
			(unlocked yes)
			(layer "F.Fab")
			(hide yes)
			(effects
				(font
					(size 1 1)
					(thickness 0.15)
				)
			)
		)
		(property ki_fp_filters "Net*Tie*")
		(sheetname "/Supply/DC-DC AUX, MGT/")
		(sheetfile "dc-dc-aux-mgt.kicad_sch")
		(attr through_hole exclude_from_pos_files exclude_from_bom)
		(net_tie_pad_groups "1, 2")
		(fp_poly
			(pts
				(xy -0.0635 -0.0635) (xy 0.0625 -0.0635) (xy 0.0625 0.0635) (xy -0.0635 0.0635)
			)
			(stroke
				(width 0)
				(type solid)
			)
			(fill yes)
			(layer "F.Cu")
		)
		(fp_poly
			(pts
				(xy 0.2 -0.16) (xy 0.29 -0.07) (xy 0.29 0.07) (xy 0.2 0.16) (xy -0.2 0.16) (xy -0.29 0.07) (xy -0.29 -0.06)
				(xy -0.19 -0.16)
			)
			(stroke
				(width 0.05)
				(type solid)
			)
			(fill no)
			(layer "F.CrtYd")
		)
		(fp_text user "License: Apache-2.0"
			(at -0.128 5.6 0)
			(layer "F.Fab")
			(effects
				(font
					(size 0.7 0.7)
					(thickness 0.15)
				)
				(justify left bottom)
			)
		)
		(fp_text user "${REFERENCE}"
			(at -0.128 3.2 0)
			(layer "F.Fab")
			(effects
				(font
					(size 0.7 0.7)
					(thickness 0.15)
				)
				(justify left bottom)
			)
		)
		(fp_text user "Author: Antmicro"
			(at -0.128 4.4 0)
			(layer "F.Fab")
			(effects
				(font
					(size 0.7 0.7)
					(thickness 0.15)
				)
				(justify left bottom)
			)
		)
		(pad "1" smd roundrect
			(at -0.127 0 180)
			(size 0.127 0.127)
			(layers "F.Cu")
			(roundrect_rratio 0.5)
			(chamfer_ratio 0)
			(chamfer top_left bottom_left)
			(net 682 "/Supply/DC-DC AUX, MGT/MGTAVTT_SEN_+")
			(pinfunction "1")
			(pintype "passive")
		)
		(pad "2" smd roundrect
			(at 0.126 0)
			(size 0.127 0.127)
			(layers "F.Cu")
			(roundrect_rratio 0.5)
			(chamfer_ratio 0)
			(chamfer top_left bottom_left)
			(net 48 "/Supply/DC-DC AUX, MGT/MGTAVTT_local")
			(pinfunction "2")
			(pintype "passive")
		)
	)
	(footprint "antmicro-footprints:C_0603_1608Metric"
		(layer "F.Cu")
		(at 257.5 160.571)
		(descr "Capacitor SMD 0603")
		(tags "capacitor 0603")
		(property "Reference" "C193"
			(at 1.0445 0.029 0)
			(layer "F.SilkS")
			(effects
				(font
					(size 0.7 0.7)
					(thickness 0.15)
				)
				(justify left bottom)
			)
		)
		(property "Value" "C_22u_0603"
			(at -1.42757 1.770288 0)
			(layer "F.Fab")
			(effects
				(font
					(size 0.7 0.7)
					(thickness 0.15)
				)
				(justify left bottom)
			)
		)
		(property "Datasheet" "https://www.murata.com/products/productdetail?partno=GRM188R60J226MEA0%23"
			(at 0 0 0)
			(layer "F.Fab")
			(hide yes)
			(effects
				(font
					(size 1.27 1.27)
					(thickness 0.15)
				)
			)
		)
		(property "Manufacturer" "Murata"
			(at 0 0 0)
			(unlocked yes)
			(layer "F.Fab")
			(hide yes)
			(effects
				(font
					(size 1 1)
					(thickness 0.15)
				)
			)
		)
		(property "MPN" "GRM188R60J226MEA0D"
			(at 0 0 0)
			(unlocked yes)
			(layer "F.Fab")
			(hide yes)
			(effects
				(font
					(size 1 1)
					(thickness 0.15)
				)
			)
		)
		(property "Val" "22u"
			(at 0 0 0)
			(unlocked yes)
			(layer "F.Fab")
			(hide yes)
			(effects
				(font
					(size 1 1)
					(thickness 0.15)
				)
			)
		)
		(property "License" "Apache-2.0"
			(at 0 0 0)
			(unlocked yes)
			(layer "F.Fab")
			(hide yes)
			(effects
				(font
					(size 1 1)
					(thickness 0.15)
				)
			)
		)
		(property "Author" "Antmicro"
			(at 0 0 0)
			(unlocked yes)
			(layer "F.Fab")
			(hide yes)
			(effects
				(font
					(size 1 1)
					(thickness 0.15)
				)
			)
		)
		(property "Voltage" ""
			(at 0 0 0)
			(unlocked yes)
			(layer "F.Fab")
			(hide yes)
			(effects
				(font
					(size 1 1)
					(thickness 0.15)
				)
			)
		)
		(property "Dielectric" ""
			(at 0 0 0)
			(unlocked yes)
			(layer "F.Fab")
			(hide yes)
			(effects
				(font
					(size 1 1)
					(thickness 0.15)
				)
			)
		)
		(sheetname "/Supply/DC-DC IO/")
		(sheetfile "dc-dc-io.kicad_sch")
		(attr smd)
		(fp_line
			(start -0.15 -0.4)
			(end 0.15 -0.4)
			(stroke
				(width 0.15)
				(type solid)
			)
			(layer "F.SilkS")
		)
		(fp_line
			(start -0.15 0.4)
			(end 0.15 0.4)
			(stroke
				(width 0.15)
				(type solid)
			)
			(layer "F.SilkS")
		)
		(fp_rect
			(start -1.25 -0.65)
			(end 1.25 0.65)
			(stroke
				(width 0.05)
				(type solid)
			)
			(fill no)
			(layer "F.CrtYd")
		)
		(fp_rect
			(start -0.8 -0.4)
			(end 0.8 0.4)
			(stroke
				(width 0.15)
				(type solid)
			)
			(fill no)
			(layer "F.Fab")
		)
		(fp_text user "${REFERENCE}"
			(at -1.682 3.895 0)
			(layer "F.Fab")
			(effects
				(font
					(size 0.7 0.7)
					(thickness 0.15)
				)
				(justify left bottom)
			)
		)
		(fp_text user "License: Apache-2.0"
			(at -1.682 5.895 0)
			(layer "F.Fab")
			(effects
				(font
					(size 0.7 0.7)
					(thickness 0.15)
				)
				(justify left bottom)
			)
		)
		(fp_text user "Author: Antmicro"
			(at -1.682 4.894 0)
			(layer "F.Fab")
			(effects
				(font
					(size 0.7 0.7)
					(thickness 0.15)
				)
				(justify left bottom)
			)
		)
		(pad "1" smd roundrect
			(at -0.7 0)
			(size 0.8 1)
			(layers "F.Cu" "F.Mask" "F.Paste")
			(roundrect_rratio 0.2)
			(net 1 "GND")
			(pintype "passive")
		)
		(pad "2" smd roundrect
			(at 0.7 0)
			(size 0.8 1)
			(layers "F.Cu" "F.Mask" "F.Paste")
			(roundrect_rratio 0.2)
			(net 159 "/Supply/DC-DC IO/1V2_local")
			(pintype "passive")
		)
	)
	(footprint "antmicro-footprints:C_0603_1608Metric"
		(layer "F.Cu")
		(at 248.793 156.521 -90)
		(descr "Capacitor SMD 0603")
		(tags "capacitor 0603")
		(property "Reference" "C184"
			(at -1.346 0.968 90)
			(layer "F.SilkS")
			(effects
				(font
					(size 0.7 0.7)
					(thickness 0.15)
				)
				(justify right bottom)
			)
		)
		(property "Value" "C_22u_0603"
			(at -1.42757 1.770288 90)
			(layer "F.Fab")
			(effects
				(font
					(size 0.7 0.7)
					(thickness 0.15)
				)
				(justify right bottom)
			)
		)
		(property "Datasheet" "https://www.murata.com/products/productdetail?partno=GRM188R60J226MEA0%23"
			(at 0 0 270)
			(layer "F.Fab")
			(hide yes)
			(effects
				(font
					(size 1.27 1.27)
					(thickness 0.15)
				)
			)
		)
		(property "Manufacturer" "Murata"
			(at 0 0 270)
			(unlocked yes)
			(layer "F.Fab")
			(hide yes)
			(effects
				(font
					(size 1 1)
					(thickness 0.15)
				)
			)
		)
		(property "MPN" "GRM188R60J226MEA0D"
			(at 0 0 270)
			(unlocked yes)
			(layer "F.Fab")
			(hide yes)
			(effects
				(font
					(size 1 1)
					(thickness 0.15)
				)
			)
		)
		(property "Val" "22u"
			(at 0 0 270)
			(unlocked yes)
			(layer "F.Fab")
			(hide yes)
			(effects
				(font
					(size 1 1)
					(thickness 0.15)
				)
			)
		)
		(property "License" "Apache-2.0"
			(at 0 0 270)
			(unlocked yes)
			(layer "F.Fab")
			(hide yes)
			(effects
				(font
					(size 1 1)
					(thickness 0.15)
				)
			)
		)
		(property "Author" "Antmicro"
			(at 0 0 270)
			(unlocked yes)
			(layer "F.Fab")
			(hide yes)
			(effects
				(font
					(size 1 1)
					(thickness 0.15)
				)
			)
		)
		(property "Voltage" ""
			(at 0 0 270)
			(unlocked yes)
			(layer "F.Fab")
			(hide yes)
			(effects
				(font
					(size 1 1)
					(thickness 0.15)
				)
			)
		)
		(property "Dielectric" ""
			(at 0 0 270)
			(unlocked yes)
			(layer "F.Fab")
			(hide yes)
			(effects
				(font
					(size 1 1)
					(thickness 0.15)
				)
			)
		)
		(sheetname "/Supply/DC-DC IO/")
		(sheetfile "dc-dc-io.kicad_sch")
		(attr smd)
		(fp_line
			(start -0.15 0.4)
			(end 0.15 0.4)
			(stroke
				(width 0.15)
				(type solid)
			)
			(layer "F.SilkS")
		)
		(fp_line
			(start -0.15 -0.4)
			(end 0.15 -0.4)
			(stroke
				(width 0.15)
				(type solid)
			)
			(layer "F.SilkS")
		)
		(fp_rect
			(start -1.25 -0.65)
			(end 1.25 0.65)
			(stroke
				(width 0.05)
				(type solid)
			)
			(fill no)
			(layer "F.CrtYd")
		)
		(fp_rect
			(start -0.8 -0.4)
			(end 0.8 0.4)
			(stroke
				(width 0.15)
				(type solid)
			)
			(fill no)
			(layer "F.Fab")
		)
		(fp_text user "Author: Antmicro"
			(at -1.682 4.894 270)
			(layer "F.Fab")
			(effects
				(font
					(size 0.7 0.7)
					(thickness 0.15)
				)
				(justify left bottom)
			)
		)
		(fp_text user "${REFERENCE}"
			(at -1.682 3.895 270)
			(layer "F.Fab")
			(effects
				(font
					(size 0.7 0.7)
					(thickness 0.15)
				)
				(justify left bottom)
			)
		)
		(fp_text user "License: Apache-2.0"
			(at -1.682 5.895 270)
			(layer "F.Fab")
			(effects
				(font
					(size 0.7 0.7)
					(thickness 0.15)
				)
				(justify left bottom)
			)
		)
		(pad "1" smd roundrect
			(at -0.7 0 270)
			(size 0.8 1)
			(layers "F.Cu" "F.Mask" "F.Paste")
			(roundrect_rratio 0.2)
			(net 1 "GND")
			(pintype "passive")
		)
		(pad "2" smd roundrect
			(at 0.7 0 270)
			(size 0.8 1)
			(layers "F.Cu" "F.Mask" "F.Paste")
			(roundrect_rratio 0.2)
			(net 45 "/Supply/DC-DC IO/3V3_local")
			(pintype "passive")
		)
	)
	(footprint "antmicro-footprints:R_0402_1005Metric"
		(layer "F.Cu")
		(at 121.681 168.3125 90)
		(descr "Resistor SMD 0402")
		(tags "resistor SMD 0402")
		(property "Reference" "R219"
			(at -3.825 0.619 90)
			(layer "F.SilkS")
			(effects
				(font
					(size 0.7 0.7)
					(thickness 0.15)
				)
				(justify left bottom)
			)
		)
		(property "Value" "R_64k9_0402"
			(at -1.011843 1.772047 90)
			(layer "F.Fab")
			(effects
				(font
					(size 0.7 0.7)
					(thickness 0.15)
				)
				(justify left bottom)
			)
		)
		(property "Datasheet" "https://www.bourns.com/docs/product-datasheets/cr.pdf"
			(at 0 0 90)
			(layer "F.Fab")
			(hide yes)
			(effects
				(font
					(size 1.27 1.27)
					(thickness 0.15)
				)
			)
		)
		(property "MPN" "CR0402-FX-6492GLF"
			(at 0 0 90)
			(unlocked yes)
			(layer "F.Fab")
			(hide yes)
			(effects
				(font
					(size 1 1)
					(thickness 0.15)
				)
			)
		)
		(property "Manufacturer" "Bourns"
			(at 0 0 90)
			(unlocked yes)
			(layer "F.Fab")
			(hide yes)
			(effects
				(font
					(size 1 1)
					(thickness 0.15)
				)
			)
		)
		(property "License" "Apache-2.0"
			(at 0 0 90)
			(unlocked yes)
			(layer "F.Fab")
			(hide yes)
			(effects
				(font
					(size 1 1)
					(thickness 0.15)
				)
			)
		)
		(property "Author" "Antmicro"
			(at 0 0 90)
			(unlocked yes)
			(layer "F.Fab")
			(hide yes)
			(effects
				(font
					(size 1 1)
					(thickness 0.15)
				)
			)
		)
		(property "Val" "64k9"
			(at 0 0 90)
			(unlocked yes)
			(layer "F.Fab")
			(hide yes)
			(effects
				(font
					(size 1 1)
					(thickness 0.15)
				)
			)
		)
		(property "Tolerance" "1%"
			(at 0 0 90)
			(unlocked yes)
			(layer "F.Fab")
			(hide yes)
			(effects
				(font
					(size 1 1)
					(thickness 0.15)
				)
			)
		)
		(sheetname "/HDMI + SD Card/")
		(sheetfile "hdmi-sd-card.kicad_sch")
		(attr smd)
		(fp_rect
			(start -0.925 -0.47)
			(end 0.925 0.47)
			(stroke
				(width 0.05)
				(type default)
			)
			(fill no)
			(layer "F.CrtYd")
		)
		(fp_rect
			(start -0.5 -0.25)
			(end 0.5 0.25)
			(stroke
				(width 0.15)
				(type solid)
			)
			(fill no)
			(layer "F.Fab")
		)
		(fp_text user "License: Apache-2.0"
			(at -0.95 5.169 90)
			(layer "F.Fab")
			(effects
				(font
					(size 0.7 0.7)
					(thickness 0.15)
				)
				(justify left bottom)
			)
		)
		(fp_text user "Author: Antmicro"
			(at -0.95 4.169 90)
			(layer "F.Fab")
			(effects
				(font
					(size 0.7 0.7)
					(thickness 0.15)
				)
				(justify left bottom)
			)
		)
		(fp_text user "${REFERENCE}"
			(at -0.95 3.168 90)
			(layer "F.Fab")
			(effects
				(font
					(size 0.7 0.7)
					(thickness 0.15)
				)
				(justify left bottom)
			)
		)
		(pad "1" smd roundrect
			(at -0.48 0 90)
			(size 0.59 0.64)
			(layers "F.Cu" "F.Mask" "F.Paste")
			(roundrect_rratio 0.25)
			(net 1 "GND")
			(pintype "passive")
		)
		(pad "2" smd roundrect
			(at 0.48 0 90)
			(size 0.59 0.64)
			(layers "F.Cu" "F.Mask" "F.Paste")
			(roundrect_rratio 0.25)
			(net 738 "/HDMI + SD Card/~{HDMI_SEL}")
			(pintype "passive")
		)
	)
	(footprint "antmicro-footprints:C_0402_1005Metric"
		(layer "F.Cu")
		(at 126.306 176.022 90)
		(descr "Capacitor SMD 0402")
		(tags "capacitor SMD 0402")
		(property "Reference" "C283"
			(at 1.2 0.49 90)
			(layer "F.SilkS")
			(effects
				(font
					(size 0.7 0.7)
					(thickness 0.15)
				)
				(justify left bottom)
			)
		)
		(property "Value" "C_100n_0402"
			(at -1.022927 2.155213 90)
			(layer "F.Fab")
			(effects
				(font
					(size 0.7 0.7)
					(thickness 0.15)
				)
				(justify left bottom)
			)
		)
		(property "Datasheet" "https://www.murata.com/products/productdetail?partno=GRM155R61H104KE14%23"
			(at 0 0 90)
			(layer "F.Fab")
			(hide yes)
			(effects
				(font
					(size 1.27 1.27)
					(thickness 0.15)
				)
			)
		)
		(property "MPN" "GRM155R61H104KE14D"
			(at 0 0 90)
			(unlocked yes)
			(layer "F.Fab")
			(hide yes)
			(effects
				(font
					(size 1 1)
					(thickness 0.15)
				)
			)
		)
		(property "Manufacturer" "Murata"
			(at 0 0 90)
			(unlocked yes)
			(layer "F.Fab")
			(hide yes)
			(effects
				(font
					(size 1 1)
					(thickness 0.15)
				)
			)
		)
		(property "License" "Apache-2.0"
			(at 0 0 90)
			(unlocked yes)
			(layer "F.Fab")
			(hide yes)
			(effects
				(font
					(size 1 1)
					(thickness 0.15)
				)
			)
		)
		(property "Author" "Antmicro"
			(at 0 0 90)
			(unlocked yes)
			(layer "F.Fab")
			(hide yes)
			(effects
				(font
					(size 1 1)
					(thickness 0.15)
				)
			)
		)
		(property "Val" "100n"
			(at 0 0 90)
			(unlocked yes)
			(layer "F.Fab")
			(hide yes)
			(effects
				(font
					(size 1 1)
					(thickness 0.15)
				)
			)
		)
		(property "Voltage" "50V"
			(at 0 0 90)
			(unlocked yes)
			(layer "F.Fab")
			(hide yes)
			(effects
				(font
					(size 1 1)
					(thickness 0.15)
				)
			)
		)
		(property "Dielectric" "X5R"
			(at 0 0 90)
			(unlocked yes)
			(layer "F.Fab")
			(hide yes)
			(effects
				(font
					(size 1 1)
					(thickness 0.15)
				)
			)
		)
		(property "Public" ""
			(at 0 0 90)
			(unlocked yes)
			(layer "F.Fab")
			(hide yes)
			(effects
				(font
					(size 1 1)
					(thickness 0.15)
				)
			)
		)
		(sheetname "/HDMI + SD Card/")
		(sheetfile "hdmi-sd-card.kicad_sch")
		(attr smd)
		(fp_rect
			(start -0.925 -0.47)
			(end 0.925 0.47)
			(stroke
				(width 0.05)
				(type default)
			)
			(fill no)
			(layer "F.CrtYd")
		)
		(fp_line
			(start 0.504 -0.25)
			(end 0.504 0.248)
			(stroke
				(width 0.15)
				(type solid)
			)
			(layer "F.Fab")
		)
		(fp_line
			(start -0.494 -0.25)
			(end 0.504 -0.25)
			(stroke
				(width 0.15)
				(type solid)
			)
			(layer "F.Fab")
		)
		(fp_line
			(start 0.504 0.248)
			(end -0.494 0.248)
			(stroke
				(width 0.15)
				(type solid)
			)
			(layer "F.Fab")
		)
		(fp_line
			(start -0.494 0.248)
			(end -0.494 -0.25)
			(stroke
				(width 0.15)
				(type solid)
			)
			(layer "F.Fab")
		)
		(fp_text user "Author: Antmicro"
			(at -0.939 3.399 90)
			(layer "F.Fab")
			(effects
				(font
					(size 0.7 0.7)
					(thickness 0.15)
				)
				(justify left bottom)
			)
		)
		(fp_text user "${REFERENCE}"
			(at -0.939 4.599 90)
			(layer "F.Fab")
			(effects
				(font
					(size 0.7 0.7)
					(thickness 0.15)
				)
				(justify left bottom)
			)
		)
		(fp_text user "License: Apache-2.0"
			(at -0.939 5.799 90)
			(layer "F.Fab")
			(effects
				(font
					(size 0.7 0.7)
					(thickness 0.15)
				)
				(justify left bottom)
			)
		)
		(pad "1" smd roundrect
			(at -0.48 0 90)
			(size 0.59 0.64)
			(layers "F.Cu" "F.Mask" "F.Paste")
			(roundrect_rratio 0.25)
			(net 810 "/HDMI + SD Card/HDMI_VDD")
			(pintype "passive")
		)
		(pad "2" smd roundrect
			(at 0.48 0 90)
			(size 0.59 0.64)
			(layers "F.Cu" "F.Mask" "F.Paste")
			(roundrect_rratio 0.25)
			(net 1 "GND")
			(pintype "passive")
		)
	)
	(footprint "antmicro-footprints:C_0402_1005Metric"
		(layer "F.Cu")
		(at 252.92 182.078 -90)
		(descr "Capacitor SMD 0402")
		(tags "capacitor SMD 0402")
		(property "Reference" "C325"
			(at -1.878 2.57 90)
			(layer "F.SilkS")
			(effects
				(font
					(size 0.7 0.7)
					(thickness 0.15)
				)
				(justify right bottom)
			)
		)
		(property "Value" "C_100n_0402"
			(at -1.022927 2.155213 90)
			(layer "F.Fab")
			(effects
				(font
					(size 0.7 0.7)
					(thickness 0.15)
				)
				(justify right bottom)
			)
		)
		(property "Datasheet" "https://www.murata.com/products/productdetail?partno=GRM155R61H104KE14%23"
			(at 0 0 270)
			(layer "F.Fab")
			(hide yes)
			(effects
				(font
					(size 1.27 1.27)
					(thickness 0.15)
				)
			)
		)
		(property "MPN" "GRM155R61H104KE14D"
			(at 0 0 270)
			(unlocked yes)
			(layer "F.Fab")
			(hide yes)
			(effects
				(font
					(size 1 1)
					(thickness 0.15)
				)
			)
		)
		(property "Manufacturer" "Murata"
			(at 0 0 270)
			(unlocked yes)
			(layer "F.Fab")
			(hide yes)
			(effects
				(font
					(size 1 1)
					(thickness 0.15)
				)
			)
		)
		(property "License" "Apache-2.0"
			(at 0 0 270)
			(unlocked yes)
			(layer "F.Fab")
			(hide yes)
			(effects
				(font
					(size 1 1)
					(thickness 0.15)
				)
			)
		)
		(property "Author" "Antmicro"
			(at 0 0 270)
			(unlocked yes)
			(layer "F.Fab")
			(hide yes)
			(effects
				(font
					(size 1 1)
					(thickness 0.15)
				)
			)
		)
		(property "Val" "100n"
			(at 0 0 270)
			(unlocked yes)
			(layer "F.Fab")
			(hide yes)
			(effects
				(font
					(size 1 1)
					(thickness 0.15)
				)
			)
		)
		(property "Voltage" "50V"
			(at 0 0 270)
			(unlocked yes)
			(layer "F.Fab")
			(hide yes)
			(effects
				(font
					(size 1 1)
					(thickness 0.15)
				)
			)
		)
		(property "Dielectric" "X5R"
			(at 0 0 270)
			(unlocked yes)
			(layer "F.Fab")
			(hide yes)
			(effects
				(font
					(size 1 1)
					(thickness 0.15)
				)
			)
		)
		(sheetname "/I^{2}C + I3C/")
		(sheetfile "i2c.kicad_sch")
		(attr smd)
		(fp_rect
			(start -0.925 -0.47)
			(end 0.925 0.47)
			(stroke
				(width 0.05)
				(type default)
			)
			(fill no)
			(layer "F.CrtYd")
		)
		(fp_line
			(start -0.494 0.248)
			(end -0.494 -0.25)
			(stroke
				(width 0.15)
				(type solid)
			)
			(layer "F.Fab")
		)
		(fp_line
			(start 0.504 0.248)
			(end -0.494 0.248)
			(stroke
				(width 0.15)
				(type solid)
			)
			(layer "F.Fab")
		)
		(fp_line
			(start -0.494 -0.25)
			(end 0.504 -0.25)
			(stroke
				(width 0.15)
				(type solid)
			)
			(layer "F.Fab")
		)
		(fp_line
			(start 0.504 -0.25)
			(end 0.504 0.248)
			(stroke
				(width 0.15)
				(type solid)
			)
			(layer "F.Fab")
		)
		(fp_text user "Author: Antmicro"
			(at -0.939 3.399 270)
			(layer "F.Fab")
			(effects
				(font
					(size 0.7 0.7)
					(thickness 0.15)
				)
				(justify left bottom)
			)
		)
		(fp_text user "License: Apache-2.0"
			(at -0.939 5.799 270)
			(layer "F.Fab")
			(effects
				(font
					(size 0.7 0.7)
					(thickness 0.15)
				)
				(justify left bottom)
			)
		)
		(fp_text user "${REFERENCE}"
			(at -0.939 4.599 270)
			(layer "F.Fab")
			(effects
				(font
					(size 0.7 0.7)
					(thickness 0.15)
				)
				(justify left bottom)
			)
		)
		(pad "1" smd roundrect
			(at -0.48 0 270)
			(size 0.59 0.64)
			(layers "F.Cu" "F.Mask" "F.Paste")
			(roundrect_rratio 0.25)
			(net 1 "GND")
			(pintype "passive")
		)
		(pad "2" smd roundrect
			(at 0.48 0 270)
			(size 0.59 0.64)
			(layers "F.Cu" "F.Mask" "F.Paste")
			(roundrect_rratio 0.25)
			(net 664 "Net-(C325-Pad2)")
			(pintype "passive")
		)
	)
	(footprint "antmicro-footprints:SOT-23-6"
		(layer "F.Cu")
		(at 153.21 191.185)
		(property "Reference" "U18"
			(at 1.59 1.715 0)
			(layer "F.SilkS")
			(effects
				(font
					(size 0.7 0.7)
					(thickness 0.15)
				)
				(justify left bottom)
			)
		)
		(property "Value" "LTC4412IS6"
			(at -1.75 2.75 0)
			(layer "F.Fab")
			(effects
				(font
					(size 0.7 0.7)
					(thickness 0.15)
				)
				(justify left bottom)
			)
		)
		(property "Datasheet" "https://www.mouser.com/datasheet/2/308/NCV8187_D-1813214.pdf"
			(at 0 0 0)
			(layer "F.Fab")
			(hide yes)
			(effects
				(font
					(size 1.27 1.27)
					(thickness 0.15)
				)
			)
		)
		(property "MPN" "LTC4412IS6#TRMPBF"
			(at 0 0 0)
			(unlocked yes)
			(layer "F.Fab")
			(hide yes)
			(effects
				(font
					(size 1 1)
					(thickness 0.15)
				)
			)
		)
		(property "Manufacturer" "Analog Devices"
			(at 0 0 0)
			(unlocked yes)
			(layer "F.Fab")
			(hide yes)
			(effects
				(font
					(size 1 1)
					(thickness 0.15)
				)
			)
		)
		(property "Author" "Antmicro"
			(at 0 0 0)
			(unlocked yes)
			(layer "F.Fab")
			(hide yes)
			(effects
				(font
					(size 1 1)
					(thickness 0.15)
				)
			)
		)
		(property "License" "Apache-2.0"
			(at 0 0 0)
			(unlocked yes)
			(layer "F.Fab")
			(hide yes)
			(effects
				(font
					(size 1 1)
					(thickness 0.15)
				)
			)
		)
		(sheetname "/Supply/")
		(sheetfile "supply.kicad_sch")
		(attr smd)
		(fp_line
			(start -1.45 -0.757)
			(end -1.45 -0.457)
			(stroke
				(width 0.12)
				(type solid)
			)
			(layer "F.SilkS")
		)
		(fp_line
			(start -1.45 0.643)
			(end -1.45 0.343)
			(stroke
				(width 0.12)
				(type solid)
			)
			(layer "F.SilkS")
		)
		(fp_line
			(start -1.3 -0.757)
			(end -1.45 -0.757)
			(stroke
				(width 0.12)
				(type solid)
			)
			(layer "F.SilkS")
		)
		(fp_line
			(start 1.3 -0.757)
			(end 1.45 -0.757)
			(stroke
				(width 0.12)
				(type solid)
			)
			(layer "F.SilkS")
		)
		(fp_line
			(start 1.3 0.643)
			(end 1.45 0.643)
			(stroke
				(width 0.12)
				(type solid)
			)
			(layer "F.SilkS")
		)
		(fp_line
			(start 1.45 -0.757)
			(end 1.45 -0.457)
			(stroke
				(width 0.12)
				(type solid)
			)
			(layer "F.SilkS")
		)
		(fp_line
			(start 1.45 0.643)
			(end 1.45 0.343)
			(stroke
				(width 0.12)
				(type solid)
			)
			(layer "F.SilkS")
		)
		(fp_rect
			(start -1.55 -1.85)
			(end 1.55 1.75)
			(stroke
				(width 0.05)
				(type solid)
			)
			(fill no)
			(layer "F.CrtYd")
		)
		(fp_line
			(start -1.5 -0.757)
			(end 1.5 -0.757)
			(stroke
				(width 0.1)
				(type solid)
			)
			(layer "F.Fab")
		)
		(fp_line
			(start -1.5 0.643)
			(end -1.5 -0.757)
			(stroke
				(width 0.1)
				(type solid)
			)
			(layer "F.Fab")
		)
		(fp_line
			(start 1.5 -0.757)
			(end 1.5 0.643)
			(stroke
				(width 0.1)
				(type solid)
			)
			(layer "F.Fab")
		)
		(fp_line
			(start 1.5 0.643)
			(end -1.5 0.643)
			(stroke
				(width 0.1)
				(type solid)
			)
			(layer "F.Fab")
		)
		(fp_text user "."
			(at -1.4 1.2 0)
			(layer "F.SilkS")
			(effects
				(font
					(size 1 1)
					(thickness 0.15)
				)
			)
		)
		(fp_text user "License: Apache-2.0"
			(at -1.75 6.5 0)
			(layer "F.Fab")
			(effects
				(font
					(size 0.7 0.7)
					(thickness 0.15)
				)
				(justify left bottom)
			)
		)
		(fp_text user "Author: Antmicro"
			(at -1.829 5.25 0)
			(layer "F.Fab")
			(effects
				(font
					(size 0.7 0.7)
					(thickness 0.15)
				)
				(justify left bottom)
			)
		)
		(fp_text user "${REFERENCE}"
			(at -1.75 4 0)
			(layer "F.Fab")
			(effects
				(font
					(size 0.7 0.7)
					(thickness 0.15)
				)
				(justify left bottom)
			)
		)
		(pad "1" smd roundrect
			(at -0.954 1.1)
			(size 0.55 1)
			(layers "F.Cu" "F.Mask" "F.Paste")
			(roundrect_rratio 0.15)
			(net 324 "/Supply/12V_PCIE_fused")
			(pinfunction "IN")
			(pintype "power_in")
		)
		(pad "2" smd roundrect
			(at -0.003 1.1)
			(size 0.55 1)
			(layers "F.Cu" "F.Mask" "F.Paste")
			(roundrect_rratio 0.15)
			(net 1 "GND")
			(pinfunction "GND")
			(pintype "power_in")
		)
		(pad "3" smd roundrect
			(at 0.947 1.1)
			(size 0.55 1)
			(layers "F.Cu" "F.Mask" "F.Paste")
			(roundrect_rratio 0.15)
			(net 1 "GND")
			(pinfunction "CTL")
			(pintype "input")
		)
		(pad "4" smd roundrect
			(at 0.947 -1.214)
			(size 0.55 1)
			(layers "F.Cu" "F.Mask" "F.Paste")
			(roundrect_rratio 0.15)
			(net 429 "unconnected-(U18-STAT-Pad4)")
			(pinfunction "STAT")
			(pintype "output+no_connect")
		)
		(pad "5" smd roundrect
			(at -0.003 -1.214)
			(size 0.55 1)
			(layers "F.Cu" "F.Mask" "F.Paste")
			(roundrect_rratio 0.15)
			(net 285 "Net-(Q13-G)")
			(pinfunction "GATE")
			(pintype "output")
		)
		(pad "6" smd roundrect
			(at -0.954 -1.214)
			(size 0.55 1)
			(layers "F.Cu" "F.Mask" "F.Paste")
			(roundrect_rratio 0.15)
			(net 35 "VDC")
			(pinfunction "SENSE")
			(pintype "input")
		)
	)
	(footprint "antmicro-footprints:X2SON8_1.4x1x0.32mm_P0.35mm"
		(layer "F.Cu")
		(at 147.934499 160.284)
		(property "Reference" "U32"
			(at -0.834499 1.591 90)
			(layer "F.SilkS")
			(effects
				(font
					(size 0.7 0.7)
					(thickness 0.15)
				)
				(justify left bottom)
			)
		)
		(property "Value" "TXS0102DQER"
			(at 0 1.929 0)
			(layer "F.Fab")
			(effects
				(font
					(size 0.7 0.7)
					(thickness 0.15)
				)
				(justify left bottom)
			)
		)
		(property "Datasheet" "https://www.ti.com/lit/ds/symlink/txs0102.pdf?ts=1637914596981&ref_url=https%253A%252F%252Fwww.ti.com%252Fstore%252Fti%252Fen%252Fp%252Fproduct%252F%253Fp%253DTXS0102DCTR%2526keyMatch%253DTXS0102DCTR%2526tisearch%253Dsearch-everything%2526usecase%253DOPN"
			(at 0 0 0)
			(layer "F.Fab")
			(hide yes)
			(effects
				(font
					(size 1.27 1.27)
					(thickness 0.15)
				)
			)
		)
		(property "MPN" "TXS0102DQER"
			(at 0 0 0)
			(unlocked yes)
			(layer "F.Fab")
			(hide yes)
			(effects
				(font
					(size 1 1)
					(thickness 0.15)
				)
			)
		)
		(property "Manufacturer" "Texas Instruments"
			(at 0 0 0)
			(unlocked yes)
			(layer "F.Fab")
			(hide yes)
			(effects
				(font
					(size 1 1)
					(thickness 0.15)
				)
			)
		)
		(property "Author" "Antmicro"
			(at 0 0 0)
			(unlocked yes)
			(layer "F.Fab")
			(hide yes)
			(effects
				(font
					(size 1 1)
					(thickness 0.15)
				)
			)
		)
		(property "License" "Apache-2.0"
			(at 0 0 0)
			(unlocked yes)
			(layer "F.Fab")
			(hide yes)
			(effects
				(font
					(size 1 1)
					(thickness 0.15)
				)
			)
		)
		(sheetname "/Debug FTDI + VNA/")
		(sheetfile "debug-ftdi.kicad_sch")
		(attr smd)
		(fp_line
			(start -0.6 -0.801)
			(end -0.6 -0.7)
			(stroke
				(width 0.15)
				(type solid)
			)
			(layer "F.SilkS")
		)
		(fp_line
			(start -0.6 0.7)
			(end -0.6 0.801)
			(stroke
				(width 0.15)
				(type solid)
			)
			(layer "F.SilkS")
		)
		(fp_line
			(start -0.6 0.801)
			(end -0.5 0.801)
			(stroke
				(width 0.15)
				(type solid)
			)
			(layer "F.SilkS")
		)
		(fp_line
			(start -0.402 -0.801)
			(end -0.6 -0.801)
			(stroke
				(width 0.15)
				(type solid)
			)
			(layer "F.SilkS")
		)
		(fp_line
			(start 0.598 -0.801)
			(end 0.498 -0.801)
			(stroke
				(width 0.15)
				(type solid)
			)
			(layer "F.SilkS")
		)
		(fp_line
			(start 0.598 -0.7)
			(end 0.598 -0.801)
			(stroke
				(width 0.15)
				(type solid)
			)
			(layer "F.SilkS")
		)
		(fp_line
			(start 0.598 0.7)
			(end 0.598 0.801)
			(stroke
				(width 0.15)
				(type solid)
			)
			(layer "F.SilkS")
		)
		(fp_line
			(start 0.598 0.801)
			(end 0.498 0.801)
			(stroke
				(width 0.15)
				(type solid)
			)
			(layer "F.SilkS")
		)
		(fp_circle
			(center -0.81 -0.77)
			(end -0.81 -0.72)
			(stroke
				(width 0.15)
				(type solid)
			)
			(fill yes)
			(layer "F.SilkS")
		)
		(fp_rect
			(start 0.75 -0.925)
			(end -0.75 0.925)
			(stroke
				(width 0.05)
				(type solid)
			)
			(fill no)
			(layer "F.CrtYd")
		)
		(fp_line
			(start -0.5 -0.729)
			(end -0.5 0.719)
			(stroke
				(width 0.15)
				(type solid)
			)
			(layer "F.Fab")
		)
		(fp_line
			(start -0.5 -0.724)
			(end 0.498 -0.724)
			(stroke
				(width 0.15)
				(type solid)
			)
			(layer "F.Fab")
		)
		(fp_line
			(start -0.5 0.724)
			(end 0.498 0.724)
			(stroke
				(width 0.15)
				(type solid)
			)
			(layer "F.Fab")
		)
		(fp_line
			(start 0.498 -0.719)
			(end 0.498 0.719)
			(stroke
				(width 0.15)
				(type solid)
			)
			(layer "F.Fab")
		)
		(fp_text user "Author: Antmicro"
			(at -0.95 5.129 0)
			(layer "F.Fab")
			(effects
				(font
					(size 0.7 0.7)
					(thickness 0.15)
				)
				(justify left bottom)
			)
		)
		(fp_text user "License: Apache-2.0"
			(at -0.95 6.329 0)
			(layer "F.Fab")
			(effects
				(font
					(size 0.7 0.7)
					(thickness 0.15)
				)
				(justify left bottom)
			)
		)
		(fp_text user "${REFERENCE}"
			(at -0.95 3.929 0)
			(layer "F.Fab")
			(effects
				(font
					(size 0.7 0.7)
					(thickness 0.15)
				)
				(justify left bottom)
			)
		)
		(pad "1" smd rect
			(at -0.43 -0.526 270)
			(size 0.17 0.5)
			(layers "F.Cu" "F.Mask" "F.Paste")
			(net 6 "/Debug FTDI + VNA/FTDI_3V3")
			(pinfunction "VCCA")
			(pintype "power_in")
		)
		(pad "2" smd rect
			(at -0.43 -0.175 270)
			(size 0.17 0.5)
			(layers "F.Cu" "F.Mask" "F.Paste")
			(net 792 "/Debug FTDI + VNA/FTDI_UART1_RX")
			(pinfunction "A1")
			(pintype "bidirectional")
		)
		(pad "3" smd rect
			(at -0.43 0.175 270)
			(size 0.17 0.5)
			(layers "F.Cu" "F.Mask" "F.Paste")
			(net 791 "/Debug FTDI + VNA/FTDI_UART1_TX")
			(pinfunction "A2")
			(pintype "bidirectional")
		)
		(pad "4" smd rect
			(at -0.43 0.526 270)
			(size 0.17 0.5)
			(layers "F.Cu" "F.Mask" "F.Paste")
			(net 1 "GND")
			(pinfunction "GND")
			(pintype "power_in")
		)
		(pad "5" smd rect
			(at 0.43 0.526 270)
			(size 0.17 0.5)
			(layers "F.Cu" "F.Mask" "F.Paste")
			(net 6 "/Debug FTDI + VNA/FTDI_3V3")
			(pinfunction "OE")
			(pintype "tri_state")
		)
		(pad "6" smd rect
			(at 0.43 0.175 270)
			(size 0.17 0.5)
			(layers "F.Cu" "F.Mask" "F.Paste")
			(net 449 "Net-(U32-B2)")
			(pinfunction "B2")
			(pintype "bidirectional")
		)
		(pad "7" smd rect
			(at 0.43 -0.175 270)
			(size 0.17 0.5)
			(layers "F.Cu" "F.Mask" "F.Paste")
			(net 448 "Net-(U32-B1)")
			(pinfunction "B1")
			(pintype "bidirectional")
		)
		(pad "8" smd rect
			(at 0.43 -0.526 270)
			(size 0.17 0.5)
			(layers "F.Cu" "F.Mask" "F.Paste")
			(net 151 "+3V3")
			(pinfunction "VCCB")
			(pintype "power_in")
		)
	)
	(footprint "antmicro-footprints:R_0402_1005Metric"
		(layer "F.Cu")
		(at 124.681 168.3125 90)
		(descr "Resistor SMD 0402")
		(tags "resistor SMD 0402")
		(property "Reference" "R218"
			(at -3.825 0.619 90)
			(layer "F.SilkS")
			(effects
				(font
					(size 0.7 0.7)
					(thickness 0.15)
				)
				(justify left bottom)
			)
		)
		(property "Value" "R_64k9_0402"
			(at -1.011843 1.772047 90)
			(layer "F.Fab")
			(effects
				(font
					(size 0.7 0.7)
					(thickness 0.15)
				)
				(justify left bottom)
			)
		)
		(property "Datasheet" "https://www.bourns.com/docs/product-datasheets/cr.pdf"
			(at 0 0 90)
			(layer "F.Fab")
			(hide yes)
			(effects
				(font
					(size 1.27 1.27)
					(thickness 0.15)
				)
			)
		)
		(property "MPN" "CR0402-FX-6492GLF"
			(at 0 0 90)
			(unlocked yes)
			(layer "F.Fab")
			(hide yes)
			(effects
				(font
					(size 1 1)
					(thickness 0.15)
				)
			)
		)
		(property "Manufacturer" "Bourns"
			(at 0 0 90)
			(unlocked yes)
			(layer "F.Fab")
			(hide yes)
			(effects
				(font
					(size 1 1)
					(thickness 0.15)
				)
			)
		)
		(property "License" "Apache-2.0"
			(at 0 0 90)
			(unlocked yes)
			(layer "F.Fab")
			(hide yes)
			(effects
				(font
					(size 1 1)
					(thickness 0.15)
				)
			)
		)
		(property "Author" "Antmicro"
			(at 0 0 90)
			(unlocked yes)
			(layer "F.Fab")
			(hide yes)
			(effects
				(font
					(size 1 1)
					(thickness 0.15)
				)
			)
		)
		(property "Val" "64k9"
			(at 0 0 90)
			(unlocked yes)
			(layer "F.Fab")
			(hide yes)
			(effects
				(font
					(size 1 1)
					(thickness 0.15)
				)
			)
		)
		(property "Tolerance" "1%"
			(at 0 0 90)
			(unlocked yes)
			(layer "F.Fab")
			(hide yes)
			(effects
				(font
					(size 1 1)
					(thickness 0.15)
				)
			)
		)
		(sheetname "/HDMI + SD Card/")
		(sheetfile "hdmi-sd-card.kicad_sch")
		(attr smd)
		(fp_rect
			(start -0.925 -0.47)
			(end 0.925 0.47)
			(stroke
				(width 0.05)
				(type default)
			)
			(fill no)
			(layer "F.CrtYd")
		)
		(fp_rect
			(start -0.5 -0.25)
			(end 0.5 0.25)
			(stroke
				(width 0.15)
				(type solid)
			)
			(fill no)
			(layer "F.Fab")
		)
		(fp_text user "Author: Antmicro"
			(at -0.95 4.169 90)
			(layer "F.Fab")
			(effects
				(font
					(size 0.7 0.7)
					(thickness 0.15)
				)
				(justify left bottom)
			)
		)
		(fp_text user "License: Apache-2.0"
			(at -0.95 5.169 90)
			(layer "F.Fab")
			(effects
				(font
					(size 0.7 0.7)
					(thickness 0.15)
				)
				(justify left bottom)
			)
		)
		(fp_text user "${REFERENCE}"
			(at -0.95 3.168 90)
			(layer "F.Fab")
			(effects
				(font
					(size 0.7 0.7)
					(thickness 0.15)
				)
				(justify left bottom)
			)
		)
		(pad "1" smd roundrect
			(at -0.48 0 90)
			(size 0.59 0.64)
			(layers "F.Cu" "F.Mask" "F.Paste")
			(roundrect_rratio 0.25)
			(net 1 "GND")
			(pintype "passive")
		)
		(pad "2" smd roundrect
			(at 0.48 0 90)
			(size 0.59 0.64)
			(layers "F.Cu" "F.Mask" "F.Paste")
			(roundrect_rratio 0.25)
			(net 737 "/HDMI + SD Card/EQ_SEL")
			(pintype "passive")
		)
	)
	(footprint "antmicro-footprints:R_0402_1005Metric"
		(layer "F.Cu")
		(at 137.424499 183.264 90)
		(descr "Resistor SMD 0402")
		(tags "resistor SMD 0402")
		(property "Reference" "R65"
			(at -1.049516 -2.151301 90)
			(layer "F.SilkS")
			(effects
				(font
					(size 0.7 0.7)
					(thickness 0.15)
				)
				(justify left bottom)
			)
		)
		(property "Value" "R_330R_0402"
			(at -1.011843 1.772047 90)
			(layer "F.Fab")
			(effects
				(font
					(size 0.7 0.7)
					(thickness 0.15)
				)
				(justify left bottom)
			)
		)
		(property "Datasheet" "https://www.bourns.com/docs/product-datasheets/cr.pdf"
			(at 0 0 90)
			(layer "F.Fab")
			(hide yes)
			(effects
				(font
					(size 1.27 1.27)
					(thickness 0.15)
				)
			)
		)
		(property "Manufacturer" "Bourns"
			(at 0 0 90)
			(unlocked yes)
			(layer "F.Fab")
			(hide yes)
			(effects
				(font
					(size 1 1)
					(thickness 0.15)
				)
			)
		)
		(property "MPN" "CR0402-FX-3300GLF"
			(at 0 0 90)
			(unlocked yes)
			(layer "F.Fab")
			(hide yes)
			(effects
				(font
					(size 1 1)
					(thickness 0.15)
				)
			)
		)
		(property "Val" "330R"
			(at 0 0 90)
			(unlocked yes)
			(layer "F.Fab")
			(hide yes)
			(effects
				(font
					(size 1 1)
					(thickness 0.15)
				)
			)
		)
		(property "License" "Apache-2.0"
			(at 0 0 90)
			(unlocked yes)
			(layer "F.Fab")
			(hide yes)
			(effects
				(font
					(size 1 1)
					(thickness 0.15)
				)
			)
		)
		(property "Author" "Antmicro"
			(at 0 0 90)
			(unlocked yes)
			(layer "F.Fab")
			(hide yes)
			(effects
				(font
					(size 1 1)
					(thickness 0.15)
				)
			)
		)
		(property "Tolerance" "1%"
			(at 0 0 90)
			(unlocked yes)
			(layer "F.Fab")
			(hide yes)
			(effects
				(font
					(size 1 1)
					(thickness 0.15)
				)
			)
		)
		(sheetname "/Debug FTDI + VNA/")
		(sheetfile "debug-ftdi.kicad_sch")
		(attr smd)
		(fp_rect
			(start -0.925 -0.47)
			(end 0.925 0.47)
			(stroke
				(width 0.05)
				(type default)
			)
			(fill no)
			(layer "F.CrtYd")
		)
		(fp_rect
			(start -0.5 -0.25)
			(end 0.5 0.25)
			(stroke
				(width 0.15)
				(type solid)
			)
			(fill no)
			(layer "F.Fab")
		)
		(fp_text user "License: Apache-2.0"
			(at -0.95 5.169 90)
			(layer "F.Fab")
			(effects
				(font
					(size 0.7 0.7)
					(thickness 0.15)
				)
				(justify left bottom)
			)
		)
		(fp_text user "${REFERENCE}"
			(at -0.95 3.168 90)
			(layer "F.Fab")
			(effects
				(font
					(size 0.7 0.7)
					(thickness 0.15)
				)
				(justify left bottom)
			)
		)
		(fp_text user "Author: Antmicro"
			(at -0.95 4.169 90)
			(layer "F.Fab")
			(effects
				(font
					(size 0.7 0.7)
					(thickness 0.15)
				)
				(justify left bottom)
			)
		)
		(pad "1" smd roundrect
			(at -0.48 0 90)
			(size 0.59 0.64)
			(layers "F.Cu" "F.Mask" "F.Paste")
			(roundrect_rratio 0.25)
			(net 41 "Net-(D11-A)")
			(pintype "passive")
		)
		(pad "2" smd roundrect
			(at 0.48 0 90)
			(size 0.59 0.64)
			(layers "F.Cu" "F.Mask" "F.Paste")
			(roundrect_rratio 0.25)
			(net 444 "/Debug FTDI + VNA/LED_RX0")
			(pintype "passive")
		)
	)
	(footprint "antmicro-footprints:TP_SMD_1mm"
		(layer "F.Cu")
		(at 244.024499 170.549 180)
		(property "Reference" "TP14"
			(at 0 -0.731898 180)
			(layer "F.SilkS")
			(hide yes)
			(effects
				(font
					(size 0.7 0.7)
					(thickness 0.15)
				)
				(justify left bottom)
			)
		)
		(property "Value" "TP_1mm_SMD"
			(at 0 1.4 180)
			(layer "F.Fab")
			(effects
				(font
					(size 0.7 0.7)
					(thickness 0.15)
				)
				(justify left bottom)
			)
		)
		(property "MPN" ""
			(at 0 0 180)
			(unlocked yes)
			(layer "F.Fab")
			(hide yes)
			(effects
				(font
					(size 1 1)
					(thickness 0.15)
				)
			)
		)
		(property "Manufacturer" ""
			(at 0 0 180)
			(unlocked yes)
			(layer "F.Fab")
			(hide yes)
			(effects
				(font
					(size 1 1)
					(thickness 0.15)
				)
			)
		)
		(property "Author" "Antmicro"
			(at 0 0 180)
			(unlocked yes)
			(layer "F.Fab")
			(hide yes)
			(effects
				(font
					(size 1 1)
					(thickness 0.15)
				)
			)
		)
		(property "License" "Apache-2.0"
			(at 0 0 180)
			(unlocked yes)
			(layer "F.Fab")
			(hide yes)
			(effects
				(font
					(size 1 1)
					(thickness 0.15)
				)
			)
		)
		(sheetname "/Supply/DC-DC AUX, MGT/")
		(sheetfile "dc-dc-aux-mgt.kicad_sch")
		(attr exclude_from_pos_files)
		(fp_circle
			(center 0 0)
			(end 0.6 0)
			(stroke
				(width 0.05)
				(type default)
			)
			(fill no)
			(layer "F.CrtYd")
		)
		(fp_text user "${REFERENCE}"
			(at -0.5 2.8 180)
			(layer "F.Fab")
			(effects
				(font
					(size 0.7 0.7)
					(thickness 0.15)
				)
				(justify left bottom)
			)
		)
		(fp_text user "Author: Antmicro"
			(at -0.5 4 180)
			(layer "F.Fab")
			(effects
				(font
					(size 0.7 0.7)
					(thickness 0.15)
				)
				(justify left bottom)
			)
		)
		(fp_text user "License: Apache-2.0"
			(at -0.5 5.2 180)
			(layer "F.Fab")
			(effects
				(font
					(size 0.7 0.7)
					(thickness 0.15)
				)
				(justify left bottom)
			)
		)
		(pad "1" smd circle
			(at 0 0 180)
			(size 1 1)
			(layers "F.Cu" "F.Mask")
			(net 172 "+1V2_MGTAVTT")
			(pinfunction "1")
			(pintype "passive")
		)
	)
	(footprint "antmicro-footprints:SC70-3"
		(layer "F.Cu")
		(at 250.274499 135.149)
		(property "Reference" "Q16"
			(at 0.505501 1.091 90)
			(layer "F.SilkS")
			(effects
				(font
					(size 0.7 0.7)
					(thickness 0.15)
				)
				(justify left bottom)
			)
		)
		(property "Value" "BSS138PW"
			(at 0 2.3 0)
			(layer "F.Fab")
			(effects
				(font
					(size 0.7 0.7)
					(thickness 0.15)
				)
				(justify left bottom)
			)
		)
		(property "Datasheet" "https://assets.nexperia.com/documents/data-sheet/BSS138PW.pdf"
			(at 0 0 0)
			(layer "F.Fab")
			(hide yes)
			(effects
				(font
					(size 1.27 1.27)
					(thickness 0.15)
				)
			)
		)
		(property "MPN" "BSS138PW"
			(at 0 0 0)
			(unlocked yes)
			(layer "F.Fab")
			(hide yes)
			(effects
				(font
					(size 1 1)
					(thickness 0.15)
				)
			)
		)
		(property "Manufacturer" "Nexperia"
			(at 0 0 0)
			(unlocked yes)
			(layer "F.Fab")
			(hide yes)
			(effects
				(font
					(size 1 1)
					(thickness 0.15)
				)
			)
		)
		(property "Author" "Antmicro"
			(at 0 0 0)
			(unlocked yes)
			(layer "F.Fab")
			(hide yes)
			(effects
				(font
					(size 1 1)
					(thickness 0.15)
				)
			)
		)
		(property "License" "Apache-2.0"
			(at 0 0 0)
			(unlocked yes)
			(layer "F.Fab")
			(hide yes)
			(effects
				(font
					(size 1 1)
					(thickness 0.15)
				)
			)
		)
		(sheetname "/Supply/")
		(sheetfile "supply.kicad_sch")
		(attr smd)
		(fp_line
			(start -0.3 -1)
			(end 0.627 -0.999)
			(stroke
				(width 0.15)
				(type solid)
			)
			(layer "F.SilkS")
		)
		(fp_line
			(start -0.3 1)
			(end 0.627 1.001)
			(stroke
				(width 0.15)
				(type solid)
			)
			(layer "F.SilkS")
		)
		(fp_line
			(start 0.627 -0.6)
			(end 0.627 -0.999)
			(stroke
				(width 0.15)
				(type solid)
			)
			(layer "F.SilkS")
		)
		(fp_line
			(start 0.627 0.6)
			(end 0.627 1.001)
			(stroke
				(width 0.15)
				(type solid)
			)
			(layer "F.SilkS")
		)
		(fp_line
			(start -1.4 1)
			(end -1.4 -1)
			(stroke
				(width 0.05)
				(type solid)
			)
			(layer "F.CrtYd")
		)
		(fp_line
			(start -0.9 -1.3)
			(end -0.9 -1)
			(stroke
				(width 0.05)
				(type solid)
			)
			(layer "F.CrtYd")
		)
		(fp_line
			(start -0.9 -1.3)
			(end 0.9 -1.3)
			(stroke
				(width 0.05)
				(type solid)
			)
			(layer "F.CrtYd")
		)
		(fp_line
			(start -0.9 -1)
			(end -1.4 -1)
			(stroke
				(width 0.05)
				(type solid)
			)
			(layer "F.CrtYd")
		)
		(fp_line
			(start -0.9 1)
			(end -1.4 1)
			(stroke
				(width 0.05)
				(type solid)
			)
			(layer "F.CrtYd")
		)
		(fp_line
			(start -0.9 1.3)
			(end -0.9 1)
			(stroke
				(width 0.05)
				(type solid)
			)
			(layer "F.CrtYd")
		)
		(fp_line
			(start 0.9 -1.3)
			(end 0.9 -0.4)
			(stroke
				(width 0.05)
				(type solid)
			)
			(layer "F.CrtYd")
		)
		(fp_line
			(start 0.9 -0.4)
			(end 1.4 -0.4)
			(stroke
				(width 0.05)
				(type solid)
			)
			(layer "F.CrtYd")
		)
		(fp_line
			(start 0.9 0.4)
			(end 0.9 1.3)
			(stroke
				(width 0.05)
				(type solid)
			)
			(layer "F.CrtYd")
		)
		(fp_line
			(start 0.9 1.3)
			(end -0.9 1.3)
			(stroke
				(width 0.05)
				(type solid)
			)
			(layer "F.CrtYd")
		)
		(fp_line
			(start 1.4 -0.4)
			(end 1.4 0.4)
			(stroke
				(width 0.05)
				(type solid)
			)
			(layer "F.CrtYd")
		)
		(fp_line
			(start 1.4 0.4)
			(end 0.9 0.4)
			(stroke
				(width 0.05)
				(type solid)
			)
			(layer "F.CrtYd")
		)
		(fp_rect
			(start -0.623 -0.999)
			(end 0.627 1.001)
			(stroke
				(width 0.15)
				(type solid)
			)
			(fill no)
			(layer "F.Fab")
		)
		(fp_text user "${REFERENCE}"
			(at -1.45 4.783 0)
			(layer "F.Fab")
			(effects
				(font
					(size 0.7 0.7)
					(thickness 0.15)
				)
				(justify left bottom)
			)
		)
		(fp_text user "License: Apache-2.0"
			(at -1.45 6.782 0)
			(layer "F.Fab")
			(effects
				(font
					(size 0.7 0.7)
					(thickness 0.15)
				)
				(justify left bottom)
			)
		)
		(fp_text user "Author: Antmicro"
			(at -1.45 5.782 0)
			(layer "F.Fab")
			(effects
				(font
					(size 0.7 0.7)
					(thickness 0.15)
				)
				(justify left bottom)
			)
		)
		(pad "1" smd rect
			(at -1.051 -0.65 90)
			(size 0.6 0.6)
			(layers "F.Cu" "F.Mask" "F.Paste")
			(net 184 "FPGA_POWER_CYCLE")
			(pinfunction "G")
			(pintype "passive")
		)
		(pad "2" smd rect
			(at -1.051 0.65 90)
			(size 0.6 0.6)
			(layers "F.Cu" "F.Mask" "F.Paste")
			(net 1 "GND")
			(pinfunction "S")
			(pintype "passive")
		)
		(pad "3" smd rect
			(at 1.05 0 90)
			(size 0.6 0.6)
			(layers "F.Cu" "F.Mask" "F.Paste")
			(net 286 "Net-(Q16-D)")
			(pinfunction "D")
			(pintype "passive")
		)
	)
	(footprint "antmicro-footprints:C_0402_1005Metric"
		(layer "F.Cu")
		(at 123.766 187.222 -90)
		(descr "Capacitor SMD 0402")
		(tags "capacitor SMD 0402")
		(property "Reference" "C294"
			(at -1.425 0.575 90)
			(layer "F.SilkS")
			(effects
				(font
					(size 0.7 0.7)
					(thickness 0.15)
				)
				(justify right bottom)
			)
		)
		(property "Value" "C_100n_0402"
			(at -1.022927 2.155213 90)
			(layer "F.Fab")
			(effects
				(font
					(size 0.7 0.7)
					(thickness 0.15)
				)
				(justify right bottom)
			)
		)
		(property "Datasheet" "https://www.murata.com/products/productdetail?partno=GRM155R61H104KE14%23"
			(at 0 0 270)
			(layer "F.Fab")
			(hide yes)
			(effects
				(font
					(size 1.27 1.27)
					(thickness 0.15)
				)
			)
		)
		(property "MPN" "GRM155R61H104KE14D"
			(at 0 0 270)
			(unlocked yes)
			(layer "F.Fab")
			(hide yes)
			(effects
				(font
					(size 1 1)
					(thickness 0.15)
				)
			)
		)
		(property "Manufacturer" "Murata"
			(at 0 0 270)
			(unlocked yes)
			(layer "F.Fab")
			(hide yes)
			(effects
				(font
					(size 1 1)
					(thickness 0.15)
				)
			)
		)
		(property "License" "Apache-2.0"
			(at 0 0 270)
			(unlocked yes)
			(layer "F.Fab")
			(hide yes)
			(effects
				(font
					(size 1 1)
					(thickness 0.15)
				)
			)
		)
		(property "Author" "Antmicro"
			(at 0 0 270)
			(unlocked yes)
			(layer "F.Fab")
			(hide yes)
			(effects
				(font
					(size 1 1)
					(thickness 0.15)
				)
			)
		)
		(property "Val" "100n"
			(at 0 0 270)
			(unlocked yes)
			(layer "F.Fab")
			(hide yes)
			(effects
				(font
					(size 1 1)
					(thickness 0.15)
				)
			)
		)
		(property "Voltage" "50V"
			(at 0 0 270)
			(unlocked yes)
			(layer "F.Fab")
			(hide yes)
			(effects
				(font
					(size 1 1)
					(thickness 0.15)
				)
			)
		)
		(property "Dielectric" "X5R"
			(at 0 0 270)
			(unlocked yes)
			(layer "F.Fab")
			(hide yes)
			(effects
				(font
					(size 1 1)
					(thickness 0.15)
				)
			)
		)
		(property "Public" ""
			(at 0 0 270)
			(unlocked yes)
			(layer "F.Fab")
			(hide yes)
			(effects
				(font
					(size 1 1)
					(thickness 0.15)
				)
			)
		)
		(sheetname "/HDMI + SD Card/")
		(sheetfile "hdmi-sd-card.kicad_sch")
		(attr smd exclude_from_bom dnp)
		(fp_rect
			(start -0.925 -0.47)
			(end 0.925 0.47)
			(stroke
				(width 0.05)
				(type default)
			)
			(fill no)
			(layer "F.CrtYd")
		)
		(fp_line
			(start -0.494 0.248)
			(end -0.494 -0.25)
			(stroke
				(width 0.15)
				(type solid)
			)
			(layer "F.Fab")
		)
		(fp_line
			(start 0.504 0.248)
			(end -0.494 0.248)
			(stroke
				(width 0.15)
				(type solid)
			)
			(layer "F.Fab")
		)
		(fp_line
			(start -0.494 -0.25)
			(end 0.504 -0.25)
			(stroke
				(width 0.15)
				(type solid)
			)
			(layer "F.Fab")
		)
		(fp_line
			(start 0.504 -0.25)
			(end 0.504 0.248)
			(stroke
				(width 0.15)
				(type solid)
			)
			(layer "F.Fab")
		)
		(fp_text user "Author: Antmicro"
			(at -0.939 3.399 270)
			(layer "F.Fab")
			(effects
				(font
					(size 0.7 0.7)
					(thickness 0.15)
				)
				(justify left bottom)
			)
		)
		(fp_text user "License: Apache-2.0"
			(at -0.939 5.799 270)
			(layer "F.Fab")
			(effects
				(font
					(size 0.7 0.7)
					(thickness 0.15)
				)
				(justify left bottom)
			)
		)
		(fp_text user "${REFERENCE}"
			(at -0.939 4.599 270)
			(layer "F.Fab")
			(effects
				(font
					(size 0.7 0.7)
					(thickness 0.15)
				)
				(justify left bottom)
			)
		)
		(pad "1" smd roundrect
			(at -0.48 0 270)
			(size 0.59 0.64)
			(layers "F.Cu" "F.Mask" "F.Paste")
			(roundrect_rratio 0.25)
			(net 385 "HDMI_OE")
			(pintype "passive")
		)
		(pad "2" smd roundrect
			(at 0.48 0 270)
			(size 0.59 0.64)
			(layers "F.Cu" "F.Mask" "F.Paste")
			(roundrect_rratio 0.25)
			(net 1 "GND")
			(pintype "passive")
		)
	)
	(footprint "antmicro-footprints:R_0402_1005Metric"
		(layer "F.Cu")
		(at 119.15 151.61 180)
		(descr "Resistor SMD 0402")
		(tags "resistor SMD 0402")
		(property "Reference" "R34"
			(at -5.11 -0.415 0)
			(layer "F.SilkS")
			(effects
				(font
					(size 0.7 0.7)
					(thickness 0.15)
				)
				(justify right bottom)
			)
		)
		(property "Value" "R_49k9_0402"
			(at -1.011843 1.772047 0)
			(layer "F.Fab")
			(effects
				(font
					(size 0.7 0.7)
					(thickness 0.15)
				)
				(justify right bottom)
			)
		)
		(property "Datasheet" "https://www.bourns.com/docs/product-datasheets/cr.pdf"
			(at 0 0 180)
			(layer "F.Fab")
			(hide yes)
			(effects
				(font
					(size 1.27 1.27)
					(thickness 0.15)
				)
			)
		)
		(property "MPN" "CR0402-FX-4992GLF"
			(at 0 0 180)
			(unlocked yes)
			(layer "F.Fab")
			(hide yes)
			(effects
				(font
					(size 1 1)
					(thickness 0.15)
				)
			)
		)
		(property "Manufacturer" "Bourns"
			(at 0 0 180)
			(unlocked yes)
			(layer "F.Fab")
			(hide yes)
			(effects
				(font
					(size 1 1)
					(thickness 0.15)
				)
			)
		)
		(property "License" "Apache-2.0"
			(at 0 0 180)
			(unlocked yes)
			(layer "F.Fab")
			(hide yes)
			(effects
				(font
					(size 1 1)
					(thickness 0.15)
				)
			)
		)
		(property "Author" "Antmicro"
			(at 0 0 180)
			(unlocked yes)
			(layer "F.Fab")
			(hide yes)
			(effects
				(font
					(size 1 1)
					(thickness 0.15)
				)
			)
		)
		(property "Val" "49k9"
			(at 0 0 180)
			(unlocked yes)
			(layer "F.Fab")
			(hide yes)
			(effects
				(font
					(size 1 1)
					(thickness 0.15)
				)
			)
		)
		(property "Tolerance" "1%"
			(at 0 0 180)
			(unlocked yes)
			(layer "F.Fab")
			(hide yes)
			(effects
				(font
					(size 1 1)
					(thickness 0.15)
				)
			)
		)
		(sheetname "/HDMI + SD Card/")
		(sheetfile "hdmi-sd-card.kicad_sch")
		(attr smd)
		(fp_rect
			(start -0.925 -0.47)
			(end 0.925 0.47)
			(stroke
				(width 0.05)
				(type default)
			)
			(fill no)
			(layer "F.CrtYd")
		)
		(fp_rect
			(start -0.5 -0.25)
			(end 0.5 0.25)
			(stroke
				(width 0.15)
				(type solid)
			)
			(fill no)
			(layer "F.Fab")
		)
		(fp_text user "License: Apache-2.0"
			(at -0.95 5.169 180)
			(layer "F.Fab")
			(effects
				(font
					(size 0.7 0.7)
					(thickness 0.15)
				)
				(justify left bottom)
			)
		)
		(fp_text user "${REFERENCE}"
			(at -0.95 3.168 180)
			(layer "F.Fab")
			(effects
				(font
					(size 0.7 0.7)
					(thickness 0.15)
				)
				(justify left bottom)
			)
		)
		(fp_text user "Author: Antmicro"
			(at -0.95 4.169 180)
			(layer "F.Fab")
			(effects
				(font
					(size 0.7 0.7)
					(thickness 0.15)
				)
				(justify left bottom)
			)
		)
		(pad "1" smd roundrect
			(at -0.48 0 180)
			(size 0.59 0.64)
			(layers "F.Cu" "F.Mask" "F.Paste")
			(roundrect_rratio 0.25)
			(net 680 "Net-(L10-Pad2)")
			(pintype "passive")
		)
		(pad "2" smd roundrect
			(at 0.48 0 180)
			(size 0.59 0.64)
			(layers "F.Cu" "F.Mask" "F.Paste")
			(roundrect_rratio 0.25)
			(net 322 "Net-(C300-Pad2)")
			(pintype "passive")
		)
	)
	(footprint "antmicro-footprints:C_0402_1005Metric"
		(layer "F.Cu")
		(at 127.711 186.1375)
		(descr "Capacitor SMD 0402")
		(tags "capacitor SMD 0402")
		(property "Reference" "C281"
			(at 1.389 0.5375 0)
			(layer "F.SilkS")
			(effects
				(font
					(size 0.7 0.7)
					(thickness 0.15)
				)
				(justify left bottom)
			)
		)
		(property "Value" "C_100n_0402"
			(at -1.022927 2.155213 0)
			(layer "F.Fab")
			(effects
				(font
					(size 0.7 0.7)
					(thickness 0.15)
				)
				(justify left bottom)
			)
		)
		(property "Datasheet" "https://www.murata.com/products/productdetail?partno=GRM155R61H104KE14%23"
			(at 0 0 0)
			(layer "F.Fab")
			(hide yes)
			(effects
				(font
					(size 1.27 1.27)
					(thickness 0.15)
				)
			)
		)
		(property "MPN" "GRM155R61H104KE14D"
			(at 0 0 0)
			(unlocked yes)
			(layer "F.Fab")
			(hide yes)
			(effects
				(font
					(size 1 1)
					(thickness 0.15)
				)
			)
		)
		(property "Manufacturer" "Murata"
			(at 0 0 0)
			(unlocked yes)
			(layer "F.Fab")
			(hide yes)
			(effects
				(font
					(size 1 1)
					(thickness 0.15)
				)
			)
		)
		(property "License" "Apache-2.0"
			(at 0 0 0)
			(unlocked yes)
			(layer "F.Fab")
			(hide yes)
			(effects
				(font
					(size 1 1)
					(thickness 0.15)
				)
			)
		)
		(property "Author" "Antmicro"
			(at 0 0 0)
			(unlocked yes)
			(layer "F.Fab")
			(hide yes)
			(effects
				(font
					(size 1 1)
					(thickness 0.15)
				)
			)
		)
		(property "Val" "100n"
			(at 0 0 0)
			(unlocked yes)
			(layer "F.Fab")
			(hide yes)
			(effects
				(font
					(size 1 1)
					(thickness 0.15)
				)
			)
		)
		(property "Voltage" "50V"
			(at 0 0 0)
			(unlocked yes)
			(layer "F.Fab")
			(hide yes)
			(effects
				(font
					(size 1 1)
					(thickness 0.15)
				)
			)
		)
		(property "Dielectric" "X5R"
			(at 0 0 0)
			(unlocked yes)
			(layer "F.Fab")
			(hide yes)
			(effects
				(font
					(size 1 1)
					(thickness 0.15)
				)
			)
		)
		(property "Public" ""
			(at 0 0 0)
			(unlocked yes)
			(layer "F.Fab")
			(hide yes)
			(effects
				(font
					(size 1 1)
					(thickness 0.15)
				)
			)
		)
		(sheetname "/HDMI + SD Card/")
		(sheetfile "hdmi-sd-card.kicad_sch")
		(attr smd)
		(fp_rect
			(start -0.925 -0.47)
			(end 0.925 0.47)
			(stroke
				(width 0.05)
				(type default)
			)
			(fill no)
			(layer "F.CrtYd")
		)
		(fp_line
			(start -0.494 -0.25)
			(end 0.504 -0.25)
			(stroke
				(width 0.15)
				(type solid)
			)
			(layer "F.Fab")
		)
		(fp_line
			(start -0.494 0.248)
			(end -0.494 -0.25)
			(stroke
				(width 0.15)
				(type solid)
			)
			(layer "F.Fab")
		)
		(fp_line
			(start 0.504 -0.25)
			(end 0.504 0.248)
			(stroke
				(width 0.15)
				(type solid)
			)
			(layer "F.Fab")
		)
		(fp_line
			(start 0.504 0.248)
			(end -0.494 0.248)
			(stroke
				(width 0.15)
				(type solid)
			)
			(layer "F.Fab")
		)
		(fp_text user "License: Apache-2.0"
			(at -0.939 5.799 0)
			(layer "F.Fab")
			(effects
				(font
					(size 0.7 0.7)
					(thickness 0.15)
				)
				(justify left bottom)
			)
		)
		(fp_text user "${REFERENCE}"
			(at -0.939 4.599 0)
			(layer "F.Fab")
			(effects
				(font
					(size 0.7 0.7)
					(thickness 0.15)
				)
				(justify left bottom)
			)
		)
		(fp_text user "Author: Antmicro"
			(at -0.939 3.399 0)
			(layer "F.Fab")
			(effects
				(font
					(size 0.7 0.7)
					(thickness 0.15)
				)
				(justify left bottom)
			)
		)
		(pad "1" smd roundrect
			(at -0.48 0)
			(size 0.59 0.64)
			(layers "F.Cu" "F.Mask" "F.Paste")
			(roundrect_rratio 0.25)
			(net 810 "/HDMI + SD Card/HDMI_VDD")
			(pintype "passive")
		)
		(pad "2" smd roundrect
			(at 0.48 0)
			(size 0.59 0.64)
			(layers "F.Cu" "F.Mask" "F.Paste")
			(roundrect_rratio 0.25)
			(net 1 "GND")
			(pintype "passive")
		)
	)
	(footprint "antmicro-footprints:R_0402_1005Metric"
		(layer "F.Cu")
		(at 248.169499 132.349 90)
		(descr "Resistor SMD 0402")
		(tags "resistor SMD 0402")
		(property "Reference" "R161"
			(at -1.401 -0.772697 90)
			(layer "F.SilkS")
			(effects
				(font
					(size 0.7 0.7)
					(thickness 0.15)
				)
				(justify left bottom)
			)
		)
		(property "Value" "R_47k_0402"
			(at -1.011843 1.772047 90)
			(layer "F.Fab")
			(effects
				(font
					(size 0.7 0.7)
					(thickness 0.15)
				)
				(justify left bottom)
			)
		)
		(property "Datasheet" "https://www.bourns.com/docs/product-datasheets/cr.pdf"
			(at 0 0 90)
			(layer "F.Fab")
			(hide yes)
			(effects
				(font
					(size 1.27 1.27)
					(thickness 0.15)
				)
			)
		)
		(property "Manufacturer" "Bourns"
			(at 0 0 90)
			(unlocked yes)
			(layer "F.Fab")
			(hide yes)
			(effects
				(font
					(size 1 1)
					(thickness 0.15)
				)
			)
		)
		(property "MPN" "CR0402-FX-4702GLF"
			(at 0 0 90)
			(unlocked yes)
			(layer "F.Fab")
			(hide yes)
			(effects
				(font
					(size 1 1)
					(thickness 0.15)
				)
			)
		)
		(property "Val" "47k"
			(at 0 0 90)
			(unlocked yes)
			(layer "F.Fab")
			(hide yes)
			(effects
				(font
					(size 1 1)
					(thickness 0.15)
				)
			)
		)
		(property "License" "Apache-2.0"
			(at 0 0 90)
			(unlocked yes)
			(layer "F.Fab")
			(hide yes)
			(effects
				(font
					(size 1 1)
					(thickness 0.15)
				)
			)
		)
		(property "Author" "Antmicro"
			(at 0 0 90)
			(unlocked yes)
			(layer "F.Fab")
			(hide yes)
			(effects
				(font
					(size 1 1)
					(thickness 0.15)
				)
			)
		)
		(property "Tolerance" "1%"
			(at 0 0 90)
			(unlocked yes)
			(layer "F.Fab")
			(hide yes)
			(effects
				(font
					(size 1 1)
					(thickness 0.15)
				)
			)
		)
		(sheetname "/Supply/")
		(sheetfile "supply.kicad_sch")
		(attr smd)
		(fp_rect
			(start -0.925 -0.47)
			(end 0.925 0.47)
			(stroke
				(width 0.05)
				(type default)
			)
			(fill no)
			(layer "F.CrtYd")
		)
		(fp_rect
			(start -0.5 -0.25)
			(end 0.5 0.25)
			(stroke
				(width 0.15)
				(type solid)
			)
			(fill no)
			(layer "F.Fab")
		)
		(fp_text user "License: Apache-2.0"
			(at -0.95 5.169 90)
			(layer "F.Fab")
			(effects
				(font
					(size 0.7 0.7)
					(thickness 0.15)
				)
				(justify left bottom)
			)
		)
		(fp_text user "${REFERENCE}"
			(at -0.95 3.168 90)
			(layer "F.Fab")
			(effects
				(font
					(size 0.7 0.7)
					(thickness 0.15)
				)
				(justify left bottom)
			)
		)
		(fp_text user "Author: Antmicro"
			(at -0.95 4.169 90)
			(layer "F.Fab")
			(effects
				(font
					(size 0.7 0.7)
					(thickness 0.15)
				)
				(justify left bottom)
			)
		)
		(pad "1" smd roundrect
			(at -0.48 0 90)
			(size 0.59 0.64)
			(layers "F.Cu" "F.Mask" "F.Paste")
			(roundrect_rratio 0.25)
			(net 1 "GND")
			(pintype "passive")
		)
		(pad "2" smd roundrect
			(at 0.48 0 90)
			(size 0.59 0.64)
			(layers "F.Cu" "F.Mask" "F.Paste")
			(roundrect_rratio 0.25)
			(net 185 "FPGA_POWER_OFF")
			(pintype "passive")
		)
	)
	(footprint "antmicro-footprints:NetTie-2_SMD_Pad0.127mm"
		(layer "F.Cu")
		(at 245.873877 167.95 180)
		(descr "Net tie, 2 pin, 0.127mm  SMD pads")
		(tags "net tie")
		(property "Reference" "NT10"
			(at -0.128 -1.345 0)
			(layer "F.SilkS")
			(hide yes)
			(effects
				(font
					(size 0.7 0.7)
					(thickness 0.15)
				)
				(justify right bottom)
			)
		)
		(property "Value" "Net-Tie_P0.127mm"
			(at 0 1.199 0)
			(layer "F.Fab")
			(effects
				(font
					(size 0.7 0.7)
					(thickness 0.15)
				)
				(justify right bottom)
			)
		)
		(property "MPN" ""
			(at 0 0 180)
			(unlocked yes)
			(layer "F.Fab")
			(hide yes)
			(effects
				(font
					(size 1 1)
					(thickness 0.15)
				)
			)
		)
		(property "Manufacturer" ""
			(at 0 0 180)
			(unlocked yes)
			(layer "F.Fab")
			(hide yes)
			(effects
				(font
					(size 1 1)
					(thickness 0.15)
				)
			)
		)
		(property "Author" "Antmicro"
			(at 0 0 180)
			(unlocked yes)
			(layer "F.Fab")
			(hide yes)
			(effects
				(font
					(size 1 1)
					(thickness 0.15)
				)
			)
		)
		(property "License" "Apache-2.0"
			(at 0 0 180)
			(unlocked yes)
			(layer "F.Fab")
			(hide yes)
			(effects
				(font
					(size 1 1)
					(thickness 0.15)
				)
			)
		)
		(property ki_fp_filters "Net*Tie*")
		(sheetname "/Supply/DC-DC AUX, MGT/")
		(sheetfile "dc-dc-aux-mgt.kicad_sch")
		(attr through_hole exclude_from_pos_files exclude_from_bom)
		(net_tie_pad_groups "1, 2")
		(fp_poly
			(pts
				(xy -0.0635 -0.0635) (xy 0.0625 -0.0635) (xy 0.0625 0.0635) (xy -0.0635 0.0635)
			)
			(stroke
				(width 0)
				(type solid)
			)
			(fill yes)
			(layer "F.Cu")
		)
		(fp_poly
			(pts
				(xy 0.2 -0.16) (xy 0.29 -0.07) (xy 0.29 0.07) (xy 0.2 0.16) (xy -0.2 0.16) (xy -0.29 0.07) (xy -0.29 -0.06)
				(xy -0.19 -0.16)
			)
			(stroke
				(width 0.05)
				(type solid)
			)
			(fill no)
			(layer "F.CrtYd")
		)
		(fp_text user "License: Apache-2.0"
			(at -0.128 5.6 180)
			(layer "F.Fab")
			(effects
				(font
					(size 0.7 0.7)
					(thickness 0.15)
				)
				(justify left bottom)
			)
		)
		(fp_text user "Author: Antmicro"
			(at -0.128 4.4 180)
			(layer "F.Fab")
			(effects
				(font
					(size 0.7 0.7)
					(thickness 0.15)
				)
				(justify left bottom)
			)
		)
		(fp_text user "${REFERENCE}"
			(at -0.128 3.2 180)
			(layer "F.Fab")
			(effects
				(font
					(size 0.7 0.7)
					(thickness 0.15)
				)
				(justify left bottom)
			)
		)
		(pad "1" smd roundrect
			(at -0.127 0)
			(size 0.127 0.127)
			(layers "F.Cu")
			(roundrect_rratio 0.5)
			(chamfer_ratio 0)
			(chamfer top_left bottom_left)
			(net 690 "/Supply/DC-DC AUX, MGT/MGTAVTT_SEN_-")
			(pinfunction "1")
			(pintype "passive")
		)
		(pad "2" smd roundrect
			(at 0.126 0 180)
			(size 0.127 0.127)
			(layers "F.Cu")
			(roundrect_rratio 0.5)
			(chamfer_ratio 0)
			(chamfer top_left bottom_left)
			(net 172 "+1V2_MGTAVTT")
			(pinfunction "2")
			(pintype "passive")
		)
	)
	(footprint "antmicro-footprints:C_0402_1005Metric"
		(layer "F.Cu")
		(at 160.1 157.199999 90)
		(descr "Capacitor SMD 0402")
		(tags "capacitor SMD 0402")
		(property "Reference" "C287"
			(at 0.96 1.23 90)
			(layer "F.SilkS")
			(effects
				(font
					(size 0.7 0.7)
					(thickness 0.15)
				)
				(justify left bottom)
			)
		)
		(property "Value" "C_100n_0402"
			(at -1.022927 2.155213 90)
			(layer "F.Fab")
			(effects
				(font
					(size 0.7 0.7)
					(thickness 0.15)
				)
				(justify left bottom)
			)
		)
		(property "Datasheet" "https://www.murata.com/products/productdetail?partno=GRM155R61H104KE14%23"
			(at 0 0 90)
			(layer "F.Fab")
			(hide yes)
			(effects
				(font
					(size 1.27 1.27)
					(thickness 0.15)
				)
			)
		)
		(property "MPN" "GRM155R61H104KE14D"
			(at 0 0 90)
			(unlocked yes)
			(layer "F.Fab")
			(hide yes)
			(effects
				(font
					(size 1 1)
					(thickness 0.15)
				)
			)
		)
		(property "Manufacturer" "Murata"
			(at 0 0 90)
			(unlocked yes)
			(layer "F.Fab")
			(hide yes)
			(effects
				(font
					(size 1 1)
					(thickness 0.15)
				)
			)
		)
		(property "License" "Apache-2.0"
			(at 0 0 90)
			(unlocked yes)
			(layer "F.Fab")
			(hide yes)
			(effects
				(font
					(size 1 1)
					(thickness 0.15)
				)
			)
		)
		(property "Author" "Antmicro"
			(at 0 0 90)
			(unlocked yes)
			(layer "F.Fab")
			(hide yes)
			(effects
				(font
					(size 1 1)
					(thickness 0.15)
				)
			)
		)
		(property "Val" "100n"
			(at 0 0 90)
			(unlocked yes)
			(layer "F.Fab")
			(hide yes)
			(effects
				(font
					(size 1 1)
					(thickness 0.15)
				)
			)
		)
		(property "Voltage" "50V"
			(at 0 0 90)
			(unlocked yes)
			(layer "F.Fab")
			(hide yes)
			(effects
				(font
					(size 1 1)
					(thickness 0.15)
				)
			)
		)
		(property "Dielectric" "X5R"
			(at 0 0 90)
			(unlocked yes)
			(layer "F.Fab")
			(hide yes)
			(effects
				(font
					(size 1 1)
					(thickness 0.15)
				)
			)
		)
		(property "Public" ""
			(at 0 0 90)
			(unlocked yes)
			(layer "F.Fab")
			(hide yes)
			(effects
				(font
					(size 1 1)
					(thickness 0.15)
				)
			)
		)
		(sheetname "/FPGA MGT Interface/")
		(sheetfile "fpga-mgt.kicad_sch")
		(attr smd)
		(fp_rect
			(start -0.925 -0.47)
			(end 0.925 0.47)
			(stroke
				(width 0.05)
				(type default)
			)
			(fill no)
			(layer "F.CrtYd")
		)
		(fp_line
			(start 0.504 -0.25)
			(end 0.504 0.248)
			(stroke
				(width 0.15)
				(type solid)
			)
			(layer "F.Fab")
		)
		(fp_line
			(start -0.494 -0.25)
			(end 0.504 -0.25)
			(stroke
				(width 0.15)
				(type solid)
			)
			(layer "F.Fab")
		)
		(fp_line
			(start 0.504 0.248)
			(end -0.494 0.248)
			(stroke
				(width 0.15)
				(type solid)
			)
			(layer "F.Fab")
		)
		(fp_line
			(start -0.494 0.248)
			(end -0.494 -0.25)
			(stroke
				(width 0.15)
				(type solid)
			)
			(layer "F.Fab")
		)
		(fp_text user "License: Apache-2.0"
			(at -0.939 5.799 90)
			(layer "F.Fab")
			(effects
				(font
					(size 0.7 0.7)
					(thickness 0.15)
				)
				(justify left bottom)
			)
		)
		(fp_text user "Author: Antmicro"
			(at -0.939 3.399 90)
			(layer "F.Fab")
			(effects
				(font
					(size 0.7 0.7)
					(thickness 0.15)
				)
				(justify left bottom)
			)
		)
		(fp_text user "${REFERENCE}"
			(at -0.939 4.599 90)
			(layer "F.Fab")
			(effects
				(font
					(size 0.7 0.7)
					(thickness 0.15)
				)
				(justify left bottom)
			)
		)
		(pad "1" smd roundrect
			(at -0.48 0 90)
			(size 0.59 0.64)
			(layers "F.Cu" "F.Mask" "F.Paste")
			(roundrect_rratio 0.25)
			(net 151 "+3V3")
			(pintype "passive")
		)
		(pad "2" smd roundrect
			(at 0.48 0 90)
			(size 0.59 0.64)
			(layers "F.Cu" "F.Mask" "F.Paste")
			(roundrect_rratio 0.25)
			(net 1 "GND")
			(pintype "passive")
		)
	)
	(footprint "antmicro-footprints:R_0402_1005Metric"
		(layer "F.Cu")
		(at 135.824499 183.264 90)
		(descr "Resistor SMD 0402")
		(tags "resistor SMD 0402")
		(property "Reference" "R64"
			(at -1.036 -1.524499 90)
			(layer "F.SilkS")
			(effects
				(font
					(size 0.7 0.7)
					(thickness 0.15)
				)
				(justify left bottom)
			)
		)
		(property "Value" "R_330R_0402"
			(at -1.011843 1.772047 90)
			(layer "F.Fab")
			(effects
				(font
					(size 0.7 0.7)
					(thickness 0.15)
				)
				(justify left bottom)
			)
		)
		(property "Datasheet" "https://www.bourns.com/docs/product-datasheets/cr.pdf"
			(at 0 0 90)
			(layer "F.Fab")
			(hide yes)
			(effects
				(font
					(size 1.27 1.27)
					(thickness 0.15)
				)
			)
		)
		(property "Manufacturer" "Bourns"
			(at 0 0 90)
			(unlocked yes)
			(layer "F.Fab")
			(hide yes)
			(effects
				(font
					(size 1 1)
					(thickness 0.15)
				)
			)
		)
		(property "MPN" "CR0402-FX-3300GLF"
			(at 0 0 90)
			(unlocked yes)
			(layer "F.Fab")
			(hide yes)
			(effects
				(font
					(size 1 1)
					(thickness 0.15)
				)
			)
		)
		(property "Val" "330R"
			(at 0 0 90)
			(unlocked yes)
			(layer "F.Fab")
			(hide yes)
			(effects
				(font
					(size 1 1)
					(thickness 0.15)
				)
			)
		)
		(property "License" "Apache-2.0"
			(at 0 0 90)
			(unlocked yes)
			(layer "F.Fab")
			(hide yes)
			(effects
				(font
					(size 1 1)
					(thickness 0.15)
				)
			)
		)
		(property "Author" "Antmicro"
			(at 0 0 90)
			(unlocked yes)
			(layer "F.Fab")
			(hide yes)
			(effects
				(font
					(size 1 1)
					(thickness 0.15)
				)
			)
		)
		(property "Tolerance" "1%"
			(at 0 0 90)
			(unlocked yes)
			(layer "F.Fab")
			(hide yes)
			(effects
				(font
					(size 1 1)
					(thickness 0.15)
				)
			)
		)
		(sheetname "/Debug FTDI + VNA/")
		(sheetfile "debug-ftdi.kicad_sch")
		(attr smd)
		(fp_rect
			(start -0.925 -0.47)
			(end 0.925 0.47)
			(stroke
				(width 0.05)
				(type default)
			)
			(fill no)
			(layer "F.CrtYd")
		)
		(fp_rect
			(start -0.5 -0.25)
			(end 0.5 0.25)
			(stroke
				(width 0.15)
				(type solid)
			)
			(fill no)
			(layer "F.Fab")
		)
		(fp_text user "Author: Antmicro"
			(at -0.95 4.169 90)
			(layer "F.Fab")
			(effects
				(font
					(size 0.7 0.7)
					(thickness 0.15)
				)
				(justify left bottom)
			)
		)
		(fp_text user "License: Apache-2.0"
			(at -0.95 5.169 90)
			(layer "F.Fab")
			(effects
				(font
					(size 0.7 0.7)
					(thickness 0.15)
				)
				(justify left bottom)
			)
		)
		(fp_text user "${REFERENCE}"
			(at -0.95 3.168 90)
			(layer "F.Fab")
			(effects
				(font
					(size 0.7 0.7)
					(thickness 0.15)
				)
				(justify left bottom)
			)
		)
		(pad "1" smd roundrect
			(at -0.48 0 90)
			(size 0.59 0.64)
			(layers "F.Cu" "F.Mask" "F.Paste")
			(roundrect_rratio 0.25)
			(net 39 "Net-(D10-A)")
			(pintype "passive")
		)
		(pad "2" smd roundrect
			(at 0.48 0 90)
			(size 0.59 0.64)
			(layers "F.Cu" "F.Mask" "F.Paste")
			(roundrect_rratio 0.25)
			(net 443 "/Debug FTDI + VNA/LED_TX0")
			(pintype "passive")
		)
	)
	(footprint "antmicro-footprints:C_0402_1005Metric"
		(layer "F.Cu")
		(at 230.2 161.35 90)
		(descr "Capacitor SMD 0402")
		(tags "capacitor SMD 0402")
		(property "Reference" "C198"
			(at -2.35 2.07 90)
			(layer "F.SilkS")
			(effects
				(font
					(size 0.7 0.7)
					(thickness 0.15)
				)
				(justify left bottom)
			)
		)
		(property "Value" "C_1u_0402"
			(at -4.564428 51.328713 90)
			(layer "F.Fab")
			(effects
				(font
					(size 0.7 0.7)
					(thickness 0.15)
				)
				(justify left bottom)
			)
		)
		(property "Datasheet" "https://product.tdk.com/en/search/capacitor/ceramic/mlcc/info?part_no=C1005X6S1A105K050BC"
			(at 0 0 90)
			(layer "F.Fab")
			(hide yes)
			(effects
				(font
					(size 1.27 1.27)
					(thickness 0.15)
				)
			)
		)
		(property "Manufacturer" "TDK"
			(at 0 0 90)
			(unlocked yes)
			(layer "F.Fab")
			(hide yes)
			(effects
				(font
					(size 1 1)
					(thickness 0.15)
				)
			)
		)
		(property "MPN" "C1005X6S1A105K050BC"
			(at 0 0 90)
			(unlocked yes)
			(layer "F.Fab")
			(hide yes)
			(effects
				(font
					(size 1 1)
					(thickness 0.15)
				)
			)
		)
		(property "Val" "1u"
			(at 0 0 90)
			(unlocked yes)
			(layer "F.Fab")
			(hide yes)
			(effects
				(font
					(size 1 1)
					(thickness 0.15)
				)
			)
		)
		(property "License" "Apache-2.0"
			(at 0 0 90)
			(unlocked yes)
			(layer "F.Fab")
			(hide yes)
			(effects
				(font
					(size 1 1)
					(thickness 0.15)
				)
			)
		)
		(property "Author" "Antmicro"
			(at 0 0 90)
			(unlocked yes)
			(layer "F.Fab")
			(hide yes)
			(effects
				(font
					(size 1 1)
					(thickness 0.15)
				)
			)
		)
		(property "Voltage" ""
			(at 0 0 90)
			(unlocked yes)
			(layer "F.Fab")
			(hide yes)
			(effects
				(font
					(size 1 1)
					(thickness 0.15)
				)
			)
		)
		(property "Dielectric" ""
			(at 0 0 90)
			(unlocked yes)
			(layer "F.Fab")
			(hide yes)
			(effects
				(font
					(size 1 1)
					(thickness 0.15)
				)
			)
		)
		(sheetname "/Supply/")
		(sheetfile "supply.kicad_sch")
		(attr smd)
		(fp_rect
			(start -0.925 -0.47)
			(end 0.925 0.47)
			(stroke
				(width 0.05)
				(type default)
			)
			(fill no)
			(layer "F.CrtYd")
		)
		(fp_line
			(start 0.504 -0.25)
			(end 0.504 0.248)
			(stroke
				(width 0.15)
				(type solid)
			)
			(layer "F.Fab")
		)
		(fp_line
			(start -0.494 -0.25)
			(end 0.504 -0.25)
			(stroke
				(width 0.15)
				(type solid)
			)
			(layer "F.Fab")
		)
		(fp_line
			(start 0.504 0.248)
			(end -0.494 0.248)
			(stroke
				(width 0.15)
				(type solid)
			)
			(layer "F.Fab")
		)
		(fp_line
			(start -0.494 0.248)
			(end -0.494 -0.25)
			(stroke
				(width 0.15)
				(type solid)
			)
			(layer "F.Fab")
		)
		(fp_text user "Author: Antmicro"
			(at -0.939 3.399 90)
			(layer "F.Fab")
			(effects
				(font
					(size 0.7 0.7)
					(thickness 0.15)
				)
				(justify left bottom)
			)
		)
		(fp_text user "License: Apache-2.0"
			(at -0.939 5.799 90)
			(layer "F.Fab")
			(effects
				(font
					(size 0.7 0.7)
					(thickness 0.15)
				)
				(justify left bottom)
			)
		)
		(fp_text user "${REFERENCE}"
			(at -0.939 4.599 90)
			(layer "F.Fab")
			(effects
				(font
					(size 0.7 0.7)
					(thickness 0.15)
				)
				(justify left bottom)
			)
		)
		(pad "1" smd roundrect
			(at -0.48 0 90)
			(size 0.59 0.64)
			(layers "F.Cu" "F.Mask" "F.Paste")
			(roundrect_rratio 0.25)
			(net 1 "GND")
			(pintype "passive")
		)
		(pad "2" smd roundrect
			(at 0.48 0 90)
			(size 0.59 0.64)
			(layers "F.Cu" "F.Mask" "F.Paste")
			(roundrect_rratio 0.25)
			(net 152 "+5V")
			(pintype "passive")
		)
	)
	(footprint "antmicro-footprints:C_0402_1005Metric"
		(layer "F.Cu")
		(at 241.774499 185.099 -90)
		(descr "Capacitor SMD 0402")
		(tags "capacitor SMD 0402")
		(property "Reference" "C196"
			(at -1.199 -1.575501 90)
			(layer "F.SilkS")
			(effects
				(font
					(size 0.7 0.7)
					(thickness 0.15)
				)
				(justify right bottom)
			)
		)
		(property "Value" "C_100n_0402"
			(at -1.022927 2.155213 90)
			(layer "F.Fab")
			(effects
				(font
					(size 0.7 0.7)
					(thickness 0.15)
				)
				(justify right bottom)
			)
		)
		(property "Datasheet" "https://www.murata.com/products/productdetail?partno=GRM155R61H104KE14%23"
			(at 0 0 270)
			(layer "F.Fab")
			(hide yes)
			(effects
				(font
					(size 1.27 1.27)
					(thickness 0.15)
				)
			)
		)
		(property "Manufacturer" "Murata"
			(at 0 0 270)
			(unlocked yes)
			(layer "F.Fab")
			(hide yes)
			(effects
				(font
					(size 1 1)
					(thickness 0.15)
				)
			)
		)
		(property "MPN" "GRM155R61H104KE14D"
			(at 0 0 270)
			(unlocked yes)
			(layer "F.Fab")
			(hide yes)
			(effects
				(font
					(size 1 1)
					(thickness 0.15)
				)
			)
		)
		(property "Val" "100n"
			(at 0 0 270)
			(unlocked yes)
			(layer "F.Fab")
			(hide yes)
			(effects
				(font
					(size 1 1)
					(thickness 0.15)
				)
			)
		)
		(property "License" "Apache-2.0"
			(at 0 0 270)
			(unlocked yes)
			(layer "F.Fab")
			(hide yes)
			(effects
				(font
					(size 1 1)
					(thickness 0.15)
				)
			)
		)
		(property "Author" "Antmicro"
			(at 0 0 270)
			(unlocked yes)
			(layer "F.Fab")
			(hide yes)
			(effects
				(font
					(size 1 1)
					(thickness 0.15)
				)
			)
		)
		(property "Voltage" "50V"
			(at 0 0 270)
			(unlocked yes)
			(layer "F.Fab")
			(hide yes)
			(effects
				(font
					(size 1 1)
					(thickness 0.15)
				)
			)
		)
		(property "Dielectric" "X5R"
			(at 0 0 270)
			(unlocked yes)
			(layer "F.Fab")
			(hide yes)
			(effects
				(font
					(size 1 1)
					(thickness 0.15)
				)
			)
		)
		(sheetname "/I^{2}C + I3C/")
		(sheetfile "i2c.kicad_sch")
		(attr smd)
		(fp_rect
			(start -0.925 -0.47)
			(end 0.925 0.47)
			(stroke
				(width 0.05)
				(type default)
			)
			(fill no)
			(layer "F.CrtYd")
		)
		(fp_line
			(start -0.494 0.248)
			(end -0.494 -0.25)
			(stroke
				(width 0.15)
				(type solid)
			)
			(layer "F.Fab")
		)
		(fp_line
			(start 0.504 0.248)
			(end -0.494 0.248)
			(stroke
				(width 0.15)
				(type solid)
			)
			(layer "F.Fab")
		)
		(fp_line
			(start -0.494 -0.25)
			(end 0.504 -0.25)
			(stroke
				(width 0.15)
				(type solid)
			)
			(layer "F.Fab")
		)
		(fp_line
			(start 0.504 -0.25)
			(end 0.504 0.248)
			(stroke
				(width 0.15)
				(type solid)
			)
			(layer "F.Fab")
		)
		(fp_text user "${REFERENCE}"
			(at -0.939 4.599 270)
			(layer "F.Fab")
			(effects
				(font
					(size 0.7 0.7)
					(thickness 0.15)
				)
				(justify left bottom)
			)
		)
		(fp_text user "Author: Antmicro"
			(at -0.939 3.399 270)
			(layer "F.Fab")
			(effects
				(font
					(size 0.7 0.7)
					(thickness 0.15)
				)
				(justify left bottom)
			)
		)
		(fp_text user "License: Apache-2.0"
			(at -0.939 5.799 270)
			(layer "F.Fab")
			(effects
				(font
					(size 0.7 0.7)
					(thickness 0.15)
				)
				(justify left bottom)
			)
		)
		(pad "1" smd roundrect
			(at -0.48 0 270)
			(size 0.59 0.64)
			(layers "F.Cu" "F.Mask" "F.Paste")
			(roundrect_rratio 0.25)
			(net 1 "GND")
			(pintype "passive")
		)
		(pad "2" smd roundrect
			(at 0.48 0 270)
			(size 0.59 0.64)
			(layers "F.Cu" "F.Mask" "F.Paste")
			(roundrect_rratio 0.25)
			(net 38 "+3V3_AON")
			(pintype "passive")
		)
	)
	(footprint "antmicro-footprints:C_0402_1005Metric"
		(layer "F.Cu")
		(at 241.774499 181.349 -90)
		(descr "Capacitor SMD 0402")
		(tags "capacitor SMD 0402")
		(property "Reference" "C197"
			(at -1.049 -1.525501 90)
			(layer "F.SilkS")
			(effects
				(font
					(size 0.7 0.7)
					(thickness 0.15)
				)
				(justify right bottom)
			)
		)
		(property "Value" "C_100n_0402"
			(at -1.022927 2.155213 90)
			(layer "F.Fab")
			(effects
				(font
					(size 0.7 0.7)
					(thickness 0.15)
				)
				(justify right bottom)
			)
		)
		(property "Datasheet" "https://www.murata.com/products/productdetail?partno=GRM155R61H104KE14%23"
			(at 0 0 270)
			(layer "F.Fab")
			(hide yes)
			(effects
				(font
					(size 1.27 1.27)
					(thickness 0.15)
				)
			)
		)
		(property "Manufacturer" "Murata"
			(at 0 0 270)
			(unlocked yes)
			(layer "F.Fab")
			(hide yes)
			(effects
				(font
					(size 1 1)
					(thickness 0.15)
				)
			)
		)
		(property "MPN" "GRM155R61H104KE14D"
			(at 0 0 270)
			(unlocked yes)
			(layer "F.Fab")
			(hide yes)
			(effects
				(font
					(size 1 1)
					(thickness 0.15)
				)
			)
		)
		(property "Val" "100n"
			(at 0 0 270)
			(unlocked yes)
			(layer "F.Fab")
			(hide yes)
			(effects
				(font
					(size 1 1)
					(thickness 0.15)
				)
			)
		)
		(property "License" "Apache-2.0"
			(at 0 0 270)
			(unlocked yes)
			(layer "F.Fab")
			(hide yes)
			(effects
				(font
					(size 1 1)
					(thickness 0.15)
				)
			)
		)
		(property "Author" "Antmicro"
			(at 0 0 270)
			(unlocked yes)
			(layer "F.Fab")
			(hide yes)
			(effects
				(font
					(size 1 1)
					(thickness 0.15)
				)
			)
		)
		(property "Voltage" "50V"
			(at 0 0 270)
			(unlocked yes)
			(layer "F.Fab")
			(hide yes)
			(effects
				(font
					(size 1 1)
					(thickness 0.15)
				)
			)
		)
		(property "Dielectric" "X5R"
			(at 0 0 270)
			(unlocked yes)
			(layer "F.Fab")
			(hide yes)
			(effects
				(font
					(size 1 1)
					(thickness 0.15)
				)
			)
		)
		(sheetname "/I^{2}C + I3C/")
		(sheetfile "i2c.kicad_sch")
		(attr smd)
		(fp_rect
			(start -0.925 -0.47)
			(end 0.925 0.47)
			(stroke
				(width 0.05)
				(type default)
			)
			(fill no)
			(layer "F.CrtYd")
		)
		(fp_line
			(start -0.494 0.248)
			(end -0.494 -0.25)
			(stroke
				(width 0.15)
				(type solid)
			)
			(layer "F.Fab")
		)
		(fp_line
			(start 0.504 0.248)
			(end -0.494 0.248)
			(stroke
				(width 0.15)
				(type solid)
			)
			(layer "F.Fab")
		)
		(fp_line
			(start -0.494 -0.25)
			(end 0.504 -0.25)
			(stroke
				(width 0.15)
				(type solid)
			)
			(layer "F.Fab")
		)
		(fp_line
			(start 0.504 -0.25)
			(end 0.504 0.248)
			(stroke
				(width 0.15)
				(type solid)
			)
			(layer "F.Fab")
		)
		(fp_text user "License: Apache-2.0"
			(at -0.939 5.799 270)
			(layer "F.Fab")
			(effects
				(font
					(size 0.7 0.7)
					(thickness 0.15)
				)
				(justify left bottom)
			)
		)
		(fp_text user "${REFERENCE}"
			(at -0.939 4.599 270)
			(layer "F.Fab")
			(effects
				(font
					(size 0.7 0.7)
					(thickness 0.15)
				)
				(justify left bottom)
			)
		)
		(fp_text user "Author: Antmicro"
			(at -0.939 3.399 270)
			(layer "F.Fab")
			(effects
				(font
					(size 0.7 0.7)
					(thickness 0.15)
				)
				(justify left bottom)
			)
		)
		(pad "1" smd roundrect
			(at -0.48 0 270)
			(size 0.59 0.64)
			(layers "F.Cu" "F.Mask" "F.Paste")
			(roundrect_rratio 0.25)
			(net 1 "GND")
			(pintype "passive")
		)
		(pad "2" smd roundrect
			(at 0.48 0 270)
			(size 0.59 0.64)
			(layers "F.Cu" "F.Mask" "F.Paste")
			(roundrect_rratio 0.25)
			(net 38 "+3V3_AON")
			(pintype "passive")
		)
	)
	(footprint "antmicro-footprints:NetTie-2_SMD_Pad0.127mm"
		(layer "F.Cu")
		(at 256.573 162.423998 180)
		(descr "Net tie, 2 pin, 0.127mm  SMD pads")
		(tags "net tie")
		(property "Reference" "NT16"
			(at -0.128 -1.345 0)
			(layer "F.SilkS")
			(hide yes)
			(effects
				(font
					(size 0.7 0.7)
					(thickness 0.15)
				)
				(justify right bottom)
			)
		)
		(property "Value" "Net-Tie_P0.127mm"
			(at 0 1.199 0)
			(layer "F.Fab")
			(effects
				(font
					(size 0.7 0.7)
					(thickness 0.15)
				)
				(justify right bottom)
			)
		)
		(property "MPN" ""
			(at 0 0 180)
			(unlocked yes)
			(layer "F.Fab")
			(hide yes)
			(effects
				(font
					(size 1 1)
					(thickness 0.15)
				)
			)
		)
		(property "Manufacturer" ""
			(at 0 0 180)
			(unlocked yes)
			(layer "F.Fab")
			(hide yes)
			(effects
				(font
					(size 1 1)
					(thickness 0.15)
				)
			)
		)
		(property "Author" "Antmicro"
			(at 0 0 180)
			(unlocked yes)
			(layer "F.Fab")
			(hide yes)
			(effects
				(font
					(size 1 1)
					(thickness 0.15)
				)
			)
		)
		(property "License" "Apache-2.0"
			(at 0 0 180)
			(unlocked yes)
			(layer "F.Fab")
			(hide yes)
			(effects
				(font
					(size 1 1)
					(thickness 0.15)
				)
			)
		)
		(property ki_fp_filters "Net*Tie*")
		(sheetname "/Supply/DC-DC IO/")
		(sheetfile "dc-dc-io.kicad_sch")
		(attr through_hole exclude_from_pos_files exclude_from_bom)
		(net_tie_pad_groups "1, 2")
		(fp_poly
			(pts
				(xy -0.0635 -0.0635) (xy 0.0625 -0.0635) (xy 0.0625 0.0635) (xy -0.0635 0.0635)
			)
			(stroke
				(width 0)
				(type solid)
			)
			(fill yes)
			(layer "F.Cu")
		)
		(fp_poly
			(pts
				(xy 0.2 -0.16) (xy 0.29 -0.07) (xy 0.29 0.07) (xy 0.2 0.16) (xy -0.2 0.16) (xy -0.29 0.07) (xy -0.29 -0.06)
				(xy -0.19 -0.16)
			)
			(stroke
				(width 0.05)
				(type solid)
			)
			(fill no)
			(layer "F.CrtYd")
		)
		(fp_text user "${REFERENCE}"
			(at -0.128 3.2 180)
			(layer "F.Fab")
			(effects
				(font
					(size 0.7 0.7)
					(thickness 0.15)
				)
				(justify left bottom)
			)
		)
		(fp_text user "Author: Antmicro"
			(at -0.128 4.4 180)
			(layer "F.Fab")
			(effects
				(font
					(size 0.7 0.7)
					(thickness 0.15)
				)
				(justify left bottom)
			)
		)
		(fp_text user "License: Apache-2.0"
			(at -0.128 5.6 180)
			(layer "F.Fab")
			(effects
				(font
					(size 0.7 0.7)
					(thickness 0.15)
				)
				(justify left bottom)
			)
		)
		(pad "1" smd roundrect
			(at -0.127 0)
			(size 0.127 0.127)
			(layers "F.Cu")
			(roundrect_rratio 0.5)
			(chamfer_ratio 0)
			(chamfer top_left bottom_left)
			(net 696 "/Supply/DC-DC IO/1V2_SEN_-")
			(pinfunction "1")
			(pintype "passive")
		)
		(pad "2" smd roundrect
			(at 0.126 0 180)
			(size 0.127 0.127)
			(layers "F.Cu")
			(roundrect_rratio 0.5)
			(chamfer_ratio 0)
			(chamfer top_left bottom_left)
			(net 150 "+1V2")
			(pinfunction "2")
			(pintype "passive")
		)
	)
	(footprint "antmicro-footprints:NetTie-2_SMD_Pad0.127mm"
		(layer "F.Cu")
		(at 245.763 177.55 180)
		(descr "Net tie, 2 pin, 0.127mm  SMD pads")
		(tags "net tie")
		(property "Reference" "NT9"
			(at -0.128 -1.345 0)
			(layer "F.SilkS")
			(hide yes)
			(effects
				(font
					(size 0.7 0.7)
					(thickness 0.15)
				)
				(justify right bottom)
			)
		)
		(property "Value" "Net-Tie_P0.127mm"
			(at 0 1.199 0)
			(layer "F.Fab")
			(effects
				(font
					(size 0.7 0.7)
					(thickness 0.15)
				)
				(justify right bottom)
			)
		)
		(property "MPN" ""
			(at 0 0 180)
			(unlocked yes)
			(layer "F.Fab")
			(hide yes)
			(effects
				(font
					(size 1 1)
					(thickness 0.15)
				)
			)
		)
		(property "Manufacturer" ""
			(at 0 0 180)
			(unlocked yes)
			(layer "F.Fab")
			(hide yes)
			(effects
				(font
					(size 1 1)
					(thickness 0.15)
				)
			)
		)
		(property "Author" "Antmicro"
			(at 0 0 180)
			(unlocked yes)
			(layer "F.Fab")
			(hide yes)
			(effects
				(font
					(size 1 1)
					(thickness 0.15)
				)
			)
		)
		(property "License" "Apache-2.0"
			(at 0 0 180)
			(unlocked yes)
			(layer "F.Fab")
			(hide yes)
			(effects
				(font
					(size 1 1)
					(thickness 0.15)
				)
			)
		)
		(property ki_fp_filters "Net*Tie*")
		(sheetname "/Supply/DC-DC AUX, MGT/")
		(sheetfile "dc-dc-aux-mgt.kicad_sch")
		(attr through_hole exclude_from_pos_files exclude_from_bom)
		(net_tie_pad_groups "1, 2")
		(fp_poly
			(pts
				(xy -0.0635 -0.0635) (xy 0.0625 -0.0635) (xy 0.0625 0.0635) (xy -0.0635 0.0635)
			)
			(stroke
				(width 0)
				(type solid)
			)
			(fill yes)
			(layer "F.Cu")
		)
		(fp_poly
			(pts
				(xy 0.2 -0.16) (xy 0.29 -0.07) (xy 0.29 0.07) (xy 0.2 0.16) (xy -0.2 0.16) (xy -0.29 0.07) (xy -0.29 -0.06)
				(xy -0.19 -0.16)
			)
			(stroke
				(width 0.05)
				(type solid)
			)
			(fill no)
			(layer "F.CrtYd")
		)
		(fp_text user "License: Apache-2.0"
			(at -0.128 5.6 180)
			(layer "F.Fab")
			(effects
				(font
					(size 0.7 0.7)
					(thickness 0.15)
				)
				(justify left bottom)
			)
		)
		(fp_text user "Author: Antmicro"
			(at -0.128 4.4 180)
			(layer "F.Fab")
			(effects
				(font
					(size 0.7 0.7)
					(thickness 0.15)
				)
				(justify left bottom)
			)
		)
		(fp_text user "${REFERENCE}"
			(at -0.128 3.2 180)
			(layer "F.Fab")
			(effects
				(font
					(size 0.7 0.7)
					(thickness 0.15)
				)
				(justify left bottom)
			)
		)
		(pad "1" smd roundrect
			(at -0.127 0)
			(size 0.127 0.127)
			(layers "F.Cu")
			(roundrect_rratio 0.5)
			(chamfer_ratio 0)
			(chamfer top_left bottom_left)
			(net 689 "/Supply/DC-DC AUX, MGT/1V8_SEN_-")
			(pinfunction "1")
			(pintype "passive")
		)
		(pad "2" smd roundrect
			(at 0.126 0 180)
			(size 0.127 0.127)
			(layers "F.Cu")
			(roundrect_rratio 0.5)
			(chamfer_ratio 0)
			(chamfer top_left bottom_left)
			(net 797 "+1V8")
			(pinfunction "2")
			(pintype "passive")
		)
	)
	(footprint "antmicro-footprints:Bus_DDR5_Socket_Amphenol_DDR504111002KQ"
		(layer "F.Cu")
		(at 188.325 108.297 180)
		(descr "DIMM Connectors DDR5 SMD 288P")
		(property "Reference" "J2"
			(at 67.825 3.797 0)
			(layer "F.SilkS")
			(effects
				(font
					(size 0.7 0.7)
					(thickness 0.15)
				)
				(justify right bottom)
			)
		)
		(property "Value" "Bus_DDR5_DDR504111002KQ"
			(at 0 4.2 0)
			(layer "F.Fab")
			(effects
				(font
					(size 0.7 0.7)
					(thickness 0.15)
				)
				(justify right bottom)
			)
		)
		(property "Datasheet" "https://www.amphenol-icc.com/ddr5-smt-ddr504111002kq.html"
			(at 0 0 180)
			(layer "F.Fab")
			(hide yes)
			(effects
				(font
					(size 1.27 1.27)
					(thickness 0.15)
				)
			)
		)
		(property "Manufacturer" "Amphenol"
			(at 0 0 180)
			(unlocked yes)
			(layer "F.Fab")
			(hide yes)
			(effects
				(font
					(size 1 1)
					(thickness 0.15)
				)
			)
		)
		(property "MPN" "DDR504111002KQ"
			(at 0 0 180)
			(unlocked yes)
			(layer "F.Fab")
			(hide yes)
			(effects
				(font
					(size 1 1)
					(thickness 0.15)
				)
			)
		)
		(property "Author" "Antmicro"
			(at 0 0 180)
			(unlocked yes)
			(layer "F.Fab")
			(hide yes)
			(effects
				(font
					(size 1 1)
					(thickness 0.15)
				)
			)
		)
		(property "License" "Apache-2.0"
			(at 0 0 180)
			(unlocked yes)
			(layer "F.Fab")
			(hide yes)
			(effects
				(font
					(size 1 1)
					(thickness 0.15)
				)
			)
		)
		(sheetname "/DDR5 RDIMM/")
		(sheetfile "ddr5-rdimm.kicad_sch")
		(attr smd)
		(fp_line
			(start 70.998 3.047)
			(end 63.975 3.047)
			(stroke
				(width 0.15)
				(type solid)
			)
			(layer "F.SilkS")
		)
		(fp_line
			(start 70.998 -3.051)
			(end 70.998 3.047)
			(stroke
				(width 0.15)
				(type solid)
			)
			(layer "F.SilkS")
		)
		(fp_line
			(start 63.975 -3.051)
			(end 70.998 -3.051)
			(stroke
				(width 0.15)
				(type solid)
			)
			(layer "F.SilkS")
		)
		(fp_line
			(start -63.976 3.047)
			(end -71 3.047)
			(stroke
				(width 0.15)
				(type solid)
			)
			(layer "F.SilkS")
		)
		(fp_line
			(start -71 3.047)
			(end -71 -3.051)
			(stroke
				(width 0.15)
				(type solid)
			)
			(layer "F.SilkS")
		)
		(fp_line
			(start -71 -3.051)
			(end -63.976 -3.051)
			(stroke
				(width 0.15)
				(type solid)
			)
			(layer "F.SilkS")
		)
		(fp_circle
			(center -64.2 3.6)
			(end -64.16 3.6)
			(stroke
				(width 0.15)
				(type solid)
			)
			(fill yes)
			(layer "F.SilkS")
		)
		(fp_rect
			(start -76.25 -3.31)
			(end 75.98 3.24)
			(stroke
				(width 0.05)
				(type solid)
			)
			(fill no)
			(layer "F.CrtYd")
		)
		(fp_line
			(start 70.998 3.047)
			(end -71 3.047)
			(stroke
				(width 0.15)
				(type solid)
			)
			(layer "F.Fab")
		)
		(fp_line
			(start 70.998 -3.051)
			(end 70.998 3.047)
			(stroke
				(width 0.15)
				(type solid)
			)
			(layer "F.Fab")
		)
		(fp_line
			(start -71 3.047)
			(end -71 -3.051)
			(stroke
				(width 0.15)
				(type solid)
			)
			(layer "F.Fab")
		)
		(fp_line
			(start -71 -3.051)
			(end 70.998 -3.051)
			(stroke
				(width 0.15)
				(type solid)
			)
			(layer "F.Fab")
		)
		(fp_text user "${REFERENCE}"
			(at -76.25 5.5 180)
			(layer "F.Fab")
			(effects
				(font
					(size 0.7 0.7)
					(thickness 0.15)
				)
				(justify left bottom)
			)
		)
		(fp_text user "License: Apache-2.0"
			(at -76.25 7.901 180)
			(layer "F.Fab")
			(effects
				(font
					(size 0.7 0.7)
					(thickness 0.15)
				)
				(justify left bottom)
			)
		)
		(fp_text user "Author: Antmicro"
			(at -76.25 6.7 180)
			(layer "F.Fab")
			(effects
				(font
					(size 0.7 0.7)
					(thickness 0.15)
				)
				(justify left bottom)
			)
		)
		(pad "1" smd rect
			(at -63.326 2.297 270)
			(size 1.8 0.57)
			(layers "F.Cu" "F.Mask" "F.Paste")
			(net 802 "/DDR5 RDIMM/VIN_BULK")
			(pinfunction "VIN_BULK")
			(pintype "power_in")
		)
		(pad "2" smd rect
			(at -62.476 2.297 270)
			(size 1.8 0.57)
			(layers "F.Cu" "F.Mask" "F.Paste")
			(net 308 "unconnected-(J2B-RFU-Pad2)")
			(pinfunction "RFU")
			(pintype "no_connect")
		)
		(pad "3" smd rect
			(at -61.625 2.297 270)
			(size 1.8 0.57)
			(layers "F.Cu" "F.Mask" "F.Paste")
			(net 803 "/DDR5 RDIMM/VIN_MGMT")
			(pinfunction "VIN_MGMT")
			(pintype "power_in")
		)
		(pad "4" smd rect
			(at -60.775 2.297 270)
			(size 1.8 0.57)
			(layers "F.Cu" "F.Mask" "F.Paste")
			(net 460 "/DDR5 RDIMM/DDR.SCL")
			(pinfunction "HSCL")
			(pintype "input")
		)
		(pad "5" smd rect
			(at -59.926 2.297 270)
			(size 1.8 0.57)
			(layers "F.Cu" "F.Mask" "F.Paste")
			(net 459 "/DDR5 RDIMM/DDR.SDA")
			(pinfunction "HSDA")
			(pintype "input")
		)
		(pad "6" smd rect
			(at -59.076 2.297 270)
			(size 1.8 0.57)
			(layers "F.Cu" "F.Mask" "F.Paste")
			(net 1 "GND")
			(pinfunction "VSS")
			(pintype "passive")
		)
		(pad "7" smd rect
			(at -58.226 2.297 270)
			(size 1.8 0.57)
			(layers "F.Cu" "F.Mask" "F.Paste")
			(net 51 "/DDR5 RDIMM/A.DQ0")
			(pinfunction "DQ0_A")
			(pintype "input")
		)
		(pad "8" smd rect
			(at -57.375 2.297 270)
			(size 1.8 0.57)
			(layers "F.Cu" "F.Mask" "F.Paste")
			(net 1 "GND")
			(pinfunction "VSS")
			(pintype "passive")
		)
		(pad "9" smd rect
			(at -56.525 2.297 270)
			(size 1.8 0.57)
			(layers "F.Cu" "F.Mask" "F.Paste")
			(net 52 "/DDR5 RDIMM/A.DQ1")
			(pinfunction "DQ1_A")
			(pintype "input")
		)
		(pad "10" smd rect
			(at -55.676 2.297 270)
			(size 1.8 0.57)
			(layers "F.Cu" "F.Mask" "F.Paste")
			(net 1 "GND")
			(pinfunction "VSS")
			(pintype "power_in")
		)
		(pad "11" smd rect
			(at -54.826 2.297 270)
			(size 1.8 0.57)
			(layers "F.Cu" "F.Mask" "F.Paste")
			(net 94 "/DDR5 RDIMM/A.DQS0_P")
			(pinfunction "DQS0_A_T")
			(pintype "input")
		)
		(pad "12" smd rect
			(at -53.976 2.297 270)
			(size 1.8 0.57)
			(layers "F.Cu" "F.Mask" "F.Paste")
			(net 101 "/DDR5 RDIMM/A.DQS0_N")
			(pinfunction "DQS0_A_C")
			(pintype "input")
		)
		(pad "13" smd rect
			(at -53.125 2.297 270)
			(size 1.8 0.57)
			(layers "F.Cu" "F.Mask" "F.Paste")
			(net 1 "GND")
			(pinfunction "VSS")
			(pintype "passive")
		)
		(pad "14" smd rect
			(at -52.275 2.297 270)
			(size 1.8 0.57)
			(layers "F.Cu" "F.Mask" "F.Paste")
			(net 53 "/DDR5 RDIMM/A.DQ4")
			(pinfunction "DQ4_A")
			(pintype "input")
		)
		(pad "15" smd rect
			(at -51.426 2.297 270)
			(size 1.8 0.57)
			(layers "F.Cu" "F.Mask" "F.Paste")
			(net 1 "GND")
			(pinfunction "VSS")
			(pintype "passive")
		)
		(pad "16" smd rect
			(at -50.576 2.297 270)
			(size 1.8 0.57)
			(layers "F.Cu" "F.Mask" "F.Paste")
			(net 54 "/DDR5 RDIMM/A.DQ5")
			(pinfunction "DQ5_A")
			(pintype "input")
		)
		(pad "17" smd rect
			(at -49.726 2.297 270)
			(size 1.8 0.57)
			(layers "F.Cu" "F.Mask" "F.Paste")
			(net 1 "GND")
			(pinfunction "VSS")
			(pintype "passive")
		)
		(pad "18" smd rect
			(at -48.875 2.297 270)
			(size 1.8 0.57)
			(layers "F.Cu" "F.Mask" "F.Paste")
			(net 55 "/DDR5 RDIMM/A.DQ8")
			(pinfunction "DQ8_A")
			(pintype "input")
		)
		(pad "19" smd rect
			(at -48.025 2.297 270)
			(size 1.8 0.57)
			(layers "F.Cu" "F.Mask" "F.Paste")
			(net 1 "GND")
			(pinfunction "VSS")
			(pintype "passive")
		)
		(pad "20" smd rect
			(at -47.176 2.297 270)
			(size 1.8 0.57)
			(layers "F.Cu" "F.Mask" "F.Paste")
			(net 56 "/DDR5 RDIMM/A.DQ9")
			(pinfunction "DQ9_A")
			(pintype "input")
		)
		(pad "21" smd rect
			(at -46.326 2.297 270)
			(size 1.8 0.57)
			(layers "F.Cu" "F.Mask" "F.Paste")
			(net 1 "GND")
			(pinfunction "VSS")
			(pintype "passive")
		)
		(pad "22" smd rect
			(at -45.476 2.297 270)
			(size 1.8 0.57)
			(layers "F.Cu" "F.Mask" "F.Paste")
			(net 102 "/DDR5 RDIMM/A.DQS1_P")
			(pinfunction "DQS1_A_T")
			(pintype "input")
		)
		(pad "23" smd rect
			(at -44.625 2.297 270)
			(size 1.8 0.57)
			(layers "F.Cu" "F.Mask" "F.Paste")
			(net 104 "/DDR5 RDIMM/A.DQS1_N")
			(pinfunction "DQS1_A_C")
			(pintype "input")
		)
		(pad "24" smd rect
			(at -43.775 2.297 270)
			(size 1.8 0.57)
			(layers "F.Cu" "F.Mask" "F.Paste")
			(net 1 "GND")
			(pinfunction "VSS")
			(pintype "passive")
		)
		(pad "25" smd rect
			(at -42.926 2.297 270)
			(size 1.8 0.57)
			(layers "F.Cu" "F.Mask" "F.Paste")
			(net 57 "/DDR5 RDIMM/A.DQ12")
			(pinfunction "DQ12_A")
			(pintype "input")
		)
		(pad "26" smd rect
			(at -42.076 2.297 270)
			(size 1.8 0.57)
			(layers "F.Cu" "F.Mask" "F.Paste")
			(net 1 "GND")
			(pinfunction "VSS")
			(pintype "passive")
		)
		(pad "27" smd rect
			(at -41.226 2.297 270)
			(size 1.8 0.57)
			(layers "F.Cu" "F.Mask" "F.Paste")
			(net 58 "/DDR5 RDIMM/A.DQ13")
			(pinfunction "DQ13_A")
			(pintype "input")
		)
		(pad "28" smd rect
			(at -40.375 2.297 270)
			(size 1.8 0.57)
			(layers "F.Cu" "F.Mask" "F.Paste")
			(net 1 "GND")
			(pinfunction "VSS")
			(pintype "passive")
		)
		(pad "29" smd rect
			(at -39.525 2.297 270)
			(size 1.8 0.57)
			(layers "F.Cu" "F.Mask" "F.Paste")
			(net 59 "/DDR5 RDIMM/A.DQ16")
			(pinfunction "DQ16_A")
			(pintype "input")
		)
		(pad "30" smd rect
			(at -38.676 2.297 270)
			(size 1.8 0.57)
			(layers "F.Cu" "F.Mask" "F.Paste")
			(net 1 "GND")
			(pinfunction "VSS")
			(pintype "passive")
		)
		(pad "31" smd rect
			(at -37.826 2.297 270)
			(size 1.8 0.57)
			(layers "F.Cu" "F.Mask" "F.Paste")
			(net 60 "/DDR5 RDIMM/A.DQ17")
			(pinfunction "DQ17_A")
			(pintype "input")
		)
		(pad "32" smd rect
			(at -36.976 2.297 270)
			(size 1.8 0.57)
			(layers "F.Cu" "F.Mask" "F.Paste")
			(net 1 "GND")
			(pinfunction "VSS")
			(pintype "passive")
		)
		(pad "33" smd rect
			(at -36.125 2.297 270)
			(size 1.8 0.57)
			(layers "F.Cu" "F.Mask" "F.Paste")
			(net 108 "/DDR5 RDIMM/A.DQS2_P")
			(pinfunction "DQS2_A_T")
			(pintype "input")
		)
		(pad "34" smd rect
			(at -35.275 2.297 270)
			(size 1.8 0.57)
			(layers "F.Cu" "F.Mask" "F.Paste")
			(net 109 "/DDR5 RDIMM/A.DQS2_N")
			(pinfunction "DQS2_A_C")
			(pintype "input")
		)
		(pad "35" smd rect
			(at -34.426 2.297 270)
			(size 1.8 0.57)
			(layers "F.Cu" "F.Mask" "F.Paste")
			(net 1 "GND")
			(pinfunction "VSS")
			(pintype "passive")
		)
		(pad "36" smd rect
			(at -33.576 2.297 270)
			(size 1.8 0.57)
			(layers "F.Cu" "F.Mask" "F.Paste")
			(net 61 "/DDR5 RDIMM/A.DQ20")
			(pinfunction "DQ20_A")
			(pintype "input")
		)
		(pad "37" smd rect
			(at -32.726 2.297 270)
			(size 1.8 0.57)
			(layers "F.Cu" "F.Mask" "F.Paste")
			(net 1 "GND")
			(pinfunction "VSS")
			(pintype "passive")
		)
		(pad "38" smd rect
			(at -31.875 2.297 270)
			(size 1.8 0.57)
			(layers "F.Cu" "F.Mask" "F.Paste")
			(net 62 "/DDR5 RDIMM/A.DQ21")
			(pinfunction "DQ21_A")
			(pintype "input")
		)
		(pad "39" smd rect
			(at -31.026 2.297 270)
			(size 1.8 0.57)
			(layers "F.Cu" "F.Mask" "F.Paste")
			(net 1 "GND")
			(pinfunction "VSS")
			(pintype "passive")
		)
		(pad "40" smd rect
			(at -30.177 2.297 270)
			(size 1.8 0.57)
			(layers "F.Cu" "F.Mask" "F.Paste")
			(net 63 "/DDR5 RDIMM/A.DQ24")
			(pinfunction "DQ24_A")
			(pintype "input")
		)
		(pad "41" smd rect
			(at -29.325 2.297 270)
			(size 1.8 0.57)
			(layers "F.Cu" "F.Mask" "F.Paste")
			(net 1 "GND")
			(pinfunction "VSS")
			(pintype "passive")
		)
		(pad "42" smd rect
			(at -28.476 2.297 270)
			(size 1.8 0.57)
			(layers "F.Cu" "F.Mask" "F.Paste")
			(net 64 "/DDR5 RDIMM/A.DQ25")
			(pinfunction "DQ25_A")
			(pintype "input")
		)
		(pad "43" smd rect
			(at -27.625 2.297 270)
			(size 1.8 0.57)
			(layers "F.Cu" "F.Mask" "F.Paste")
			(net 1 "GND")
			(pinfunction "VSS")
			(pintype "passive")
		)
		(pad "44" smd rect
			(at -26.776 2.297 270)
			(size 1.8 0.57)
			(layers "F.Cu" "F.Mask" "F.Paste")
			(net 114 "/DDR5 RDIMM/A.DQS3_P")
			(pinfunction "DQS3_A_T")
			(pintype "input")
		)
		(pad "45" smd rect
			(at -25.927 2.297 270)
			(size 1.8 0.57)
			(layers "F.Cu" "F.Mask" "F.Paste")
			(net 115 "/DDR5 RDIMM/A.DQS3_N")
			(pinfunction "DQS3_A_C")
			(pintype "input")
		)
		(pad "46" smd rect
			(at -25.075 2.297 270)
			(size 1.8 0.57)
			(layers "F.Cu" "F.Mask" "F.Paste")
			(net 1 "GND")
			(pinfunction "VSS")
			(pintype "passive")
		)
		(pad "47" smd rect
			(at -24.226 2.297 270)
			(size 1.8 0.57)
			(layers "F.Cu" "F.Mask" "F.Paste")
			(net 65 "/DDR5 RDIMM/A.DQ28")
			(pinfunction "DQ28_A")
			(pintype "input")
		)
		(pad "48" smd rect
			(at -23.375 2.297 270)
			(size 1.8 0.57)
			(layers "F.Cu" "F.Mask" "F.Paste")
			(net 1 "GND")
			(pinfunction "VSS")
			(pintype "passive")
		)
		(pad "49" smd rect
			(at -22.526 2.297 270)
			(size 1.8 0.57)
			(layers "F.Cu" "F.Mask" "F.Paste")
			(net 66 "/DDR5 RDIMM/A.DQ29")
			(pinfunction "DQ29_A")
			(pintype "input")
		)
		(pad "50" smd rect
			(at -21.677 2.297 270)
			(size 1.8 0.57)
			(layers "F.Cu" "F.Mask" "F.Paste")
			(net 1 "GND")
			(pinfunction "VSS")
			(pintype "passive")
		)
		(pad "51" smd rect
			(at -20.825 2.297 270)
			(size 1.8 0.57)
			(layers "F.Cu" "F.Mask" "F.Paste")
			(net 67 "/DDR5 RDIMM/A.CB0")
			(pinfunction "CB0_A")
			(pintype "input")
		)
		(pad "52" smd rect
			(at -19.976 2.297 270)
			(size 1.8 0.57)
			(layers "F.Cu" "F.Mask" "F.Paste")
			(net 1 "GND")
			(pinfunction "VSS")
			(pintype "passive")
		)
		(pad "53" smd rect
			(at -19.125 2.297 270)
			(size 1.8 0.57)
			(layers "F.Cu" "F.Mask" "F.Paste")
			(net 68 "/DDR5 RDIMM/A.CB1")
			(pinfunction "CB1_A")
			(pintype "input")
		)
		(pad "54" smd rect
			(at -18.276 2.297 270)
			(size 1.8 0.57)
			(layers "F.Cu" "F.Mask" "F.Paste")
			(net 1 "GND")
			(pinfunction "VSS")
			(pintype "passive")
		)
		(pad "55" smd rect
			(at -17.427 2.297 270)
			(size 1.8 0.57)
			(layers "F.Cu" "F.Mask" "F.Paste")
			(net 120 "/DDR5 RDIMM/A.DQS4_P")
			(pinfunction "DQS4_A_T")
			(pintype "input")
		)
		(pad "56" smd rect
			(at -16.575 2.297 270)
			(size 1.8 0.57)
			(layers "F.Cu" "F.Mask" "F.Paste")
			(net 121 "/DDR5 RDIMM/A.DQS4_N")
			(pinfunction "DQS4_A_C")
			(pintype "input")
		)
		(pad "57" smd rect
			(at -15.725 2.297 270)
			(size 1.8 0.57)
			(layers "F.Cu" "F.Mask" "F.Paste")
			(net 1 "GND")
			(pinfunction "VSS")
			(pintype "passive")
		)
		(pad "58" smd rect
			(at -14.875 2.297 270)
			(size 1.8 0.57)
			(layers "F.Cu" "F.Mask" "F.Paste")
			(net 70 "/DDR5 RDIMM/A.CB4")
			(pinfunction "CB4_A")
			(pintype "input")
		)
		(pad "59" smd rect
			(at -14.026 2.297 270)
			(size 1.8 0.57)
			(layers "F.Cu" "F.Mask" "F.Paste")
			(net 1 "GND")
			(pinfunction "VSS")
			(pintype "passive")
		)
		(pad "60" smd rect
			(at -13.176 2.297 270)
			(size 1.8 0.57)
			(layers "F.Cu" "F.Mask" "F.Paste")
			(net 71 "/DDR5 RDIMM/A.CB5")
			(pinfunction "CB5_A")
			(pintype "input")
		)
		(pad "61" smd rect
			(at -12.326 2.297 270)
			(size 1.8 0.57)
			(layers "F.Cu" "F.Mask" "F.Paste")
			(net 1 "GND")
			(pinfunction "VSS")
			(pintype "passive")
		)
		(pad "62" smd rect
			(at -11.475 2.297 270)
			(size 1.8 0.57)
			(layers "F.Cu" "F.Mask" "F.Paste")
			(net 72 "/DDR5 RDIMM/CTRL.~{ALERT}")
			(pinfunction "ALERT_N")
			(pintype "input")
		)
		(pad "63" smd rect
			(at -10.625 2.297 270)
			(size 1.8 0.57)
			(layers "F.Cu" "F.Mask" "F.Paste")
			(net 1 "GND")
			(pinfunction "VSS")
			(pintype "passive")
		)
		(pad "64" smd rect
			(at -9.776 2.297 270)
			(size 1.8 0.57)
			(layers "F.Cu" "F.Mask" "F.Paste")
			(net 73 "/DDR5 RDIMM/A.CS0_c")
			(pinfunction "CS0_A_N")
			(pintype "input")
		)
		(pad "65" smd rect
			(at -8.926 2.297 270)
			(size 1.8 0.57)
			(layers "F.Cu" "F.Mask" "F.Paste")
			(net 1 "GND")
			(pinfunction "VSS")
			(pintype "passive")
		)
		(pad "66" smd rect
			(at -8.075 2.297 270)
			(size 1.8 0.57)
			(layers "F.Cu" "F.Mask" "F.Paste")
			(net 74 "/DDR5 RDIMM/A.CA0")
			(pinfunction "CA0_A")
			(pintype "input")
		)
		(pad "67" smd rect
			(at -7.226 2.297 270)
			(size 1.8 0.57)
			(layers "F.Cu" "F.Mask" "F.Paste")
			(net 1 "GND")
			(pinfunction "VSS")
			(pintype "passive")
		)
		(pad "68" smd rect
			(at -6.375 2.297 270)
			(size 1.8 0.57)
			(layers "F.Cu" "F.Mask" "F.Paste")
			(net 75 "/DDR5 RDIMM/A.CA2")
			(pinfunction "CA2_A")
			(pintype "input")
		)
		(pad "69" smd rect
			(at -5.526 2.297 270)
			(size 1.8 0.57)
			(layers "F.Cu" "F.Mask" "F.Paste")
			(net 1 "GND")
			(pinfunction "VSS")
			(pintype "passive")
		)
		(pad "70" smd rect
			(at -4.675 2.297 270)
			(size 1.8 0.57)
			(layers "F.Cu" "F.Mask" "F.Paste")
			(net 76 "/DDR5 RDIMM/A.CA4")
			(pinfunction "CA4_A")
			(pintype "input")
		)
		(pad "71" smd rect
			(at -3.826 2.297 270)
			(size 1.8 0.57)
			(layers "F.Cu" "F.Mask" "F.Paste")
			(net 1 "GND")
			(pinfunction "VSS")
			(pintype "passive")
		)
		(pad "72" smd rect
			(at -2.976 2.297 270)
			(size 1.8 0.57)
			(layers "F.Cu" "F.Mask" "F.Paste")
			(net 77 "/DDR5 RDIMM/A.CA6")
			(pinfunction "CA6_A")
			(pintype "input")
		)
		(pad "73" smd rect
			(at -2.125 2.297 270)
			(size 1.8 0.57)
			(layers "F.Cu" "F.Mask" "F.Paste")
			(net 1 "GND")
			(pinfunction "VSS")
			(pintype "passive")
		)
		(pad "74" smd rect
			(at -1.276 2.297 270)
			(size 1.8 0.57)
			(layers "F.Cu" "F.Mask" "F.Paste")
			(net 78 "/DDR5 RDIMM/A.PAR")
			(pinfunction "PAR_A")
			(pintype "input")
		)
		(pad "75" smd rect
			(at -0.425 2.297 270)
			(size 1.8 0.57)
			(layers "F.Cu" "F.Mask" "F.Paste")
			(net 703 "/DDR5 RDIMM/VSS_DET1")
			(pinfunction "VSS_DET")
			(pintype "passive")
		)
		(pad "76" smd rect
			(at 5.525 2.297 270)
			(size 1.8 0.57)
			(layers "F.Cu" "F.Mask" "F.Paste")
			(net 79 "/DDR5 RDIMM/B.CA0")
			(pinfunction "CA0_B")
			(pintype "input")
		)
		(pad "77" smd rect
			(at 6.373 2.297 270)
			(size 1.8 0.57)
			(layers "F.Cu" "F.Mask" "F.Paste")
			(net 1 "GND")
			(pinfunction "VSS")
			(pintype "passive")
		)
		(pad "78" smd rect
			(at 7.224 2.297 270)
			(size 1.8 0.57)
			(layers "F.Cu" "F.Mask" "F.Paste")
			(net 80 "/DDR5 RDIMM/B.CA1")
			(pinfunction "CA2_B")
			(pintype "input")
		)
		(pad "79" smd rect
			(at 8.073 2.297 270)
			(size 1.8 0.57)
			(layers "F.Cu" "F.Mask" "F.Paste")
			(net 1 "GND")
			(pinfunction "VSS")
			(pintype "passive")
		)
		(pad "80" smd rect
			(at 8.925 2.297 270)
			(size 1.8 0.57)
			(layers "F.Cu" "F.Mask" "F.Paste")
			(net 81 "/DDR5 RDIMM/B.CA4")
			(pinfunction "CA4_B")
			(pintype "input")
		)
		(pad "81" smd rect
			(at 9.775 2.297 270)
			(size 1.8 0.57)
			(layers "F.Cu" "F.Mask" "F.Paste")
			(net 1 "GND")
			(pinfunction "VSS")
			(pintype "passive")
		)
		(pad "82" smd rect
			(at 10.624 2.297 270)
			(size 1.8 0.57)
			(layers "F.Cu" "F.Mask" "F.Paste")
			(net 82 "/DDR5 RDIMM/B.CA6")
			(pinfunction "CA6_B")
			(pintype "input")
		)
		(pad "83" smd rect
			(at 11.473 2.297 270)
			(size 1.8 0.57)
			(layers "F.Cu" "F.Mask" "F.Paste")
			(net 1 "GND")
			(pinfunction "VSS")
			(pintype "passive")
		)
		(pad "84" smd rect
			(at 12.323 2.297 270)
			(size 1.8 0.57)
			(layers "F.Cu" "F.Mask" "F.Paste")
			(net 83 "/DDR5 RDIMM/B.CS0_c")
			(pinfunction "CS0_B_N")
			(pintype "input")
		)
		(pad "85" smd rect
			(at 13.175 2.297 270)
			(size 1.8 0.57)
			(layers "F.Cu" "F.Mask" "F.Paste")
			(net 1 "GND")
			(pinfunction "VSS")
			(pintype "passive")
		)
		(pad "86" smd rect
			(at 14.025 2.297 270)
			(size 1.8 0.57)
			(layers "F.Cu" "F.Mask" "F.Paste")
			(net 84 "/DDR5 RDIMM/CTRL.DLBDQ")
			(pinfunction "DLBDQ")
			(pintype "input")
		)
		(pad "87" smd rect
			(at 14.874 2.297 270)
			(size 1.8 0.57)
			(layers "F.Cu" "F.Mask" "F.Paste")
			(net 85 "/DDR5 RDIMM/CTRL.DLBDQS")
			(pinfunction "DLBDQS")
			(pintype "input")
		)
		(pad "88" smd rect
			(at 15.723 2.297 270)
			(size 1.8 0.57)
			(layers "F.Cu" "F.Mask" "F.Paste")
			(net 1 "GND")
			(pinfunction "VSS")
			(pintype "passive")
		)
		(pad "89" smd rect
			(at 16.574 2.297 270)
			(size 1.8 0.57)
			(layers "F.Cu" "F.Mask" "F.Paste")
			(net 99 "/DDR5 RDIMM/B.CB4")
			(pinfunction "CB4_B")
			(pintype "input")
		)
		(pad "90" smd rect
			(at 17.425 2.297 270)
			(size 1.8 0.57)
			(layers "F.Cu" "F.Mask" "F.Paste")
			(net 1 "GND")
			(pinfunction "VSS")
			(pintype "passive")
		)
		(pad "91" smd rect
			(at 18.274 2.297 270)
			(size 1.8 0.57)
			(layers "F.Cu" "F.Mask" "F.Paste")
			(net 100 "/DDR5 RDIMM/B.CB5")
			(pinfunction "CB5_B")
			(pintype "input")
		)
		(pad "92" smd rect
			(at 19.123 2.297 270)
			(size 1.8 0.57)
			(layers "F.Cu" "F.Mask" "F.Paste")
			(net 1 "GND")
			(pinfunction "VSS")
			(pintype "passive")
		)
		(pad "93" smd rect
			(at 19.975 2.297 270)
			(size 1.8 0.57)
			(layers "F.Cu" "F.Mask" "F.Paste")
			(net 126 "/DDR5 RDIMM/B.DQS9_P")
			(pinfunction "DQS9_B_T")
			(pintype "input")
		)
		(pad "94" smd rect
			(at 20.824 2.297 270)
			(size 1.8 0.57)
			(layers "F.Cu" "F.Mask" "F.Paste")
			(net 127 "/DDR5 RDIMM/B.DQS9_N")
			(pinfunction "DQS9_B_C")
			(pintype "input")
		)
		(pad "95" smd rect
			(at 21.675 2.297 270)
			(size 1.8 0.57)
			(layers "F.Cu" "F.Mask" "F.Paste")
			(net 1 "GND")
			(pinfunction "VSS")
			(pintype "passive")
		)
		(pad "96" smd rect
			(at 22.524 2.297 270)
			(size 1.8 0.57)
			(layers "F.Cu" "F.Mask" "F.Paste")
			(net 103 "/DDR5 RDIMM/B.CB0")
			(pinfunction "CB0_B")
			(pintype "input")
		)
		(pad "97" smd rect
			(at 23.373 2.297 270)
			(size 1.8 0.57)
			(layers "F.Cu" "F.Mask" "F.Paste")
			(net 1 "GND")
			(pinfunction "VSS")
			(pintype "passive")
		)
		(pad "98" smd rect
			(at 24.225 2.297 270)
			(size 1.8 0.57)
			(layers "F.Cu" "F.Mask" "F.Paste")
			(net 105 "/DDR5 RDIMM/B.CB1")
			(pinfunction "CB1_B")
			(pintype "input")
		)
		(pad "99" smd rect
			(at 25.074 2.297 270)
			(size 1.8 0.57)
			(layers "F.Cu" "F.Mask" "F.Paste")
			(net 1 "GND")
			(pinfunction "VSS")
			(pintype "passive")
		)
		(pad "100" smd rect
			(at 25.925 2.297 270)
			(size 1.8 0.57)
			(layers "F.Cu" "F.Mask" "F.Paste")
			(net 106 "/DDR5 RDIMM/B.DQ0")
			(pinfunction "DQ0_B")
			(pintype "input")
		)
		(pad "101" smd rect
			(at 26.774 2.297 270)
			(size 1.8 0.57)
			(layers "F.Cu" "F.Mask" "F.Paste")
			(net 1 "GND")
			(pinfunction "VSS")
			(pintype "passive")
		)
		(pad "102" smd rect
			(at 27.623 2.297 270)
			(size 1.8 0.57)
			(layers "F.Cu" "F.Mask" "F.Paste")
			(net 107 "/DDR5 RDIMM/B.DQ1")
			(pinfunction "DQ1_B")
			(pintype "input")
		)
		(pad "103" smd rect
			(at 28.475 2.297 270)
			(size 1.8 0.57)
			(layers "F.Cu" "F.Mask" "F.Paste")
			(net 1 "GND")
			(pinfunction "VSS")
			(pintype "passive")
		)
		(pad "104" smd rect
			(at 29.324 2.297 270)
			(size 1.8 0.57)
			(layers "F.Cu" "F.Mask" "F.Paste")
			(net 132 "/DDR5 RDIMM/B.DQS0_P")
			(pinfunction "DQS0_B_T")
			(pintype "input")
		)
		(pad "105" smd rect
			(at 30.175 2.297 270)
			(size 1.8 0.57)
			(layers "F.Cu" "F.Mask" "F.Paste")
			(net 133 "/DDR5 RDIMM/B.DQS0_N")
			(pinfunction "DQS0_B_C")
			(pintype "input")
		)
		(pad "106" smd rect
			(at 31.024 2.297 270)
			(size 1.8 0.57)
			(layers "F.Cu" "F.Mask" "F.Paste")
			(net 1 "GND")
			(pinfunction "VSS")
			(pintype "passive")
		)
		(pad "107" smd rect
			(at 31.873 2.297 270)
			(size 1.8 0.57)
			(layers "F.Cu" "F.Mask" "F.Paste")
			(net 110 "/DDR5 RDIMM/B.DQ4")
			(pinfunction "DQ4_B")
			(pintype "input")
		)
		(pad "108" smd rect
			(at 32.725 2.297 270)
			(size 1.8 0.57)
			(layers "F.Cu" "F.Mask" "F.Paste")
			(net 1 "GND")
			(pinfunction "VSS")
			(pintype "passive")
		)
		(pad "109" smd rect
			(at 33.575 2.297 270)
			(size 1.8 0.57)
			(layers "F.Cu" "F.Mask" "F.Paste")
			(net 111 "/DDR5 RDIMM/B.DQ5")
			(pinfunction "DQ5_B")
			(pintype "input")
		)
		(pad "110" smd rect
			(at 34.423 2.297 270)
			(size 1.8 0.57)
			(layers "F.Cu" "F.Mask" "F.Paste")
			(net 1 "GND")
			(pinfunction "VSS")
			(pintype "passive")
		)
		(pad "111" smd rect
			(at 35.274 2.297 270)
			(size 1.8 0.57)
			(layers "F.Cu" "F.Mask" "F.Paste")
			(net 112 "/DDR5 RDIMM/B.DQ8")
			(pinfunction "DQ8_B")
			(pintype "input")
		)
		(pad "112" smd rect
			(at 36.124 2.297 270)
			(size 1.8 0.57)
			(layers "F.Cu" "F.Mask" "F.Paste")
			(net 1 "GND")
			(pinfunction "VSS")
			(pintype "passive")
		)
		(pad "113" smd rect
			(at 36.975 2.297 270)
			(size 1.8 0.57)
			(layers "F.Cu" "F.Mask" "F.Paste")
			(net 113 "/DDR5 RDIMM/B.DQ9")
			(pinfunction "DQ9_B")
			(pintype "input")
		)
		(pad "114" smd rect
			(at 37.825 2.297 270)
			(size 1.8 0.57)
			(layers "F.Cu" "F.Mask" "F.Paste")
			(net 1 "GND")
			(pinfunction "VSS")
			(pintype "passive")
		)
		(pad "115" smd rect
			(at 38.673 2.297 270)
			(size 1.8 0.57)
			(layers "F.Cu" "F.Mask" "F.Paste")
			(net 141 "/DDR5 RDIMM/B.DQS1_P")
			(pinfunction "DQS1_B_T")
			(pintype "input")
		)
		(pad "116" smd rect
			(at 39.524 2.297 270)
			(size 1.8 0.57)
			(layers "F.Cu" "F.Mask" "F.Paste")
			(net 142 "/DDR5 RDIMM/B.DQS1_N")
			(pinfunction "DQS1_B_C")
			(pintype "input")
		)
		(pad "117" smd rect
			(at 40.374 2.297 270)
			(size 1.8 0.57)
			(layers "F.Cu" "F.Mask" "F.Paste")
			(net 1 "GND")
			(pinfunction "VSS")
			(pintype "passive")
		)
		(pad "118" smd rect
			(at 41.225 2.297 270)
			(size 1.8 0.57)
			(layers "F.Cu" "F.Mask" "F.Paste")
			(net 116 "/DDR5 RDIMM/B.DQ12")
			(pinfunction "DQ12_B")
			(pintype "input")
		)
		(pad "119" smd rect
			(at 42.075 2.297 270)
			(size 1.8 0.57)
			(layers "F.Cu" "F.Mask" "F.Paste")
			(net 1 "GND")
			(pinfunction "VSS")
			(pintype "passive")
		)
		(pad "120" smd rect
			(at 42.923 2.297 270)
			(size 1.8 0.57)
			(layers "F.Cu" "F.Mask" "F.Paste")
			(net 117 "/DDR5 RDIMM/B.DQ13")
			(pinfunction "DQ13_B")
			(pintype "input")
		)
		(pad "121" smd rect
			(at 43.773 2.297 270)
			(size 1.8 0.57)
			(layers "F.Cu" "F.Mask" "F.Paste")
			(net 1 "GND")
			(pinfunction "VSS")
			(pintype "passive")
		)
		(pad "122" smd rect
			(at 44.624 2.297 270)
			(size 1.8 0.57)
			(layers "F.Cu" "F.Mask" "F.Paste")
			(net 118 "/DDR5 RDIMM/B.DQ16")
			(pinfunction "DQ16_B")
			(pintype "input")
		)
		(pad "123" smd rect
			(at 45.475 2.297 270)
			(size 1.8 0.57)
			(layers "F.Cu" "F.Mask" "F.Paste")
			(net 1 "GND")
			(pinfunction "VSS")
			(pintype "passive")
		)
		(pad "124" smd rect
			(at 46.325 2.297 270)
			(size 1.8 0.57)
			(layers "F.Cu" "F.Mask" "F.Paste")
			(net 119 "/DDR5 RDIMM/B.DQ17")
			(pinfunction "DQ17_B")
			(pintype "input")
		)
		(pad "125" smd rect
			(at 47.173 2.297 270)
			(size 1.8 0.57)
			(layers "F.Cu" "F.Mask" "F.Paste")
			(net 1 "GND")
			(pinfunction "VSS")
			(pintype "passive")
		)
		(pad "126" smd rect
			(at 48.023 2.297 270)
			(size 1.8 0.57)
			(layers "F.Cu" "F.Mask" "F.Paste")
			(net 147 "/DDR5 RDIMM/B.DQS2_P")
			(pinfunction "DQS2_B_T")
			(pintype "input")
		)
		(pad "127" smd rect
			(at 48.874 2.297 270)
			(size 1.8 0.57)
			(layers "F.Cu" "F.Mask" "F.Paste")
			(net 148 "/DDR5 RDIMM/B.DQS2_N")
			(pinfunction "DQS2_B_C")
			(pintype "input")
		)
		(pad "128" smd rect
			(at 49.725 2.297 270)
			(size 1.8 0.57)
			(layers "F.Cu" "F.Mask" "F.Paste")
			(net 1 "GND")
			(pinfunction "VSS")
			(pintype "passive")
		)
		(pad "129" smd rect
			(at 50.575 2.297 270)
			(size 1.8 0.57)
			(layers "F.Cu" "F.Mask" "F.Paste")
			(net 122 "/DDR5 RDIMM/B.DQ20")
			(pinfunction "DQ20_B")
			(pintype "input")
		)
		(pad "130" smd rect
			(at 51.423 2.297 270)
			(size 1.8 0.57)
			(layers "F.Cu" "F.Mask" "F.Paste")
			(net 1 "GND")
			(pinfunction "VSS")
			(pintype "passive")
		)
		(pad "131" smd rect
			(at 52.273 2.297 270)
			(size 1.8 0.57)
			(layers "F.Cu" "F.Mask" "F.Paste")
			(net 123 "/DDR5 RDIMM/B.DQ21")
			(pinfunction "DQ21_B")
			(pintype "input")
		)
		(pad "132" smd rect
			(at 53.124 2.297 270)
			(size 1.8 0.57)
			(layers "F.Cu" "F.Mask" "F.Paste")
			(net 1 "GND")
			(pinfunction "VSS")
			(pintype "passive")
		)
		(pad "133" smd rect
			(at 53.975 2.297 270)
			(size 1.8 0.57)
			(layers "F.Cu" "F.Mask" "F.Paste")
			(net 124 "/DDR5 RDIMM/B.DQ24")
			(pinfunction "DQ24_B")
			(pintype "input")
		)
		(pad "134" smd rect
			(at 54.825 2.297 270)
			(size 1.8 0.57)
			(layers "F.Cu" "F.Mask" "F.Paste")
			(net 1 "GND")
			(pinfunction "VSS")
			(pintype "passive")
		)
		(pad "135" smd rect
			(at 55.673 2.297 270)
			(size 1.8 0.57)
			(layers "F.Cu" "F.Mask" "F.Paste")
			(net 125 "/DDR5 RDIMM/B.DQ25")
			(pinfunction "DQ25_B")
			(pintype "input")
		)
		(pad "136" smd rect
			(at 56.523 2.297 270)
			(size 1.8 0.57)
			(layers "F.Cu" "F.Mask" "F.Paste")
			(net 1 "GND")
			(pinfunction "VSS")
			(pintype "passive")
		)
		(pad "137" smd rect
			(at 57.374 2.297 270)
			(size 1.8 0.57)
			(layers "F.Cu" "F.Mask" "F.Paste")
			(net 156 "/DDR5 RDIMM/B.DQS3_P")
			(pinfunction "DQS3_B_T")
			(pintype "input")
		)
		(pad "138" smd rect
			(at 58.225 2.297 270)
			(size 1.8 0.57)
			(layers "F.Cu" "F.Mask" "F.Paste")
			(net 161 "/DDR5 RDIMM/B.DQS3_N")
			(pinfunction "DQS3_B_C")
			(pintype "input")
		)
		(pad "139" smd rect
			(at 59.075 2.297 270)
			(size 1.8 0.57)
			(layers "F.Cu" "F.Mask" "F.Paste")
			(net 1 "GND")
			(pinfunction "VSS")
			(pintype "passive")
		)
		(pad "140" smd rect
			(at 59.923 2.297 270)
			(size 1.8 0.57)
			(layers "F.Cu" "F.Mask" "F.Paste")
			(net 128 "/DDR5 RDIMM/B.DQ28")
			(pinfunction "DQ28_B")
			(pintype "input")
		)
		(pad "141" smd rect
			(at 60.773 2.297 270)
			(size 1.8 0.57)
			(layers "F.Cu" "F.Mask" "F.Paste")
			(net 1 "GND")
			(pinfunction "VSS")
			(pintype "passive")
		)
		(pad "142" smd rect
			(at 61.624 2.297 270)
			(size 1.8 0.57)
			(layers "F.Cu" "F.Mask" "F.Paste")
			(net 129 "/DDR5 RDIMM/B.DQ29")
			(pinfunction "DQ29_B")
			(pintype "input")
		)
		(pad "143" smd rect
			(at 62.475 2.297 270)
			(size 1.8 0.57)
			(layers "F.Cu" "F.Mask" "F.Paste")
			(net 1 "GND")
			(pinfunction "VSS")
			(pintype "passive")
		)
		(pad "144" smd rect
			(at 63.325 2.297 270)
			(size 1.8 0.57)
			(layers "F.Cu" "F.Mask" "F.Paste")
			(net 309 "unconnected-(J2B-RFU-Pad144)")
			(pinfunction "RFU")
			(pintype "no_connect")
		)
		(pad "145" smd rect
			(at -63.326 -2.301 270)
			(size 1.8 0.57)
			(layers "F.Cu" "F.Mask" "F.Paste")
			(net 802 "/DDR5 RDIMM/VIN_BULK")
			(pinfunction "VIN_BULK")
			(pintype "passive")
		)
		(pad "146" smd rect
			(at -62.476 -2.301 270)
			(size 1.8 0.57)
			(layers "F.Cu" "F.Mask" "F.Paste")
			(net 802 "/DDR5 RDIMM/VIN_BULK")
			(pinfunction "VIN_BULK")
			(pintype "passive")
		)
		(pad "147" smd rect
			(at -61.625 -2.301 270)
			(size 1.8 0.57)
			(layers "F.Cu" "F.Mask" "F.Paste")
			(net 602 "/DDR5 RDIMM/CTRL.PWR_GOOD")
			(pinfunction "PCAMP")
			(pintype "input")
		)
		(pad "148" smd rect
			(at -60.775 -2.301 270)
			(size 1.8 0.57)
			(layers "F.Cu" "F.Mask" "F.Paste")
			(net 461 "/DDR5 RDIMM/HSA")
			(pinfunction "HSA")
			(pintype "input")
		)
		(pad "149" smd rect
			(at -59.926 -2.301 270)
			(size 1.8 0.57)
			(layers "F.Cu" "F.Mask" "F.Paste")
			(net 310 "unconnected-(J2B-RFU-Pad149)")
			(pinfunction "RFU")
			(pintype "no_connect")
		)
		(pad "150" smd rect
			(at -59.076 -2.301 270)
			(size 1.8 0.57)
			(layers "F.Cu" "F.Mask" "F.Paste")
			(net 361 "unconnected-(J2B-RFU-Pad150)")
			(pinfunction "RFU")
			(pintype "no_connect")
		)
		(pad "151" smd rect
			(at -58.226 -2.301 270)
			(size 1.8 0.57)
			(layers "F.Cu" "F.Mask" "F.Paste")
			(net 1 "GND")
			(pinfunction "VSS")
			(pintype "passive")
		)
		(pad "152" smd rect
			(at -57.375 -2.301 270)
			(size 1.8 0.57)
			(layers "F.Cu" "F.Mask" "F.Paste")
			(net 130 "/DDR5 RDIMM/A.DQ2")
			(pinfunction "DQ2_A")
			(pintype "input")
		)
		(pad "153" smd rect
			(at -56.525 -2.301 270)
			(size 1.8 0.57)
			(layers "F.Cu" "F.Mask" "F.Paste")
			(net 1 "GND")
			(pinfunction "VSS")
			(pintype "passive")
		)
		(pad "154" smd rect
			(at -55.676 -2.301 270)
			(size 1.8 0.57)
			(layers "F.Cu" "F.Mask" "F.Paste")
			(net 131 "/DDR5 RDIMM/A.DQ3")
			(pinfunction "DQ3_A")
			(pintype "input")
		)
		(pad "155" smd rect
			(at -54.826 -2.301 270)
			(size 1.8 0.57)
			(layers "F.Cu" "F.Mask" "F.Paste")
			(net 1 "GND")
			(pinfunction "VSS")
			(pintype "passive")
		)
		(pad "156" smd rect
			(at -53.976 -2.301 270)
			(size 1.8 0.57)
			(layers "F.Cu" "F.Mask" "F.Paste")
			(net 177 "/DDR5 RDIMM/A.DQS5_N")
			(pinfunction "DQS5_A_C")
			(pintype "input")
		)
		(pad "157" smd rect
			(at -53.125 -2.301 270)
			(size 1.8 0.57)
			(layers "F.Cu" "F.Mask" "F.Paste")
			(net 178 "/DDR5 RDIMM/A.DQS5_P")
			(pinfunction "DQS5_A_T")
			(pintype "input")
		)
		(pad "158" smd rect
			(at -52.275 -2.301 270)
			(size 1.8 0.57)
			(layers "F.Cu" "F.Mask" "F.Paste")
			(net 1 "GND")
			(pinfunction "VSS")
			(pintype "passive")
		)
		(pad "159" smd rect
			(at -51.426 -2.301 270)
			(size 1.8 0.57)
			(layers "F.Cu" "F.Mask" "F.Paste")
			(net 134 "/DDR5 RDIMM/A.DQ6")
			(pinfunction "DQ6_A")
			(pintype "input")
		)
		(pad "160" smd rect
			(at -50.576 -2.301 270)
			(size 1.8 0.57)
			(layers "F.Cu" "F.Mask" "F.Paste")
			(net 1 "GND")
			(pinfunction "VSS")
			(pintype "passive")
		)
		(pad "161" smd rect
			(at -49.726 -2.301 270)
			(size 1.8 0.57)
			(layers "F.Cu" "F.Mask" "F.Paste")
			(net 135 "/DDR5 RDIMM/A.DQ7")
			(pinfunction "DQ7_A")
			(pintype "input")
		)
		(pad "162" smd rect
			(at -48.875 -2.301 270)
			(size 1.8 0.57)
			(layers "F.Cu" "F.Mask" "F.Paste")
			(net 1 "GND")
			(pinfunction "VSS")
			(pintype "passive")
		)
		(pad "163" smd rect
			(at -48.025 -2.301 270)
			(size 1.8 0.57)
			(layers "F.Cu" "F.Mask" "F.Paste")
			(net 136 "/DDR5 RDIMM/A.DQ10")
			(pinfunction "DQ10_A")
			(pintype "input")
		)
		(pad "164" smd rect
			(at -47.176 -2.301 270)
			(size 1.8 0.57)
			(layers "F.Cu" "F.Mask" "F.Paste")
			(net 1 "GND")
			(pinfunction "VSS")
			(pintype "passive")
		)
		(pad "165" smd rect
			(at -46.326 -2.301 270)
			(size 1.8 0.57)
			(layers "F.Cu" "F.Mask" "F.Paste")
			(net 140 "/DDR5 RDIMM/A.DQ11")
			(pinfunction "DQ11_A")
			(pintype "input")
		)
		(pad "166" smd rect
			(at -45.476 -2.301 270)
			(size 1.8 0.57)
			(layers "F.Cu" "F.Mask" "F.Paste")
			(net 1 "GND")
			(pinfunction "VSS")
			(pintype "passive")
		)
		(pad "167" smd rect
			(at -44.625 -2.301 270)
			(size 1.8 0.57)
			(layers "F.Cu" "F.Mask" "F.Paste")
			(net 181 "/DDR5 RDIMM/A.DQS6_N")
			(pinfunction "DQS6_A_C")
			(pintype "input")
		)
		(pad "168" smd rect
			(at -43.775 -2.301 270)
			(size 1.8 0.57)
			(layers "F.Cu" "F.Mask" "F.Paste")
			(net 182 "/DDR5 RDIMM/A.DQS6_P")
			(pinfunction "DQS6_A_T")
			(pintype "input")
		)
		(pad "169" smd rect
			(at -42.926 -2.301 270)
			(size 1.8 0.57)
			(layers "F.Cu" "F.Mask" "F.Paste")
			(net 1 "GND")
			(pinfunction "VSS")
			(pintype "passive")
		)
		(pad "170" smd rect
			(at -42.076 -2.301 270)
			(size 1.8 0.57)
			(layers "F.Cu" "F.Mask" "F.Paste")
			(net 143 "/DDR5 RDIMM/A.DQ14")
			(pinfunction "DQ14_A")
			(pintype "input")
		)
		(pad "171" smd rect
			(at -41.226 -2.301 270)
			(size 1.8 0.57)
			(layers "F.Cu" "F.Mask" "F.Paste")
			(net 1 "GND")
			(pinfunction "VSS")
			(pintype "passive")
		)
		(pad "172" smd rect
			(at -40.375 -2.301 270)
			(size 1.8 0.57)
			(layers "F.Cu" "F.Mask" "F.Paste")
			(net 144 "/DDR5 RDIMM/A.DQ15")
			(pinfunction "DQ15_A")
			(pintype "input")
		)
		(pad "173" smd rect
			(at -39.525 -2.301 270)
			(size 1.8 0.57)
			(layers "F.Cu" "F.Mask" "F.Paste")
			(net 1 "GND")
			(pinfunction "VSS")
			(pintype "passive")
		)
		(pad "174" smd rect
			(at -38.676 -2.301 270)
			(size 1.8 0.57)
			(layers "F.Cu" "F.Mask" "F.Paste")
			(net 145 "/DDR5 RDIMM/A.DQ18")
			(pinfunction "DQ18_A")
			(pintype "input")
		)
		(pad "175" smd rect
			(at -37.826 -2.301 270)
			(size 1.8 0.57)
			(layers "F.Cu" "F.Mask" "F.Paste")
			(net 1 "GND")
			(pinfunction "VSS")
			(pintype "passive")
		)
		(pad "176" smd rect
			(at -36.976 -2.301 270)
			(size 1.8 0.57)
			(layers "F.Cu" "F.Mask" "F.Paste")
			(net 146 "/DDR5 RDIMM/A.DQ19")
			(pinfunction "DQ19_A")
			(pintype "input")
		)
		(pad "177" smd rect
			(at -36.125 -2.301 270)
			(size 1.8 0.57)
			(layers "F.Cu" "F.Mask" "F.Paste")
			(net 1 "GND")
			(pinfunction "VSS")
			(pintype "passive")
		)
		(pad "178" smd rect
			(at -35.275 -2.301 270)
			(size 1.8 0.57)
			(layers "F.Cu" "F.Mask" "F.Paste")
			(net 208 "/DDR5 RDIMM/A.DQS7_N")
			(pinfunction "DQS7_A_C")
			(pintype "input")
		)
		(pad "179" smd rect
			(at -34.426 -2.301 270)
			(size 1.8 0.57)
			(layers "F.Cu" "F.Mask" "F.Paste")
			(net 209 "/DDR5 RDIMM/A.DQS7_P")
			(pinfunction "DQS7_A_T")
			(pintype "input")
		)
		(pad "180" smd rect
			(at -33.576 -2.301 270)
			(size 1.8 0.57)
			(layers "F.Cu" "F.Mask" "F.Paste")
			(net 1 "GND")
			(pinfunction "VSS")
			(pintype "passive")
		)
		(pad "181" smd rect
			(at -32.726 -2.301 270)
			(size 1.8 0.57)
			(layers "F.Cu" "F.Mask" "F.Paste")
			(net 149 "/DDR5 RDIMM/A.DQ22")
			(pinfunction "DQ22_A")
			(pintype "input")
		)
		(pad "182" smd rect
			(at -31.875 -2.301 270)
			(size 1.8 0.57)
			(layers "F.Cu" "F.Mask" "F.Paste")
			(net 1 "GND")
			(pinfunction "VSS")
			(pintype "passive")
		)
		(pad "183" smd rect
			(at -31.026 -2.301 270)
			(size 1.8 0.57)
			(layers "F.Cu" "F.Mask" "F.Paste")
			(net 153 "/DDR5 RDIMM/A.DQ23")
			(pinfunction "DQ23_A")
			(pintype "input")
		)
		(pad "184" smd rect
			(at -30.177 -2.301 270)
			(size 1.8 0.57)
			(layers "F.Cu" "F.Mask" "F.Paste")
			(net 1 "GND")
			(pinfunction "VSS")
			(pintype "passive")
		)
		(pad "185" smd rect
			(at -29.325 -2.301 270)
			(size 1.8 0.57)
			(layers "F.Cu" "F.Mask" "F.Paste")
			(net 154 "/DDR5 RDIMM/A.DQ26")
			(pinfunction "DQ26_A")
			(pintype "input")
		)
		(pad "186" smd rect
			(at -28.476 -2.301 270)
			(size 1.8 0.57)
			(layers "F.Cu" "F.Mask" "F.Paste")
			(net 1 "GND")
			(pinfunction "VSS")
			(pintype "passive")
		)
		(pad "187" smd rect
			(at -27.625 -2.301 270)
			(size 1.8 0.57)
			(layers "F.Cu" "F.Mask" "F.Paste")
			(net 155 "/DDR5 RDIMM/A.DQ27")
			(pinfunction "DQ27_A")
			(pintype "input")
		)
		(pad "188" smd rect
			(at -26.776 -2.301 270)
			(size 1.8 0.57)
			(layers "F.Cu" "F.Mask" "F.Paste")
			(net 1 "GND")
			(pinfunction "VSS")
			(pintype "passive")
		)
		(pad "189" smd rect
			(at -25.927 -2.301 270)
			(size 1.8 0.57)
			(layers "F.Cu" "F.Mask" "F.Paste")
			(net 214 "/DDR5 RDIMM/A.DQS8_N")
			(pinfunction "DQS8_A_C")
			(pintype "input")
		)
		(pad "190" smd rect
			(at -25.075 -2.301 270)
			(size 1.8 0.57)
			(layers "F.Cu" "F.Mask" "F.Paste")
			(net 216 "/DDR5 RDIMM/A.DQS8_P")
			(pinfunction "DQS8_A_T")
			(pintype "input")
		)
		(pad "191" smd rect
			(at -24.226 -2.301 270)
			(size 1.8 0.57)
			(layers "F.Cu" "F.Mask" "F.Paste")
			(net 1 "GND")
			(pinfunction "VSS")
			(pintype "passive")
		)
		(pad "192" smd rect
			(at -23.375 -2.301 270)
			(size 1.8 0.57)
			(layers "F.Cu" "F.Mask" "F.Paste")
			(net 162 "/DDR5 RDIMM/A.DQ30")
			(pinfunction "DQ30_A")
			(pintype "input")
		)
		(pad "193" smd rect
			(at -22.526 -2.301 270)
			(size 1.8 0.57)
			(layers "F.Cu" "F.Mask" "F.Paste")
			(net 1 "GND")
			(pinfunction "VSS")
			(pintype "passive")
		)
		(pad "194" smd rect
			(at -21.677 -2.301 270)
			(size 1.8 0.57)
			(layers "F.Cu" "F.Mask" "F.Paste")
			(net 166 "/DDR5 RDIMM/A.DQ31")
			(pinfunction "DQ31_A")
			(pintype "input")
		)
		(pad "195" smd rect
			(at -20.825 -2.301 270)
			(size 1.8 0.57)
			(layers "F.Cu" "F.Mask" "F.Paste")
			(net 1 "GND")
			(pinfunction "VSS")
			(pintype "passive")
		)
		(pad "196" smd rect
			(at -19.976 -2.301 270)
			(size 1.8 0.57)
			(layers "F.Cu" "F.Mask" "F.Paste")
			(net 171 "/DDR5 RDIMM/A.CB2")
			(pinfunction "CB2_A")
			(pintype "input")
		)
		(pad "197" smd rect
			(at -19.125 -2.301 270)
			(size 1.8 0.57)
			(layers "F.Cu" "F.Mask" "F.Paste")
			(net 1 "GND")
			(pinfunction "VSS")
			(pintype "passive")
		)
		(pad "198" smd rect
			(at -18.276 -2.301 270)
			(size 1.8 0.57)
			(layers "F.Cu" "F.Mask" "F.Paste")
			(net 173 "/DDR5 RDIMM/A.CB3")
			(pinfunction "CB3_A")
			(pintype "input")
		)
		(pad "199" smd rect
			(at -17.427 -2.301 270)
			(size 1.8 0.57)
			(layers "F.Cu" "F.Mask" "F.Paste")
			(net 1 "GND")
			(pinfunction "VSS")
			(pintype "passive")
		)
		(pad "200" smd rect
			(at -16.575 -2.301 270)
			(size 1.8 0.57)
			(layers "F.Cu" "F.Mask" "F.Paste")
			(net 234 "/DDR5 RDIMM/A.DQS9_N")
			(pinfunction "DQS9_A_C")
			(pintype "input")
		)
		(pad "201" smd rect
			(at -15.725 -2.301 270)
			(size 1.8 0.57)
			(layers "F.Cu" "F.Mask" "F.Paste")
			(net 235 "/DDR5 RDIMM/A.DQS9_P")
			(pinfunction "DQS9_A_T")
			(pintype "input")
		)
		(pad "202" smd rect
			(at -14.875 -2.301 270)
			(size 1.8 0.57)
			(layers "F.Cu" "F.Mask" "F.Paste")
			(net 1 "GND")
			(pinfunction "VSS")
			(pintype "passive")
		)
		(pad "203" smd rect
			(at -14.026 -2.301 270)
			(size 1.8 0.57)
			(layers "F.Cu" "F.Mask" "F.Paste")
			(net 186 "/DDR5 RDIMM/A.CB6")
			(pinfunction "CB6_A")
			(pintype "input")
		)
		(pad "204" smd rect
			(at -13.176 -2.301 270)
			(size 1.8 0.57)
			(layers "F.Cu" "F.Mask" "F.Paste")
			(net 1 "GND")
			(pinfunction "VSS")
			(pintype "passive")
		)
		(pad "205" smd rect
			(at -12.326 -2.301 270)
			(size 1.8 0.57)
			(layers "F.Cu" "F.Mask" "F.Paste")
			(net 187 "/DDR5 RDIMM/A.CB7")
			(pinfunction "CB7_A")
			(pintype "input")
		)
		(pad "206" smd rect
			(at -11.475 -2.301 270)
			(size 1.8 0.57)
			(layers "F.Cu" "F.Mask" "F.Paste")
			(net 1 "GND")
			(pinfunction "VSS")
			(pintype "passive")
		)
		(pad "207" smd rect
			(at -10.625 -2.301 270)
			(size 1.8 0.57)
			(layers "F.Cu" "F.Mask" "F.Paste")
			(net 190 "/DDR5 RDIMM/CTRL.~{RESET}")
			(pinfunction "RESET_N")
			(pintype "input")
		)
		(pad "208" smd rect
			(at -9.776 -2.301 270)
			(size 1.8 0.57)
			(layers "F.Cu" "F.Mask" "F.Paste")
			(net 1 "GND")
			(pinfunction "VSS")
			(pintype "passive")
		)
		(pad "209" smd rect
			(at -8.926 -2.301 270)
			(size 1.8 0.57)
			(layers "F.Cu" "F.Mask" "F.Paste")
			(net 191 "/DDR5 RDIMM/A.CS1_c")
			(pinfunction "CS1_A_N")
			(pintype "input")
		)
		(pad "210" smd rect
			(at -8.075 -2.301 270)
			(size 1.8 0.57)
			(layers "F.Cu" "F.Mask" "F.Paste")
			(net 1 "GND")
			(pinfunction "VSS")
			(pintype "passive")
		)
		(pad "211" smd rect
			(at -7.226 -2.301 270)
			(size 1.8 0.57)
			(layers "F.Cu" "F.Mask" "F.Paste")
			(net 192 "/DDR5 RDIMM/A.CA1")
			(pinfunction "CA1_A")
			(pintype "input")
		)
		(pad "212" smd rect
			(at -6.375 -2.301 270)
			(size 1.8 0.57)
			(layers "F.Cu" "F.Mask" "F.Paste")
			(net 1 "GND")
			(pinfunction "VSS")
			(pintype "passive")
		)
		(pad "213" smd rect
			(at -5.526 -2.301 270)
			(size 1.8 0.57)
			(layers "F.Cu" "F.Mask" "F.Paste")
			(net 193 "/DDR5 RDIMM/A.CA3")
			(pinfunction "CA3_A")
			(pintype "input")
		)
		(pad "214" smd rect
			(at -4.675 -2.301 270)
			(size 1.8 0.57)
			(layers "F.Cu" "F.Mask" "F.Paste")
			(net 1 "GND")
			(pinfunction "VSS")
			(pintype "passive")
		)
		(pad "215" smd rect
			(at -3.826 -2.301 270)
			(size 1.8 0.57)
			(layers "F.Cu" "F.Mask" "F.Paste")
			(net 194 "/DDR5 RDIMM/A.CA5")
			(pinfunction "CA5_A")
			(pintype "input")
		)
		(pad "216" smd rect
			(at -2.976 -2.301 270)
			(size 1.8 0.57)
			(layers "F.Cu" "F.Mask" "F.Paste")
			(net 1 "GND")
			(pinfunction "VSS")
			(pintype "passive")
		)
		(pad "217" smd rect
			(at -2.125 -2.301 270)
			(size 1.8 0.57)
			(layers "F.Cu" "F.Mask" "F.Paste")
			(net 634 "/DDR5 RDIMM/CTRL.CK_P")
			(pinfunction "CK_T")
			(pintype "input")
		)
		(pad "218" smd rect
			(at -1.276 -2.301 270)
			(size 1.8 0.57)
			(layers "F.Cu" "F.Mask" "F.Paste")
			(net 633 "/DDR5 RDIMM/CTRL.CK_N")
			(pinfunction "CK_C")
			(pintype "input")
		)
		(pad "219" smd rect
			(at -0.425 -2.301 270)
			(size 1.8 0.57)
			(layers "F.Cu" "F.Mask" "F.Paste")
			(net 1 "GND")
			(pinfunction "VSS")
			(pintype "passive")
		)
		(pad "220" smd rect
			(at 5.525 -2.301 270)
			(size 1.8 0.57)
			(layers "F.Cu" "F.Mask" "F.Paste")
			(net 362 "unconnected-(J2B-RFU-Pad220)")
			(pinfunction "RFU")
			(pintype "no_connect")
		)
		(pad "221" smd rect
			(at 6.373 -2.301 270)
			(size 1.8 0.57)
			(layers "F.Cu" "F.Mask" "F.Paste")
			(net 198 "/DDR5 RDIMM/B.CA2")
			(pinfunction "CA1_B")
			(pintype "input")
		)
		(pad "222" smd rect
			(at 7.224 -2.301 270)
			(size 1.8 0.57)
			(layers "F.Cu" "F.Mask" "F.Paste")
			(net 1 "GND")
			(pinfunction "VSS")
			(pintype "passive")
		)
		(pad "223" smd rect
			(at 8.073 -2.301 270)
			(size 1.8 0.57)
			(layers "F.Cu" "F.Mask" "F.Paste")
			(net 199 "/DDR5 RDIMM/B.CA3")
			(pinfunction "CA3_B")
			(pintype "input")
		)
		(pad "224" smd rect
			(at 8.925 -2.301 270)
			(size 1.8 0.57)
			(layers "F.Cu" "F.Mask" "F.Paste")
			(net 1 "GND")
			(pinfunction "VSS")
			(pintype "passive")
		)
		(pad "225" smd rect
			(at 9.775 -2.301 270)
			(size 1.8 0.57)
			(layers "F.Cu" "F.Mask" "F.Paste")
			(net 200 "/DDR5 RDIMM/B.CA5")
			(pinfunction "CA5_B")
			(pintype "input")
		)
		(pad "226" smd rect
			(at 10.624 -2.301 270)
			(size 1.8 0.57)
			(layers "F.Cu" "F.Mask" "F.Paste")
			(net 1 "GND")
			(pinfunction "VSS")
			(pintype "passive")
		)
		(pad "227" smd rect
			(at 11.473 -2.301 270)
			(size 1.8 0.57)
			(layers "F.Cu" "F.Mask" "F.Paste")
			(net 202 "/DDR5 RDIMM/B.PAR")
			(pinfunction "PAR_B")
			(pintype "input")
		)
		(pad "228" smd rect
			(at 12.323 -2.301 270)
			(size 1.8 0.57)
			(layers "F.Cu" "F.Mask" "F.Paste")
			(net 1 "GND")
			(pinfunction "VSS")
			(pintype "passive")
		)
		(pad "229" smd rect
			(at 13.175 -2.301 270)
			(size 1.8 0.57)
			(layers "F.Cu" "F.Mask" "F.Paste")
			(net 203 "/DDR5 RDIMM/B.CS1_c")
			(pinfunction "CS1_B_N")
			(pintype "input")
		)
		(pad "230" smd rect
			(at 14.025 -2.301 270)
			(size 1.8 0.57)
			(layers "F.Cu" "F.Mask" "F.Paste")
			(net 1 "GND")
			(pinfunction "VSS")
			(pintype "passive")
		)
		(pad "231" smd rect
			(at 14.874 -2.301 270)
			(size 1.8 0.57)
			(layers "F.Cu" "F.Mask" "F.Paste")
			(net 195 "unconnected-(J2B-RFU-Pad231)")
			(pinfunction "RFU")
			(pintype "no_connect")
		)
		(pad "232" smd rect
			(at 15.723 -2.301 270)
			(size 1.8 0.57)
			(layers "F.Cu" "F.Mask" "F.Paste")
			(net 196 "unconnected-(J2B-RFU-Pad232)")
			(pinfunction "RFU")
			(pintype "no_connect")
		)
		(pad "233" smd rect
			(at 16.574 -2.301 270)
			(size 1.8 0.57)
			(layers "F.Cu" "F.Mask" "F.Paste")
			(net 1 "GND")
			(pinfunction "VSS")
			(pintype "passive")
		)
		(pad "234" smd rect
			(at 17.425 -2.301 270)
			(size 1.8 0.57)
			(layers "F.Cu" "F.Mask" "F.Paste")
			(net 204 "/DDR5 RDIMM/B.CB6")
			(pinfunction "CB6_B")
			(pintype "input")
		)
		(pad "235" smd rect
			(at 18.274 -2.301 270)
			(size 1.8 0.57)
			(layers "F.Cu" "F.Mask" "F.Paste")
			(net 1 "GND")
			(pinfunction "VSS")
			(pintype "passive")
		)
		(pad "236" smd rect
			(at 19.123 -2.301 270)
			(size 1.8 0.57)
			(layers "F.Cu" "F.Mask" "F.Paste")
			(net 205 "/DDR5 RDIMM/B.CB7")
			(pinfunction "CB7_B")
			(pintype "input")
		)
		(pad "237" smd rect
			(at 19.975 -2.301 270)
			(size 1.8 0.57)
			(layers "F.Cu" "F.Mask" "F.Paste")
			(net 1 "GND")
			(pinfunction "VSS")
			(pintype "passive")
		)
		(pad "238" smd rect
			(at 20.824 -2.301 270)
			(size 1.8 0.57)
			(layers "F.Cu" "F.Mask" "F.Paste")
			(net 451 "/DDR5 RDIMM/B.DQS4_N")
			(pinfunction "DQS4_B_C")
			(pintype "input")
		)
		(pad "239" smd rect
			(at 21.675 -2.301 270)
			(size 1.8 0.57)
			(layers "F.Cu" "F.Mask" "F.Paste")
			(net 452 "/DDR5 RDIMM/B.DQS4_P")
			(pinfunction "DQS4_B_T")
			(pintype "input")
		)
		(pad "240" smd rect
			(at 22.524 -2.301 270)
			(size 1.8 0.57)
			(layers "F.Cu" "F.Mask" "F.Paste")
			(net 1 "GND")
			(pinfunction "VSS")
			(pintype "passive")
		)
		(pad "241" smd rect
			(at 23.373 -2.301 270)
			(size 1.8 0.57)
			(layers "F.Cu" "F.Mask" "F.Paste")
			(net 210 "/DDR5 RDIMM/B.CB2")
			(pinfunction "CB2_B")
			(pintype "input")
		)
		(pad "242" smd rect
			(at 24.225 -2.301 270)
			(size 1.8 0.57)
			(layers "F.Cu" "F.Mask" "F.Paste")
			(net 1 "GND")
			(pinfunction "VSS")
			(pintype "passive")
		)
		(pad "243" smd rect
			(at 25.074 -2.301 270)
			(size 1.8 0.57)
			(layers "F.Cu" "F.Mask" "F.Paste")
			(net 211 "/DDR5 RDIMM/B.CB3")
			(pinfunction "CB3_B")
			(pintype "input")
		)
		(pad "244" smd rect
			(at 25.925 -2.301 270)
			(size 1.8 0.57)
			(layers "F.Cu" "F.Mask" "F.Paste")
			(net 1 "GND")
			(pinfunction "VSS")
			(pintype "passive")
		)
		(pad "245" smd rect
			(at 26.774 -2.301 270)
			(size 1.8 0.57)
			(layers "F.Cu" "F.Mask" "F.Paste")
			(net 212 "/DDR5 RDIMM/B.DQ2")
			(pinfunction "DQ2_B")
			(pintype "input")
		)
		(pad "246" smd rect
			(at 27.623 -2.301 270)
			(size 1.8 0.57)
			(layers "F.Cu" "F.Mask" "F.Paste")
			(net 1 "GND")
			(pinfunction "VSS")
			(pintype "passive")
		)
		(pad "247" smd rect
			(at 28.475 -2.301 270)
			(size 1.8 0.57)
			(layers "F.Cu" "F.Mask" "F.Paste")
			(net 213 "/DDR5 RDIMM/B.DQ3")
			(pinfunction "DQ3_B")
			(pintype "input")
		)
		(pad "248" smd rect
			(at 29.324 -2.301 270)
			(size 1.8 0.57)
			(layers "F.Cu" "F.Mask" "F.Paste")
			(net 1 "GND")
			(pinfunction "VSS")
			(pintype "passive")
		)
		(pad "249" smd rect
			(at 30.175 -2.301 270)
			(size 1.8 0.57)
			(layers "F.Cu" "F.Mask" "F.Paste")
			(net 457 "/DDR5 RDIMM/B.DQS5_N")
			(pinfunction "DQS5_B_C")
			(pintype "input")
		)
		(pad "250" smd rect
			(at 31.024 -2.301 270)
			(size 1.8 0.57)
			(layers "F.Cu" "F.Mask" "F.Paste")
			(net 474 "/DDR5 RDIMM/B.DQS5_P")
			(pinfunction "DQS5_B_T")
			(pintype "input")
		)
		(pad "251" smd rect
			(at 31.873 -2.301 270)
			(size 1.8 0.57)
			(layers "F.Cu" "F.Mask" "F.Paste")
			(net 1 "GND")
			(pinfunction "VSS")
			(pintype "passive")
		)
		(pad "252" smd rect
			(at 32.725 -2.301 270)
			(size 1.8 0.57)
			(layers "F.Cu" "F.Mask" "F.Paste")
			(net 217 "/DDR5 RDIMM/B.DQ6")
			(pinfunction "DQ6_B")
			(pintype "input")
		)
		(pad "253" smd rect
			(at 33.575 -2.301 270)
			(size 1.8 0.57)
			(layers "F.Cu" "F.Mask" "F.Paste")
			(net 1 "GND")
			(pinfunction "VSS")
			(pintype "passive")
		)
		(pad "254" smd rect
			(at 34.423 -2.301 270)
			(size 1.8 0.57)
			(layers "F.Cu" "F.Mask" "F.Paste")
			(net 218 "/DDR5 RDIMM/B.DQ7")
			(pinfunction "DQ7_B")
			(pintype "input")
		)
		(pad "255" smd rect
			(at 35.274 -2.301 270)
			(size 1.8 0.57)
			(layers "F.Cu" "F.Mask" "F.Paste")
			(net 1 "GND")
			(pinfunction "VSS")
			(pintype "passive")
		)
		(pad "256" smd rect
			(at 36.124 -2.301 270)
			(size 1.8 0.57)
			(layers "F.Cu" "F.Mask" "F.Paste")
			(net 219 "/DDR5 RDIMM/B.DQ10")
			(pinfunction "DQ10_B")
			(pintype "input")
		)
		(pad "257" smd rect
			(at 36.975 -2.301 270)
			(size 1.8 0.57)
			(layers "F.Cu" "F.Mask" "F.Paste")
			(net 1 "GND")
			(pinfunction "VSS")
			(pintype "passive")
		)
		(pad "258" smd rect
			(at 37.825 -2.301 270)
			(size 1.8 0.57)
			(layers "F.Cu" "F.Mask" "F.Paste")
			(net 229 "/DDR5 RDIMM/B.DQ11")
			(pinfunction "DQ11_B")
			(pintype "input")
		)
		(pad "259" smd rect
			(at 38.673 -2.301 270)
			(size 1.8 0.57)
			(layers "F.Cu" "F.Mask" "F.Paste")
			(net 1 "GND")
			(pinfunction "VSS")
			(pintype "passive")
		)
		(pad "260" smd rect
			(at 39.524 -2.301 270)
			(size 1.8 0.57)
			(layers "F.Cu" "F.Mask" "F.Paste")
			(net 592 "/DDR5 RDIMM/B.DQS6_N")
			(pinfunction "DQS6_B_C")
			(pintype "input")
		)
		(pad "261" smd rect
			(at 40.374 -2.301 270)
			(size 1.8 0.57)
			(layers "F.Cu" "F.Mask" "F.Paste")
			(net 593 "/DDR5 RDIMM/B.DQS6_P")
			(pinfunction "DQS6_B_T")
			(pintype "input")
		)
		(pad "262" smd rect
			(at 41.225 -2.301 270)
			(size 1.8 0.57)
			(layers "F.Cu" "F.Mask" "F.Paste")
			(net 1 "GND")
			(pinfunction "VSS")
			(pintype "passive")
		)
		(pad "263" smd rect
			(at 42.075 -2.301 270)
			(size 1.8 0.57)
			(layers "F.Cu" "F.Mask" "F.Paste")
			(net 358 "/DDR5 RDIMM/B.DQ14")
			(pinfunction "DQ14_B")
			(pintype "input")
		)
		(pad "264" smd rect
			(at 42.923 -2.301 270)
			(size 1.8 0.57)
			(layers "F.Cu" "F.Mask" "F.Paste")
			(net 1 "GND")
			(pinfunction "VSS")
			(pintype "passive")
		)
		(pad "265" smd rect
			(at 43.773 -2.301 270)
			(size 1.8 0.57)
			(layers "F.Cu" "F.Mask" "F.Paste")
			(net 359 "/DDR5 RDIMM/B.DQ15")
			(pinfunction "DQ15_B")
			(pintype "input")
		)
		(pad "266" smd rect
			(at 44.624 -2.301 270)
			(size 1.8 0.57)
			(layers "F.Cu" "F.Mask" "F.Paste")
			(net 1 "GND")
			(pinfunction "VSS")
			(pintype "passive")
		)
		(pad "267" smd rect
			(at 45.475 -2.301 270)
			(size 1.8 0.57)
			(layers "F.Cu" "F.Mask" "F.Paste")
			(net 360 "/DDR5 RDIMM/B.DQ18")
			(pinfunction "DQ18_B")
			(pintype "input")
		)
		(pad "268" smd rect
			(at 46.325 -2.301 270)
			(size 1.8 0.57)
			(layers "F.Cu" "F.Mask" "F.Paste")
			(net 1 "GND")
			(pinfunction "VSS")
			(pintype "passive")
		)
		(pad "269" smd rect
			(at 47.173 -2.301 270)
			(size 1.8 0.57)
			(layers "F.Cu" "F.Mask" "F.Paste")
			(net 450 "/DDR5 RDIMM/B.DQ19")
			(pinfunction "DQ19_B")
			(pintype "input")
		)
		(pad "270" smd rect
			(at 48.023 -2.301 270)
			(size 1.8 0.57)
			(layers "F.Cu" "F.Mask" "F.Paste")
			(net 1 "GND")
			(pinfunction "VSS")
			(pintype "passive")
		)
		(pad "271" smd rect
			(at 48.874 -2.301 270)
			(size 1.8 0.57)
			(layers "F.Cu" "F.Mask" "F.Paste")
			(net 594 "/DDR5 RDIMM/B.DQS7_N")
			(pinfunction "DQS7_B_C")
			(pintype "input")
		)
		(pad "272" smd rect
			(at 49.725 -2.301 270)
			(size 1.8 0.57)
			(layers "F.Cu" "F.Mask" "F.Paste")
			(net 595 "/DDR5 RDIMM/B.DQS7_P")
			(pinfunction "DQS7_B_T")
			(pintype "input")
		)
		(pad "273" smd rect
			(at 50.575 -2.301 270)
			(size 1.8 0.57)
			(layers "F.Cu" "F.Mask" "F.Paste")
			(net 1 "GND")
			(pinfunction "VSS")
			(pintype "passive")
		)
		(pad "274" smd rect
			(at 51.423 -2.301 270)
			(size 1.8 0.57)
			(layers "F.Cu" "F.Mask" "F.Paste")
			(net 453 "/DDR5 RDIMM/B.DQ22")
			(pinfunction "DQ22_B")
			(pintype "input")
		)
		(pad "275" smd rect
			(at 52.273 -2.301 270)
			(size 1.8 0.57)
			(layers "F.Cu" "F.Mask" "F.Paste")
			(net 1 "GND")
			(pinfunction "VSS")
			(pintype "passive")
		)
		(pad "276" smd rect
			(at 53.124 -2.301 270)
			(size 1.8 0.57)
			(layers "F.Cu" "F.Mask" "F.Paste")
			(net 454 "/DDR5 RDIMM/B.DQ23")
			(pinfunction "DQ23_B")
			(pintype "input")
		)
		(pad "277" smd rect
			(at 53.975 -2.301 270)
			(size 1.8 0.57)
			(layers "F.Cu" "F.Mask" "F.Paste")
			(net 1 "GND")
			(pinfunction "VSS")
			(pintype "passive")
		)
		(pad "278" smd rect
			(at 54.825 -2.301 270)
			(size 1.8 0.57)
			(layers "F.Cu" "F.Mask" "F.Paste")
			(net 455 "/DDR5 RDIMM/B.DQ26")
			(pinfunction "DQ26_B")
			(pintype "input")
		)
		(pad "279" smd rect
			(at 55.673 -2.301 270)
			(size 1.8 0.57)
			(layers "F.Cu" "F.Mask" "F.Paste")
			(net 1 "GND")
			(pinfunction "VSS")
			(pintype "passive")
		)
		(pad "280" smd rect
			(at 56.523 -2.301 270)
			(size 1.8 0.57)
			(layers "F.Cu" "F.Mask" "F.Paste")
			(net 456 "/DDR5 RDIMM/B.DQ27")
			(pinfunction "DQ27_B")
			(pintype "input")
		)
		(pad "281" smd rect
			(at 57.374 -2.301 270)
			(size 1.8 0.57)
			(layers "F.Cu" "F.Mask" "F.Paste")
			(net 1 "GND")
			(pinfunction "VSS")
			(pintype "passive")
		)
		(pad "282" smd rect
			(at 58.225 -2.301 270)
			(size 1.8 0.57)
			(layers "F.Cu" "F.Mask" "F.Paste")
			(net 596 "/DDR5 RDIMM/B.DQS8_N")
			(pinfunction "DQS8_B_C")
			(pintype "input")
		)
		(pad "283" smd rect
			(at 59.075 -2.301 270)
			(size 1.8 0.57)
			(layers "F.Cu" "F.Mask" "F.Paste")
			(net 597 "/DDR5 RDIMM/B.DQS8_P")
			(pinfunction "DQS8_B_T")
			(pintype "input")
		)
		(pad "284" smd rect
			(at 59.923 -2.301 270)
			(size 1.8 0.57)
			(layers "F.Cu" "F.Mask" "F.Paste")
			(net 1 "GND")
			(pinfunction "VSS")
			(pintype "passive")
		)
		(pad "285" smd rect
			(at 60.773 -2.301 270)
			(size 1.8 0.57)
			(layers "F.Cu" "F.Mask" "F.Paste")
			(net 475 "/DDR5 RDIMM/B.DQ30")
			(pinfunction "DQ30_B")
			(pintype "input")
		)
		(pad "286" smd rect
			(at 61.624 -2.301 270)
			(size 1.8 0.57)
			(layers "F.Cu" "F.Mask" "F.Paste")
			(net 1 "GND")
			(pinfunction "VSS")
			(pintype "passive")
		)
		(pad "287" smd rect
			(at 62.475 -2.301 270)
			(size 1.8 0.57)
			(layers "F.Cu" "F.Mask" "F.Paste")
			(net 476 "/DDR5 RDIMM/B.DQ31")
			(pinfunction "DQ31_B")
			(pintype "input")
		)
		(pad "288" smd rect
			(at 63.325 -2.301 270)
			(size 1.8 0.57)
			(layers "F.Cu" "F.Mask" "F.Paste")
			(net 1 "GND")
			(pinfunction "VSS")
			(pintype "passive")
		)
		(pad "S1" thru_hole oval
			(at -68.976 0 180)
			(size 1.875 3.75)
			(drill oval 1.25 2.53)
			(layers "*.Cu" "*.Mask")
			(remove_unused_layers no)
			(net 1 "GND")
			(pinfunction "SH")
			(pintype "passive")
		)
		(pad "S2" thru_hole oval
			(at 3.874 0 180)
			(size 1.875 3.75)
			(drill oval 1.25 2.53)
			(layers "*.Cu" "*.Mask")
			(remove_unused_layers no)
			(net 1 "GND")
			(pinfunction "SH")
			(pintype "passive")
		)
		(pad "S3" thru_hole oval
			(at 68.974 0 180)
			(size 1.875 3.75)
			(drill oval 1.25 2.53)
			(layers "*.Cu" "*.Mask")
			(remove_unused_layers no)
			(net 1 "GND")
			(pinfunction "SH")
			(pintype "passive")
		)
	)
	(footprint "antmicro-footprints:SOT-23-5"
		(layer "F.Cu")
		(at 254.287998 128.939)
		(property "Reference" "U21"
			(at -2.363499 2.81 90)
			(layer "F.SilkS")
			(effects
				(font
					(size 0.7 0.7)
					(thickness 0.15)
				)
				(justify left bottom)
			)
		)
		(property "Value" "NCP718BSN330T1G"
			(at 0.002 2.799 0)
			(layer "F.Fab")
			(effects
				(font
					(size 0.7 0.7)
					(thickness 0.15)
				)
				(justify left bottom)
			)
		)
		(property "Datasheet" "https://www.mouser.com/datasheet/2/308/NCP718_D-1224359.pdf"
			(at 0 0 0)
			(layer "F.Fab")
			(hide yes)
			(effects
				(font
					(size 1.27 1.27)
					(thickness 0.15)
				)
			)
		)
		(property "MPN" "NCP718BSN330T1G"
			(at 0 0 0)
			(unlocked yes)
			(layer "F.Fab")
			(hide yes)
			(effects
				(font
					(size 1 1)
					(thickness 0.15)
				)
			)
		)
		(property "Manufacturer" "ON Semiconductor"
			(at 0 0 0)
			(unlocked yes)
			(layer "F.Fab")
			(hide yes)
			(effects
				(font
					(size 1 1)
					(thickness 0.15)
				)
			)
		)
		(property "Author" "Antmicro"
			(at 0 0 0)
			(unlocked yes)
			(layer "F.Fab")
			(hide yes)
			(effects
				(font
					(size 1 1)
					(thickness 0.15)
				)
			)
		)
		(property "License" "Apache-2.0"
			(at 0 0 0)
			(unlocked yes)
			(layer "F.Fab")
			(hide yes)
			(effects
				(font
					(size 1 1)
					(thickness 0.15)
				)
			)
		)
		(sheetname "/Supply/")
		(sheetfile "supply.kicad_sch")
		(attr smd)
		(fp_line
			(start -0.85 1.6)
			(end -0.85 1.301)
			(stroke
				(width 0.15)
				(type solid)
			)
			(layer "F.SilkS")
		)
		(fp_line
			(start -0.8 -1.6)
			(end -0.8 -1.3)
			(stroke
				(width 0.15)
				(type solid)
			)
			(layer "F.SilkS")
		)
		(fp_line
			(start -0.8 -1.6)
			(end -0.5 -1.6)
			(stroke
				(width 0.15)
				(type solid)
			)
			(layer "F.SilkS")
		)
		(fp_line
			(start -0.55 1.6)
			(end -0.85 1.6)
			(stroke
				(width 0.15)
				(type solid)
			)
			(layer "F.SilkS")
		)
		(fp_line
			(start 0.8 -1.6)
			(end 0.5 -1.6)
			(stroke
				(width 0.15)
				(type solid)
			)
			(layer "F.SilkS")
		)
		(fp_line
			(start 0.8 -1.3)
			(end 0.8 -1.6)
			(stroke
				(width 0.15)
				(type solid)
			)
			(layer "F.SilkS")
		)
		(fp_line
			(start 0.8 0.55)
			(end 0.8 -0.55)
			(stroke
				(width 0.15)
				(type solid)
			)
			(layer "F.SilkS")
		)
		(fp_line
			(start 0.8 1.3)
			(end 0.8 1.599)
			(stroke
				(width 0.15)
				(type solid)
			)
			(layer "F.SilkS")
		)
		(fp_line
			(start 0.8 1.599)
			(end 0.549 1.599)
			(stroke
				(width 0.15)
				(type solid)
			)
			(layer "F.SilkS")
		)
		(fp_circle
			(center -1.25 -1.5)
			(end -1.2 -1.5)
			(stroke
				(width 0.15)
				(type solid)
			)
			(fill yes)
			(layer "F.SilkS")
		)
		(fp_rect
			(start 1.9 -1.76)
			(end -1.9 1.75)
			(stroke
				(width 0.05)
				(type solid)
			)
			(fill no)
			(layer "F.CrtYd")
		)
		(fp_line
			(start -0.398 -1.526)
			(end -0.874 -1.05)
			(stroke
				(width 0.15)
				(type solid)
			)
			(layer "F.Fab")
		)
		(fp_rect
			(start 0.874 1.523)
			(end -0.873 -1.525)
			(stroke
				(width 0.15)
				(type solid)
			)
			(fill no)
			(layer "F.Fab")
		)
		(fp_text user "Author: Antmicro"
			(at -1.898 5.499 0)
			(layer "F.Fab")
			(effects
				(font
					(size 0.7 0.7)
					(thickness 0.15)
				)
				(justify left bottom)
			)
		)
		(fp_text user "${REFERENCE}"
			(at -1.898 4.299 0)
			(layer "F.Fab")
			(effects
				(font
					(size 0.7 0.7)
					(thickness 0.15)
				)
				(justify left bottom)
			)
		)
		(fp_text user "License: Apache-2.0"
			(at -1.898 6.7 0)
			(layer "F.Fab")
			(effects
				(font
					(size 0.7 0.7)
					(thickness 0.15)
				)
				(justify left bottom)
			)
		)
		(pad "1" smd rect
			(at -1.351 -0.951 270)
			(size 0.55 1)
			(layers "F.Cu" "F.Mask" "F.Paste")
			(net 35 "VDC")
			(pinfunction "VIN")
			(pintype "passive")
		)
		(pad "2" smd rect
			(at -1.351 0 270)
			(size 0.55 1)
			(layers "F.Cu" "F.Mask" "F.Paste")
			(net 1 "GND")
			(pinfunction "GND")
			(pintype "passive")
		)
		(pad "3" smd rect
			(at -1.351 0.949 270)
			(size 0.55 1)
			(layers "F.Cu" "F.Mask" "F.Paste")
			(net 35 "VDC")
			(pinfunction "EN")
			(pintype "passive")
		)
		(pad "4" smd rect
			(at 1.35 0.949 270)
			(size 0.55 1)
			(layers "F.Cu" "F.Mask" "F.Paste")
			(net 434 "unconnected-(U21-NC-Pad4)")
			(pinfunction "NC")
			(pintype "no_connect")
		)
		(pad "5" smd rect
			(at 1.35 -0.951 270)
			(size 0.55 1)
			(layers "F.Cu" "F.Mask" "F.Paste")
			(net 38 "+3V3_AON")
			(pinfunction "VOUT")
			(pintype "passive")
		)
	)
	(footprint "antmicro-footprints:C_0402_1005Metric"
		(layer "F.Cu")
		(at 150.375499 169.033 -90)
		(descr "Capacitor SMD 0402")
		(tags "capacitor SMD 0402")
		(property "Reference" "C130"
			(at -2.233 -1.964501 90)
			(layer "F.SilkS")
			(effects
				(font
					(size 0.7 0.7)
					(thickness 0.15)
				)
				(justify right bottom)
			)
		)
		(property "Value" "C_100n_0402"
			(at -1.022927 2.155213 90)
			(layer "F.Fab")
			(effects
				(font
					(size 0.7 0.7)
					(thickness 0.15)
				)
				(justify right bottom)
			)
		)
		(property "Datasheet" "https://www.murata.com/products/productdetail?partno=GRM155R61H104KE14%23"
			(at 0 0 270)
			(layer "F.Fab")
			(hide yes)
			(effects
				(font
					(size 1.27 1.27)
					(thickness 0.15)
				)
			)
		)
		(property "MPN" "GRM155R61H104KE14D"
			(at 0 0 270)
			(unlocked yes)
			(layer "F.Fab")
			(hide yes)
			(effects
				(font
					(size 1 1)
					(thickness 0.15)
				)
			)
		)
		(property "Manufacturer" "Murata"
			(at 0 0 270)
			(unlocked yes)
			(layer "F.Fab")
			(hide yes)
			(effects
				(font
					(size 1 1)
					(thickness 0.15)
				)
			)
		)
		(property "License" "Apache-2.0"
			(at 0 0 270)
			(unlocked yes)
			(layer "F.Fab")
			(hide yes)
			(effects
				(font
					(size 1 1)
					(thickness 0.15)
				)
			)
		)
		(property "Author" "Antmicro"
			(at 0 0 270)
			(unlocked yes)
			(layer "F.Fab")
			(hide yes)
			(effects
				(font
					(size 1 1)
					(thickness 0.15)
				)
			)
		)
		(property "Val" "100n"
			(at 0 0 270)
			(unlocked yes)
			(layer "F.Fab")
			(hide yes)
			(effects
				(font
					(size 1 1)
					(thickness 0.15)
				)
			)
		)
		(property "Voltage" "50V"
			(at 0 0 270)
			(unlocked yes)
			(layer "F.Fab")
			(hide yes)
			(effects
				(font
					(size 1 1)
					(thickness 0.15)
				)
			)
		)
		(property "Dielectric" "X5R"
			(at 0 0 270)
			(unlocked yes)
			(layer "F.Fab")
			(hide yes)
			(effects
				(font
					(size 1 1)
					(thickness 0.15)
				)
			)
		)
		(sheetname "/Debug FTDI + VNA/")
		(sheetfile "debug-ftdi.kicad_sch")
		(attr smd)
		(fp_rect
			(start -0.925 -0.47)
			(end 0.925 0.47)
			(stroke
				(width 0.05)
				(type default)
			)
			(fill no)
			(layer "F.CrtYd")
		)
		(fp_line
			(start -0.494 0.248)
			(end -0.494 -0.25)
			(stroke
				(width 0.15)
				(type solid)
			)
			(layer "F.Fab")
		)
		(fp_line
			(start 0.504 0.248)
			(end -0.494 0.248)
			(stroke
				(width 0.15)
				(type solid)
			)
			(layer "F.Fab")
		)
		(fp_line
			(start -0.494 -0.25)
			(end 0.504 -0.25)
			(stroke
				(width 0.15)
				(type solid)
			)
			(layer "F.Fab")
		)
		(fp_line
			(start 0.504 -0.25)
			(end 0.504 0.248)
			(stroke
				(width 0.15)
				(type solid)
			)
			(layer "F.Fab")
		)
		(fp_text user "Author: Antmicro"
			(at -0.939 3.399 270)
			(layer "F.Fab")
			(effects
				(font
					(size 0.7 0.7)
					(thickness 0.15)
				)
				(justify left bottom)
			)
		)
		(fp_text user "${REFERENCE}"
			(at -0.939 4.599 270)
			(layer "F.Fab")
			(effects
				(font
					(size 0.7 0.7)
					(thickness 0.15)
				)
				(justify left bottom)
			)
		)
		(fp_text user "License: Apache-2.0"
			(at -0.939 5.799 270)
			(layer "F.Fab")
			(effects
				(font
					(size 0.7 0.7)
					(thickness 0.15)
				)
				(justify left bottom)
			)
		)
		(pad "1" smd roundrect
			(at -0.48 0 270)
			(size 0.59 0.64)
			(layers "F.Cu" "F.Mask" "F.Paste")
			(roundrect_rratio 0.25)
			(net 1 "GND")
			(pintype "passive")
		)
		(pad "2" smd roundrect
			(at 0.48 0 270)
			(size 0.59 0.64)
			(layers "F.Cu" "F.Mask" "F.Paste")
			(roundrect_rratio 0.25)
			(net 6 "/Debug FTDI + VNA/FTDI_3V3")
			(pintype "passive")
		)
	)
	(footprint "antmicro-footprints:USON-10_2.5x1mm_P0.5mm"
		(layer "F.Cu")
		(at 220.857 148.098 180)
		(descr "USON-10 2.5x1mm_ Pitch 0.5mm")
		(tags "USON-10 2.5x1mm Pitch 0.5mm")
		(property "Reference" "U2"
			(at -0.543 -2.552 0)
			(layer "F.SilkS")
			(effects
				(font
					(size 0.7 0.7)
					(thickness 0.15)
				)
				(justify right bottom)
			)
		)
		(property "Value" "TPD4E05U06QDQARQ1"
			(at 0.018 2.499 0)
			(layer "F.Fab")
			(effects
				(font
					(size 0.7 0.7)
					(thickness 0.15)
				)
				(justify right bottom)
			)
		)
		(property "Datasheet" "https://www.ti.com/lit/ds/symlink/tpd4e05u06-q1.pdf?HQS=dis-mous-null-mousermode-dsf-pf-null-wwe&ts=1663591265741&ref_url=https%253A%252F%252Fwww.mouser.com%252F"
			(at 0 0 180)
			(layer "F.Fab")
			(hide yes)
			(effects
				(font
					(size 1.27 1.27)
					(thickness 0.15)
				)
			)
		)
		(property "MPN" "TPD4E05U06QDQARQ1"
			(at 0 0 180)
			(unlocked yes)
			(layer "F.Fab")
			(hide yes)
			(effects
				(font
					(size 1 1)
					(thickness 0.15)
				)
			)
		)
		(property "Manufacturer" "Texas Instruments"
			(at 0 0 180)
			(unlocked yes)
			(layer "F.Fab")
			(hide yes)
			(effects
				(font
					(size 1 1)
					(thickness 0.15)
				)
			)
		)
		(property "Author" "Antmicro"
			(at 0 0 180)
			(unlocked yes)
			(layer "F.Fab")
			(hide yes)
			(effects
				(font
					(size 1 1)
					(thickness 0.15)
				)
			)
		)
		(property "License" "Apache-2.0"
			(at 0 0 180)
			(unlocked yes)
			(layer "F.Fab")
			(hide yes)
			(effects
				(font
					(size 1 1)
					(thickness 0.15)
				)
			)
		)
		(sheetname "/FPGA Config/")
		(sheetfile "fpga-config.kicad_sch")
		(attr smd)
		(fp_line
			(start 0.498 1.398)
			(end -0.5 1.398)
			(stroke
				(width 0.15)
				(type solid)
			)
			(layer "F.SilkS")
		)
		(fp_line
			(start 0.498 -1.401)
			(end -0.5 -1.401)
			(stroke
				(width 0.15)
				(type solid)
			)
			(layer "F.SilkS")
		)
		(fp_circle
			(center -0.68 -1.27)
			(end -0.63 -1.27)
			(stroke
				(width 0.15)
				(type solid)
			)
			(fill yes)
			(layer "F.SilkS")
		)
		(fp_rect
			(start -0.8 -1.5)
			(end 0.8 1.499)
			(stroke
				(width 0.05)
				(type solid)
			)
			(fill no)
			(layer "F.CrtYd")
		)
		(fp_line
			(start 0.498 -1.25)
			(end 0.498 1.249)
			(stroke
				(width 0.15)
				(type solid)
			)
			(layer "F.Fab")
		)
		(fp_line
			(start 0.498 -1.25)
			(end -0.25 -1.25)
			(stroke
				(width 0.15)
				(type solid)
			)
			(layer "F.Fab")
		)
		(fp_line
			(start -0.25 -1.25)
			(end -0.5 -1)
			(stroke
				(width 0.15)
				(type solid)
			)
			(layer "F.Fab")
		)
		(fp_line
			(start -0.5 1.249)
			(end 0.498 1.249)
			(stroke
				(width 0.15)
				(type solid)
			)
			(layer "F.Fab")
		)
		(fp_line
			(start -0.5 -1)
			(end -0.5 1.249)
			(stroke
				(width 0.15)
				(type solid)
			)
			(layer "F.Fab")
		)
		(fp_text user "${REFERENCE}"
			(at -0.802 4.498 180)
			(layer "F.Fab")
			(effects
				(font
					(size 0.7 0.7)
					(thickness 0.15)
				)
				(justify left bottom)
			)
		)
		(fp_text user "Author: Antmicro"
			(at -0.802 5.7 180)
			(layer "F.Fab")
			(effects
				(font
					(size 0.7 0.7)
					(thickness 0.15)
				)
				(justify left bottom)
			)
		)
		(fp_text user "License: Apache-2.0"
			(at -0.802 6.9 180)
			(layer "F.Fab")
			(effects
				(font
					(size 0.7 0.7)
					(thickness 0.15)
				)
				(justify left bottom)
			)
		)
		(pad "1" smd roundrect
			(at -0.387 -1 90)
			(size 0.25 0.55)
			(layers "F.Cu" "F.Mask" "F.Paste")
			(roundrect_rratio 0.25)
			(net 238 "/Debug FTDI + VNA/JTAG.TMS")
			(pintype "passive")
		)
		(pad "2" smd roundrect
			(at -0.387 -0.5 90)
			(size 0.25 0.55)
			(layers "F.Cu" "F.Mask" "F.Paste")
			(roundrect_rratio 0.25)
			(net 239 "/Debug FTDI + VNA/JTAG.TCK")
			(pintype "passive")
		)
		(pad "3" smd roundrect
			(at -0.387 0 90)
			(size 0.4 0.55)
			(layers "F.Cu" "F.Mask" "F.Paste")
			(roundrect_rratio 0.25)
			(net 1 "GND")
			(pintype "power_in")
		)
		(pad "4" smd roundrect
			(at -0.387 0.498 90)
			(size 0.25 0.55)
			(layers "F.Cu" "F.Mask" "F.Paste")
			(roundrect_rratio 0.25)
			(net 242 "/Debug FTDI + VNA/JTAG.TDO")
			(pintype "passive")
		)
		(pad "5" smd roundrect
			(at -0.387 0.998 90)
			(size 0.25 0.55)
			(layers "F.Cu" "F.Mask" "F.Paste")
			(roundrect_rratio 0.25)
			(net 244 "/Debug FTDI + VNA/JTAG.TDI")
			(pintype "passive")
		)
		(pad "6" smd roundrect
			(at 0.385 0.998 90)
			(size 0.25 0.55)
			(layers "F.Cu" "F.Mask" "F.Paste")
			(roundrect_rratio 0.25)
			(net 244 "/Debug FTDI + VNA/JTAG.TDI")
			(pintype "passive")
		)
		(pad "7" smd roundrect
			(at 0.385 0.498 90)
			(size 0.25 0.55)
			(layers "F.Cu" "F.Mask" "F.Paste")
			(roundrect_rratio 0.25)
			(net 242 "/Debug FTDI + VNA/JTAG.TDO")
			(pintype "passive")
		)
		(pad "8" smd roundrect
			(at 0.385 0 90)
			(size 0.4 0.55)
			(layers "F.Cu" "F.Mask" "F.Paste")
			(roundrect_rratio 0.25)
			(net 1 "GND")
			(pintype "passive")
		)
		(pad "9" smd roundrect
			(at 0.385 -0.5 90)
			(size 0.25 0.55)
			(layers "F.Cu" "F.Mask" "F.Paste")
			(roundrect_rratio 0.25)
			(net 239 "/Debug FTDI + VNA/JTAG.TCK")
			(pintype "passive")
		)
		(pad "10" smd roundrect
			(at 0.385 -1 90)
			(size 0.25 0.55)
			(layers "F.Cu" "F.Mask" "F.Paste")
			(roundrect_rratio 0.25)
			(net 238 "/Debug FTDI + VNA/JTAG.TMS")
			(pintype "passive")
		)
	)
	(footprint "antmicro-footprints:L_0402_1005Metric"
		(layer "F.Cu")
		(at 121.025 151.61 180)
		(descr "Inductor SMD 0402")
		(tags "Inductor SMD 0402")
		(property "Reference" "L10"
			(at -5.745 -0.415 0)
			(layer "F.SilkS")
			(effects
				(font
					(size 0.7 0.7)
					(thickness 0.15)
				)
				(justify right bottom)
			)
		)
		(property "Value" "L_20n_0.35A_0402"
			(at 0 1.4 0)
			(layer "F.Fab")
			(effects
				(font
					(size 0.7 0.7)
					(thickness 0.15)
				)
				(justify right bottom)
			)
		)
		(property "Datasheet" "https://product.tdk.com/system/files/dam/doc/product/inductor/inductor/smd/catalog/inductor_automotive_high-frequency_mlg1005s_en.pdf?ref_disty=mouser"
			(at 0 0 180)
			(layer "F.Fab")
			(hide yes)
			(effects
				(font
					(size 1.27 1.27)
					(thickness 0.15)
				)
			)
		)
		(property "Val" "20n/0.35A"
			(at 0 0 180)
			(unlocked yes)
			(layer "F.Fab")
			(hide yes)
			(effects
				(font
					(size 1 1)
					(thickness 0.15)
				)
			)
		)
		(property "Manufacturer" "TDK"
			(at 0 0 180)
			(unlocked yes)
			(layer "F.Fab")
			(hide yes)
			(effects
				(font
					(size 1 1)
					(thickness 0.15)
				)
			)
		)
		(property "MPN" "MLG1005S20NJTD25"
			(at 0 0 180)
			(unlocked yes)
			(layer "F.Fab")
			(hide yes)
			(effects
				(font
					(size 1 1)
					(thickness 0.15)
				)
			)
		)
		(property "ISat" ""
			(at 0 0 180)
			(unlocked yes)
			(layer "F.Fab")
			(hide yes)
			(effects
				(font
					(size 1 1)
					(thickness 0.15)
				)
			)
		)
		(property "IMax" "0.35 A"
			(at 0 0 180)
			(unlocked yes)
			(layer "F.Fab")
			(hide yes)
			(effects
				(font
					(size 1 1)
					(thickness 0.15)
				)
			)
		)
		(property "Size" "1.0x0.5"
			(at 0 0 180)
			(unlocked yes)
			(layer "F.Fab")
			(hide yes)
			(effects
				(font
					(size 1 1)
					(thickness 0.15)
				)
			)
		)
		(property "Author" "Antmicro"
			(at 0 0 180)
			(unlocked yes)
			(layer "F.Fab")
			(hide yes)
			(effects
				(font
					(size 1 1)
					(thickness 0.15)
				)
			)
		)
		(property "License" "Apache-2.0"
			(at 0 0 180)
			(unlocked yes)
			(layer "F.Fab")
			(hide yes)
			(effects
				(font
					(size 1 1)
					(thickness 0.15)
				)
			)
		)
		(sheetname "/HDMI + SD Card/")
		(sheetfile "hdmi-sd-card.kicad_sch")
		(attr smd)
		(fp_rect
			(start -0.925 -0.47)
			(end 0.925 0.47)
			(stroke
				(width 0.05)
				(type default)
			)
			(fill no)
			(layer "F.CrtYd")
		)
		(fp_rect
			(start -0.499 -0.249)
			(end 0.499 0.249)
			(stroke
				(width 0.15)
				(type solid)
			)
			(fill no)
			(layer "F.Fab")
		)
		(fp_text user "${REFERENCE}"
			(at -0.932 3.168 180)
			(layer "F.Fab")
			(effects
				(font
					(size 0.7 0.7)
					(thickness 0.15)
				)
				(justify left bottom)
			)
		)
		(fp_text user "Author: Antmicro"
			(at -0.932 4.17 180)
			(layer "F.Fab")
			(effects
				(font
					(size 0.7 0.7)
					(thickness 0.15)
				)
				(justify left bottom)
			)
		)
		(fp_text user "License: Apache-2.0"
			(at -0.932 5.17 180)
			(layer "F.Fab")
			(effects
				(font
					(size 0.7 0.7)
					(thickness 0.15)
				)
				(justify left bottom)
			)
		)
		(pad "1" smd roundrect
			(at -0.48 0 180)
			(size 0.59 0.64)
			(layers "F.Cu" "F.Mask" "F.Paste")
			(roundrect_rratio 0.25)
			(net 380 "/FPGA MGT Interface/HDMI_IN.D0_P")
			(pintype "passive")
		)
		(pad "2" smd roundrect
			(at 0.48 0 180)
			(size 0.59 0.64)
			(layers "F.Cu" "F.Mask" "F.Paste")
			(roundrect_rratio 0.25)
			(net 680 "Net-(L10-Pad2)")
			(pintype "passive")
		)
	)
	(footprint "antmicro-footprints:R_0402_1005Metric"
		(layer "F.Cu")
		(at 114.806 173.322 -90)
		(descr "Resistor SMD 0402")
		(tags "resistor SMD 0402")
		(property "Reference" "R38"
			(at -3.05 -0.43 90)
			(layer "F.SilkS")
			(effects
				(font
					(size 0.7 0.7)
					(thickness 0.15)
				)
				(justify right bottom)
			)
		)
		(property "Value" "R_0R_0402"
			(at -1.011843 1.772047 90)
			(layer "F.Fab")
			(effects
				(font
					(size 0.7 0.7)
					(thickness 0.15)
				)
				(justify right bottom)
			)
		)
		(property "Datasheet" "https://industrial.panasonic.com/cdbs/www-data/pdf/RDA0000/AOA0000C301.pdf"
			(at 0 0 270)
			(layer "F.Fab")
			(hide yes)
			(effects
				(font
					(size 1.27 1.27)
					(thickness 0.15)
				)
			)
		)
		(property "MPN" "ERJ2GE0R00X"
			(at 0 0 270)
			(unlocked yes)
			(layer "F.Fab")
			(hide yes)
			(effects
				(font
					(size 1 1)
					(thickness 0.15)
				)
			)
		)
		(property "Manufacturer" "Panasonic"
			(at 0 0 270)
			(unlocked yes)
			(layer "F.Fab")
			(hide yes)
			(effects
				(font
					(size 1 1)
					(thickness 0.15)
				)
			)
		)
		(property "License" "Apache-2.0"
			(at 0 0 270)
			(unlocked yes)
			(layer "F.Fab")
			(hide yes)
			(effects
				(font
					(size 1 1)
					(thickness 0.15)
				)
			)
		)
		(property "Author" "Antmicro"
			(at 0 0 270)
			(unlocked yes)
			(layer "F.Fab")
			(hide yes)
			(effects
				(font
					(size 1 1)
					(thickness 0.15)
				)
			)
		)
		(property "Val" "0R"
			(at 0 0 270)
			(unlocked yes)
			(layer "F.Fab")
			(hide yes)
			(effects
				(font
					(size 1 1)
					(thickness 0.15)
				)
			)
		)
		(property "Tolerance" "~"
			(at 0 0 270)
			(unlocked yes)
			(layer "F.Fab")
			(hide yes)
			(effects
				(font
					(size 1 1)
					(thickness 0.15)
				)
			)
		)
		(property "Current" "1A"
			(at 0 0 270)
			(unlocked yes)
			(layer "F.Fab")
			(hide yes)
			(effects
				(font
					(size 1 1)
					(thickness 0.15)
				)
			)
		)
		(sheetname "/HDMI + SD Card/")
		(sheetfile "hdmi-sd-card.kicad_sch")
		(attr smd)
		(fp_rect
			(start -0.925 -0.47)
			(end 0.925 0.47)
			(stroke
				(width 0.05)
				(type default)
			)
			(fill no)
			(layer "F.CrtYd")
		)
		(fp_rect
			(start -0.5 -0.25)
			(end 0.5 0.25)
			(stroke
				(width 0.15)
				(type solid)
			)
			(fill no)
			(layer "F.Fab")
		)
		(fp_text user "License: Apache-2.0"
			(at -0.95 5.169 270)
			(layer "F.Fab")
			(effects
				(font
					(size 0.7 0.7)
					(thickness 0.15)
				)
				(justify left bottom)
			)
		)
		(fp_text user "${REFERENCE}"
			(at -0.95 3.168 270)
			(layer "F.Fab")
			(effects
				(font
					(size 0.7 0.7)
					(thickness 0.15)
				)
				(justify left bottom)
			)
		)
		(fp_text user "Author: Antmicro"
			(at -0.95 4.169 270)
			(layer "F.Fab")
			(effects
				(font
					(size 0.7 0.7)
					(thickness 0.15)
				)
				(justify left bottom)
			)
		)
		(pad "1" smd roundrect
			(at -0.48 0 270)
			(size 0.59 0.64)
			(layers "F.Cu" "F.Mask" "F.Paste")
			(roundrect_rratio 0.25)
			(net 530 "Net-(U38-HPD_SNK)")
			(pintype "passive")
		)
		(pad "2" smd roundrect
			(at 0.48 0 270)
			(size 0.59 0.64)
			(layers "F.Cu" "F.Mask" "F.Paste")
			(roundrect_rratio 0.25)
			(net 605 "/HDMI + SD Card/HDMI0.HPD")
			(pintype "passive")
		)
	)
	(footprint "antmicro-footprints:MicroSD_Wurth_693071020811"
		(layer "F.Cu")
		(at 105.584 160.865 -90)
		(descr "SMT MICRO SD CARD CONNECTOR")
		(property "Reference" "J5"
			(at 8.685 -3.991 0)
			(layer "F.SilkS")
			(effects
				(font
					(size 0.7 0.7)
					(thickness 0.15)
				)
				(justify left bottom)
			)
		)
		(property "Value" "MicroSD_693071020811"
			(at 0 8.9 90)
			(layer "F.Fab")
			(effects
				(font
					(size 0.7 0.7)
					(thickness 0.15)
				)
				(justify right bottom)
			)
		)
		(property "Datasheet" "https://www.we-online.com/catalog/datasheet/693071020811.pdf"
			(at 0 0 90)
			(layer "F.Fab")
			(hide yes)
			(effects
				(font
					(size 1.27 1.27)
					(thickness 0.15)
				)
			)
		)
		(property "Manufacturer" "Würth Elektronik"
			(at 0 0 270)
			(unlocked yes)
			(layer "F.Fab")
			(hide yes)
			(effects
				(font
					(size 1 1)
					(thickness 0.15)
				)
			)
		)
		(property "MPN" "693071020811"
			(at 0 0 270)
			(unlocked yes)
			(layer "F.Fab")
			(hide yes)
			(effects
				(font
					(size 1 1)
					(thickness 0.15)
				)
			)
		)
		(property "Author" "Antmicro"
			(at 0 0 270)
			(unlocked yes)
			(layer "F.Fab")
			(hide yes)
			(effects
				(font
					(size 1 1)
					(thickness 0.15)
				)
			)
		)
		(property "License" "Apache-2.0"
			(at 0 0 270)
			(unlocked yes)
			(layer "F.Fab")
			(hide yes)
			(effects
				(font
					(size 1 1)
					(thickness 0.15)
				)
			)
		)
		(sheetname "/HDMI + SD Card/")
		(sheetfile "hdmi-sd-card.kicad_sch")
		(attr smd)
		(fp_line
			(start -7.35 1.432)
			(end -7.35 -5.267)
			(stroke
				(width 0.15)
				(type solid)
			)
			(layer "F.SilkS")
		)
		(fp_line
			(start 7.35 1.432)
			(end 7.35 -5.267)
			(stroke
				(width 0.15)
				(type solid)
			)
			(layer "F.SilkS")
		)
		(fp_line
			(start 6.201 -7.148)
			(end 2.801 -7.148)
			(stroke
				(width 0.15)
				(type solid)
			)
			(layer "F.SilkS")
		)
		(fp_circle
			(center 2.85 -7.9)
			(end 2.9 -7.9)
			(stroke
				(width 0.15)
				(type solid)
			)
			(fill yes)
			(layer "F.SilkS")
		)
		(fp_line
			(start -7.55 7.7)
			(end -7.55 4.55)
			(stroke
				(width 0.05)
				(type solid)
			)
			(layer "F.CrtYd")
		)
		(fp_line
			(start 7.5 7.7)
			(end -7.55 7.7)
			(stroke
				(width 0.05)
				(type solid)
			)
			(layer "F.CrtYd")
		)
		(fp_line
			(start 7.5 7.7)
			(end 7.5 4.55)
			(stroke
				(width 0.05)
				(type solid)
			)
			(layer "F.CrtYd")
		)
		(fp_line
			(start -8.7 4.55)
			(end -7.55 4.55)
			(stroke
				(width 0.05)
				(type solid)
			)
			(layer "F.CrtYd")
		)
		(fp_line
			(start -8.7 4.55)
			(end -8.7 1.6)
			(stroke
				(width 0.05)
				(type solid)
			)
			(layer "F.CrtYd")
		)
		(fp_line
			(start 8.7 4.55)
			(end 7.5 4.55)
			(stroke
				(width 0.05)
				(type solid)
			)
			(layer "F.CrtYd")
		)
		(fp_line
			(start 8.7 4.55)
			(end 8.7 1.6)
			(stroke
				(width 0.05)
				(type solid)
			)
			(layer "F.CrtYd")
		)
		(fp_line
			(start -7.55 1.6)
			(end -8.7 1.6)
			(stroke
				(width 0.05)
				(type solid)
			)
			(layer "F.CrtYd")
		)
		(fp_line
			(start 7.5 1.6)
			(end 8.7 1.6)
			(stroke
				(width 0.05)
				(type solid)
			)
			(layer "F.CrtYd")
		)
		(fp_line
			(start 7.5 1.6)
			(end 7.5 -5.45)
			(stroke
				(width 0.05)
				(type solid)
			)
			(layer "F.CrtYd")
		)
		(fp_line
			(start -7.55 -5.45)
			(end -7.55 1.6)
			(stroke
				(width 0.05)
				(type solid)
			)
			(layer "F.CrtYd")
		)
		(fp_line
			(start -7.55 -5.45)
			(end -9.1 -5.45)
			(stroke
				(width 0.05)
				(type solid)
			)
			(layer "F.CrtYd")
		)
		(fp_line
			(start 7.5 -5.45)
			(end 8.4 -5.45)
			(stroke
				(width 0.05)
				(type solid)
			)
			(layer "F.CrtYd")
		)
		(fp_line
			(start -9.1 -7.6)
			(end -9.1 -5.45)
			(stroke
				(width 0.05)
				(type solid)
			)
			(layer "F.CrtYd")
		)
		(fp_line
			(start -9.1 -7.6)
			(end -7.05 -7.6)
			(stroke
				(width 0.05)
				(type solid)
			)
			(layer "F.CrtYd")
		)
		(fp_line
			(start 2.75 -7.6)
			(end 2.75 -8.7)
			(stroke
				(width 0.05)
				(type solid)
			)
			(layer "F.CrtYd")
		)
		(fp_line
			(start 8.4 -7.6)
			(end 8.4 -5.45)
			(stroke
				(width 0.05)
				(type solid)
			)
			(layer "F.CrtYd")
		)
		(fp_line
			(start 8.4 -7.6)
			(end 2.75 -7.6)
			(stroke
				(width 0.05)
				(type solid)
			)
			(layer "F.CrtYd")
		)
		(fp_line
			(start -7.05 -8.7)
			(end -7.05 -7.6)
			(stroke
				(width 0.05)
				(type solid)
			)
			(layer "F.CrtYd")
		)
		(fp_line
			(start -7.05 -8.7)
			(end 2.75 -8.7)
			(stroke
				(width 0.05)
				(type solid)
			)
			(layer "F.CrtYd")
		)
		(fp_line
			(start -7.35 7.502)
			(end 7.35 7.502)
			(stroke
				(width 0.15)
				(type solid)
			)
			(layer "F.Fab")
		)
		(fp_line
			(start 7.35 7.353)
			(end 7.35 -7.148)
			(stroke
				(width 0.15)
				(type solid)
			)
			(layer "F.Fab")
		)
		(fp_line
			(start -7.35 -7.148)
			(end -7.35 7.353)
			(stroke
				(width 0.15)
				(type solid)
			)
			(layer "F.Fab")
		)
		(fp_line
			(start 7.35 -7.148)
			(end -7.35 -7.148)
			(stroke
				(width 0.15)
				(type solid)
			)
			(layer "F.Fab")
		)
		(fp_text user "Author: Antmicro"
			(at -9.1 13.501 270)
			(layer "F.Fab")
			(effects
				(font
					(size 0.7 0.7)
					(thickness 0.15)
				)
				(justify left bottom)
			)
		)
		(fp_text user "${REFERENCE}"
			(at -9.1 15.901 270)
			(layer "F.Fab")
			(effects
				(font
					(size 0.7 0.7)
					(thickness 0.15)
				)
				(justify left bottom)
			)
		)
		(fp_text user "License: Apache-2.0"
			(at -9.1 14.701 270)
			(layer "F.Fab")
			(effects
				(font
					(size 0.7 0.7)
					(thickness 0.15)
				)
				(justify left bottom)
			)
		)
		(pad "" np_thru_hole circle
			(at -4.95 3.485 270)
			(size 1 1)
			(drill 1)
			(layers "*.Cu" "*.Mask")
		)
		(pad "" np_thru_hole oval
			(at 3.05 3.485 270)
			(size 1.7 1)
			(drill oval 1.7 1)
			(layers "*.Cu" "*.Mask")
		)
		(pad "1" smd rect
			(at 2.25 -7.57 270)
			(size 0.7 1.9)
			(layers "F.Cu" "F.Mask" "F.Paste")
			(net 606 "/HDMI + SD Card/SD_DAT2")
			(pinfunction "DAT2")
			(pintype "bidirectional")
		)
		(pad "2" smd rect
			(at 1.15 -7.57 270)
			(size 0.7 1.9)
			(layers "F.Cu" "F.Mask" "F.Paste")
			(net 607 "/HDMI + SD Card/SD_DAT3")
			(pinfunction "DAT3/CD")
			(pintype "bidirectional")
		)
		(pad "3" smd rect
			(at 0.05 -7.57 270)
			(size 0.7 1.9)
			(layers "F.Cu" "F.Mask" "F.Paste")
			(net 608 "/HDMI + SD Card/SD_CMD")
			(pinfunction "CMD")
			(pintype "input")
		)
		(pad "4" smd rect
			(at -1.05 -7.57 270)
			(size 0.7 1.9)
			(layers "F.Cu" "F.Mask" "F.Paste")
			(net 151 "+3V3")
			(pinfunction "VDD")
			(pintype "power_in")
		)
		(pad "5" smd rect
			(at -2.15 -7.57 270)
			(size 0.7 1.9)
			(layers "F.Cu" "F.Mask" "F.Paste")
			(net 609 "/HDMI + SD Card/SD_CLK")
			(pinfunction "CLK")
			(pintype "input")
		)
		(pad "6" smd rect
			(at -3.25 -7.57 270)
			(size 0.7 1.9)
			(layers "F.Cu" "F.Mask" "F.Paste")
			(net 1 "GND")
			(pinfunction "VSS")
			(pintype "passive")
		)
		(pad "7" smd rect
			(at -4.35 -7.57 270)
			(size 0.7 1.9)
			(layers "F.Cu" "F.Mask" "F.Paste")
			(net 611 "/HDMI + SD Card/SD_DAT0")
			(pinfunction "DAT0")
			(pintype "input")
		)
		(pad "8" smd rect
			(at -5.45 -7.57 270)
			(size 0.7 1.9)
			(layers "F.Cu" "F.Mask" "F.Paste")
			(net 612 "/HDMI + SD Card/SD_DAT1")
			(pinfunction "DAT1")
			(pintype "input")
		)
		(pad "9" smd rect
			(at -6.55 -7.57 270)
			(size 0.7 1.9)
			(layers "F.Cu" "F.Mask" "F.Paste")
			(net 249 "Net-(J5-CD_SW1)")
			(pinfunction "CD_SW1")
			(pintype "passive")
		)
		(pad "SH" smd rect
			(at -8.1 -6.515 270)
			(size 1.7 1.8)
			(layers "F.Cu" "F.Mask" "F.Paste")
			(net 1 "GND")
			(pinfunction "SH")
			(pintype "passive")
		)
		(pad "SH" smd rect
			(at -7.85 3.08 270)
			(size 1.4 2.6)
			(layers "F.Cu" "F.Mask" "F.Paste")
			(net 1 "GND")
			(pinfunction "SH")
			(pintype "passive")
		)
		(pad "SH" smd rect
			(at 7.4 -6.515 270)
			(size 1.7 1.8)
			(layers "F.Cu" "F.Mask" "F.Paste")
			(net 1 "GND")
			(pinfunction "SH")
			(pintype "passive")
		)
		(pad "SH" smd rect
			(at 7.85 3.08 270)
			(size 1.4 2.6)
			(layers "F.Cu" "F.Mask" "F.Paste")
			(net 1 "GND")
			(pinfunction "SH")
			(pintype "passive")
		)
	)
	(footprint "antmicro-footprints:C_0603_1608Metric"
		(layer "F.Cu")
		(at 242.8 114.7)
		(descr "Capacitor SMD 0603")
		(tags "capacitor 0603")
		(property "Reference" "C7"
			(at -2.8 0.26 0)
			(layer "F.SilkS")
			(effects
				(font
					(size 0.7 0.7)
					(thickness 0.15)
				)
				(justify left bottom)
			)
		)
		(property "Value" "C_10u_25V_0603"
			(at -1.42757 1.770288 0)
			(layer "F.Fab")
			(effects
				(font
					(size 0.7 0.7)
					(thickness 0.15)
				)
				(justify left bottom)
			)
		)
		(property "Datasheet" "https://product.tdk.com/en/search/capacitor/ceramic/mlcc/info?part_no=C1608X5R1E106M080AC"
			(at 0 0 0)
			(layer "F.Fab")
			(hide yes)
			(effects
				(font
					(size 1.27 1.27)
					(thickness 0.15)
				)
			)
		)
		(property "MPN" "C1608X5R1E106M080AC"
			(at 0 0 0)
			(unlocked yes)
			(layer "F.Fab")
			(hide yes)
			(effects
				(font
					(size 1 1)
					(thickness 0.15)
				)
			)
		)
		(property "Manufacturer" "TDK"
			(at 0 0 0)
			(unlocked yes)
			(layer "F.Fab")
			(hide yes)
			(effects
				(font
					(size 1 1)
					(thickness 0.15)
				)
			)
		)
		(property "License" "Apache-2.0"
			(at 0 0 0)
			(unlocked yes)
			(layer "F.Fab")
			(hide yes)
			(effects
				(font
					(size 1 1)
					(thickness 0.15)
				)
			)
		)
		(property "Author" "Antmicro"
			(at 0 0 0)
			(unlocked yes)
			(layer "F.Fab")
			(hide yes)
			(effects
				(font
					(size 1 1)
					(thickness 0.15)
				)
			)
		)
		(property "Val" "10u"
			(at 0 0 0)
			(unlocked yes)
			(layer "F.Fab")
			(hide yes)
			(effects
				(font
					(size 1 1)
					(thickness 0.15)
				)
			)
		)
		(property "Voltage" "25V"
			(at 0 0 0)
			(unlocked yes)
			(layer "F.Fab")
			(hide yes)
			(effects
				(font
					(size 1 1)
					(thickness 0.15)
				)
			)
		)
		(property "Dielectric" ""
			(at 0 0 0)
			(unlocked yes)
			(layer "F.Fab")
			(hide yes)
			(effects
				(font
					(size 1 1)
					(thickness 0.15)
				)
			)
		)
		(sheetname "/DDR5 RDIMM/")
		(sheetfile "ddr5-rdimm.kicad_sch")
		(attr smd)
		(fp_line
			(start -0.15 -0.4)
			(end 0.15 -0.4)
			(stroke
				(width 0.15)
				(type solid)
			)
			(layer "F.SilkS")
		)
		(fp_line
			(start -0.15 0.4)
			(end 0.15 0.4)
			(stroke
				(width 0.15)
				(type solid)
			)
			(layer "F.SilkS")
		)
		(fp_rect
			(start -1.25 -0.65)
			(end 1.25 0.65)
			(stroke
				(width 0.05)
				(type solid)
			)
			(fill no)
			(layer "F.CrtYd")
		)
		(fp_rect
			(start -0.8 -0.4)
			(end 0.8 0.4)
			(stroke
				(width 0.15)
				(type solid)
			)
			(fill no)
			(layer "F.Fab")
		)
		(fp_text user "${REFERENCE}"
			(at -1.682 3.895 0)
			(layer "F.Fab")
			(effects
				(font
					(size 0.7 0.7)
					(thickness 0.15)
				)
				(justify left bottom)
			)
		)
		(fp_text user "Author: Antmicro"
			(at -1.682 4.894 0)
			(layer "F.Fab")
			(effects
				(font
					(size 0.7 0.7)
					(thickness 0.15)
				)
				(justify left bottom)
			)
		)
		(fp_text user "License: Apache-2.0"
			(at -1.682 5.895 0)
			(layer "F.Fab")
			(effects
				(font
					(size 0.7 0.7)
					(thickness 0.15)
				)
				(justify left bottom)
			)
		)
		(pad "1" smd roundrect
			(at -0.7 0)
			(size 0.8 1)
			(layers "F.Cu" "F.Mask" "F.Paste")
			(roundrect_rratio 0.2)
			(net 1 "GND")
			(pintype "passive")
		)
		(pad "2" smd roundrect
			(at 0.7 0)
			(size 0.8 1)
			(layers "F.Cu" "F.Mask" "F.Paste")
			(roundrect_rratio 0.2)
			(net 802 "/DDR5 RDIMM/VIN_BULK")
			(pintype "passive")
		)
	)
	(footprint "antmicro-footprints:MP_NPTH_Drill3mm"
		(layer "F.Cu")
		(at 262 187)
		(property "Reference" "MP3"
			(at 0 -1.8 0)
			(layer "F.SilkS")
			(hide yes)
			(effects
				(font
					(size 0.7 0.7)
					(thickness 0.15)
				)
				(justify left bottom)
			)
		)
		(property "Value" "MP_NPTH_Drill3mm"
			(at 0 2.4 0)
			(layer "F.Fab")
			(effects
				(font
					(size 0.7 0.7)
					(thickness 0.15)
				)
				(justify left bottom)
			)
		)
		(sheetfile "data-center-rdimm-ddr5-tester.kicad_sch")
		(attr board_only exclude_from_pos_files exclude_from_bom)
		(fp_circle
			(center 0 0)
			(end 1.6 0)
			(stroke
				(width 0.05)
				(type default)
			)
			(fill no)
			(layer "F.CrtYd")
		)
		(fp_text user "${REFERENCE}"
			(at 0 4.749 0)
			(layer "F.Fab")
			(effects
				(font
					(size 0.7 0.7)
					(thickness 0.15)
				)
				(justify left bottom)
			)
		)
		(fp_text user "Author: Antmicro"
			(at 0 5.95 0)
			(layer "F.Fab")
			(effects
				(font
					(size 0.7 0.7)
					(thickness 0.15)
				)
				(justify left bottom)
			)
		)
		(fp_text user "License: Apache-2.0"
			(at 0 7.15 0)
			(layer "F.Fab")
			(effects
				(font
					(size 0.7 0.7)
					(thickness 0.15)
				)
				(justify left bottom)
			)
		)
		(pad "" np_thru_hole circle
			(at 0 0)
			(size 3 3)
			(drill 3)
			(layers "*.Cu" "*.Mask")
		)
	)
	(footprint "antmicro-footprints:Heatsink_ATS-61500R-C2-R0"
		(layer "F.Cu")
		(at 188.5 152.5)
		(property "Reference" "A1"
			(at 0.003 -27.94 0)
			(unlocked yes)
			(layer "F.SilkS")
			(hide yes)
			(effects
				(font
					(size 0.7 0.7)
					(thickness 0.15)
				)
				(justify left bottom)
			)
		)
		(property "Value" "Heatsink_ATS-61500R-C2-R0"
			(at 0.003 27.94 0)
			(unlocked yes)
			(layer "F.Fab")
			(effects
				(font
					(size 0.7 0.7)
					(thickness 0.15)
				)
				(justify left bottom)
			)
		)
		(property "Datasheet" "https://www.qats.com/DataSheet/ATS-61500-Series-C2-R0"
			(at 0 0 0)
			(layer "F.Fab")
			(hide yes)
			(effects
				(font
					(size 1.27 1.27)
					(thickness 0.15)
				)
			)
		)
		(property "MPN" "ATS-61500R-C2-R0"
			(at 0 0 0)
			(unlocked yes)
			(layer "F.Fab")
			(hide yes)
			(effects
				(font
					(size 1 1)
					(thickness 0.15)
				)
			)
		)
		(property "Manufacturer" "Advanced Thermal Solutions"
			(at 0 0 0)
			(unlocked yes)
			(layer "F.Fab")
			(hide yes)
			(effects
				(font
					(size 1 1)
					(thickness 0.15)
				)
			)
		)
		(property "Author" "Antmicro"
			(at 0 0 0)
			(unlocked yes)
			(layer "F.Fab")
			(hide yes)
			(effects
				(font
					(size 1 1)
					(thickness 0.15)
				)
			)
		)
		(property "License" "Apache-2.0"
			(at 0 0 0)
			(unlocked yes)
			(layer "F.Fab")
			(hide yes)
			(effects
				(font
					(size 1 1)
					(thickness 0.15)
				)
			)
		)
		(property ki_fp_filters "Heatsink_*")
		(sheetname "/")
		(sheetfile "data-center-rdimm-ddr5-tester.kicad_sch")
		(attr exclude_from_pos_files)
		(fp_circle
			(center -22 -22)
			(end -17.78 -22)
			(stroke
				(width 0.05)
				(type solid)
			)
			(fill no)
			(layer "F.CrtYd")
		)
		(fp_circle
			(center -22 22)
			(end -17.78 22)
			(stroke
				(width 0.05)
				(type solid)
			)
			(fill no)
			(layer "F.CrtYd")
		)
		(fp_circle
			(center 22 -22)
			(end 26.22 -22)
			(stroke
				(width 0.05)
				(type solid)
			)
			(fill no)
			(layer "F.CrtYd")
		)
		(fp_circle
			(center 22 22)
			(end 26.22 22)
			(stroke
				(width 0.05)
				(type solid)
			)
			(fill no)
			(layer "F.CrtYd")
		)
		(fp_text user "Author: Antmicro"
			(at -27.32 31.72 0)
			(layer "F.Fab")
			(effects
				(font
					(size 0.7 0.7)
					(thickness 0.15)
				)
				(justify left bottom)
			)
		)
		(fp_text user "${REFERENCE}"
			(at -27.32 30.52 0)
			(layer "F.Fab")
			(effects
				(font
					(size 0.7 0.7)
					(thickness 0.15)
				)
				(justify left bottom)
			)
		)
		(fp_text user "License: Apache-2.0"
			(at -27.32 29.32 0)
			(layer "F.Fab")
			(effects
				(font
					(size 0.7 0.7)
					(thickness 0.15)
				)
				(justify left bottom)
			)
		)
		(fp_text user "Suggested mounting holes diameter: 3.18 mm"
			(at -9.07 -0.18 0)
			(layer "F.Fab")
			(effects
				(font
					(size 0.7 0.7)
					(thickness 0.15)
				)
				(justify left bottom)
			)
		)
		(zone
			(net 0)
			(net_name "")
			(layers "F.Cu" "B.Cu" "In1.Cu" "In2.Cu" "In3.Cu" "In4.Cu" "In5.Cu" "In6.Cu"
				"In7.Cu" "In8.Cu" "In9.Cu" "In10.Cu"
			)
			(hatch edge 0.5)
			(connect_pads
				(clearance 0)
			)
			(min_thickness 0.25)
			(filled_areas_thickness no)
			(keepout
				(tracks not_allowed)
				(vias not_allowed)
				(pads allowed)
				(copperpour not_allowed)
				(footprints allowed)
			)
			(placement
				(enabled no)
				(sheetname "")
			)
			(fill
				(thermal_gap 0.5)
				(thermal_bridge_width 0.5)
			)
			(polygon
				(pts
					(xy 168.5 130.5) (xy 168.479643 130.21537) (xy 168.418986 129.936535) (xy 168.319264 129.66917)
					(xy 168.182507 129.418718) (xy 168.011499 129.190279) (xy 167.809721 128.988501) (xy 167.581282 128.817493)
					(xy 167.33083 128.680736) (xy 167.063465 128.581014) (xy 166.78463 128.520357) (xy 166.5 128.5)
					(xy 166.21537 128.520357) (xy 165.936535 128.581014) (xy 165.66917 128.680736) (xy 165.418718 128.817493)
					(xy 165.190279 128.988501) (xy 164.988501 129.190279) (xy 164.817493 129.418718) (xy 164.680736 129.66917)
					(xy 164.581014 129.936535) (xy 164.520357 130.21537) (xy 164.5 130.5) (xy 164.520357 130.78463)
					(xy 164.581014 131.063465) (xy 164.680736 131.33083) (xy 164.817493 131.581282) (xy 164.988501 131.809721)
					(xy 165.190279 132.011499) (xy 165.418718 132.182507) (xy 165.66917 132.319264) (xy 165.936535 132.418986)
					(xy 166.21537 132.479643) (xy 166.5 132.5) (xy 166.78463 132.479643) (xy 167.063465 132.418986)
					(xy 167.33083 132.319264) (xy 167.581282 132.182507) (xy 167.809721 132.011499) (xy 168.011499 131.809721)
					(xy 168.182507 131.581282) (xy 168.319264 131.33083) (xy 168.418986 131.063465) (xy 168.479643 130.78463)
				)
			)
		)
		(zone
			(net 0)
			(net_name "")
			(layers "F.Cu" "B.Cu" "In1.Cu" "In2.Cu" "In3.Cu" "In4.Cu" "In5.Cu" "In6.Cu"
				"In7.Cu" "In8.Cu" "In9.Cu" "In10.Cu"
			)
			(hatch edge 0.5)
			(connect_pads
				(clearance 0)
			)
			(min_thickness 0.25)
			(filled_areas_thickness no)
			(keepout
				(tracks not_allowed)
				(vias not_allowed)
				(pads allowed)
				(copperpour not_allowed)
				(footprints allowed)
			)
			(placement
				(enabled no)
				(sheetname "")
			)
			(fill
				(thermal_gap 0.5)
				(thermal_bridge_width 0.5)
			)
			(polygon
				(pts
					(xy 168.5 174.481014) (xy 168.479643 174.196384) (xy 168.418986 173.917549) (xy 168.319264 173.650184)
					(xy 168.182507 173.399732) (xy 168.011499 173.171293) (xy 167.809721 172.969515) (xy 167.581282 172.798507)
					(xy 167.33083 172.66175) (xy 167.063465 172.562028) (xy 166.78463 172.501371) (xy 166.5 172.481014)
					(xy 166.21537 172.501371) (xy 165.936535 172.562028) (xy 165.66917 172.66175) (xy 165.418718 172.798507)
					(xy 165.190279 172.969515) (xy 164.988501 173.171293) (xy 164.817493 173.399732) (xy 164.680736 173.650184)
					(xy 164.581014 173.917549) (xy 164.520357 174.196384) (xy 164.5 174.481014) (xy 164.520357 174.765644)
					(xy 164.581014 175.044479) (xy 164.680736 175.311844) (xy 164.817493 175.562296) (xy 164.988501 175.790735)
					(xy 165.190279 175.992513) (xy 165.418718 176.163521) (xy 165.66917 176.300278) (xy 165.936535 176.4)
					(xy 166.21537 176.460657) (xy 166.5 176.481014) (xy 166.78463 176.460657) (xy 167.063465 176.4)
					(xy 167.33083 176.300278) (xy 167.581282 176.163521) (xy 167.809721 175.992513) (xy 168.011499 175.790735)
					(xy 168.182507 175.562296) (xy 168.319264 175.311844) (xy 168.418986 175.044479) (xy 168.479643 174.765644)
				)
			)
		)
		(zone
			(net 0)
			(net_name "")
			(layers "F.Cu" "B.Cu" "In1.Cu" "In2.Cu" "In3.Cu" "In4.Cu" "In5.Cu" "In6.Cu"
				"In7.Cu" "In8.Cu" "In9.Cu" "In10.Cu"
			)
			(hatch edge 0.5)
			(connect_pads
				(clearance 0)
			)
			(min_thickness 0.25)
			(filled_areas_thickness no)
			(keepout
				(tracks not_allowed)
				(vias not_allowed)
				(pads allowed)
				(copperpour not_allowed)
				(footprints allowed)
			)
			(placement
				(enabled no)
				(sheetname "")
			)
			(fill
				(thermal_gap 0.5)
				(thermal_bridge_width 0.5)
			)
			(polygon
				(pts
					(xy 212.517493 174.481014) (xy 212.497136 174.196384) (xy 212.436479 173.917549) (xy 212.336757 173.650184)
					(xy 212.2 173.399732) (xy 212.028992 173.171293) (xy 211.827214 172.969515) (xy 211.598775 172.798507)
					(xy 211.348323 172.66175) (xy 211.080958 172.562028) (xy 210.802123 172.501371) (xy 210.517493 172.481014)
					(xy 210.232863 172.501371) (xy 209.954028 172.562028) (xy 209.686663 172.66175) (xy 209.436211 172.798507)
					(xy 209.207772 172.969515) (xy 209.005994 173.171293) (xy 208.834986 173.399732) (xy 208.698229 173.650184)
					(xy 208.598507 173.917549) (xy 208.53785 174.196384) (xy 208.517493 174.481014) (xy 208.53785 174.765644)
					(xy 208.598507 175.044479) (xy 208.698229 175.311844) (xy 208.834986 175.562296) (xy 209.005994 175.790735)
					(xy 209.207772 175.992513) (xy 209.436211 176.163521) (xy 209.686663 176.300278) (xy 209.954028 176.4)
					(xy 210.232863 176.460657) (xy 210.517493 176.481014) (xy 210.802123 176.460657) (xy 211.080958 176.4)
					(xy 211.348323 176.300278) (xy 211.598775 176.163521) (xy 211.827214 175.992513) (xy 212.028992 175.790735)
					(xy 212.2 175.562296) (xy 212.336757 175.311844) (xy 212.436479 175.044479) (xy 212.497136 174.765644)
				)
			)
		)
		(zone
			(net 0)
			(net_name "")
			(layers "F.Cu" "B.Cu" "In1.Cu" "In2.Cu" "In3.Cu" "In4.Cu" "In5.Cu" "In6.Cu"
				"In7.Cu" "In8.Cu" "In9.Cu" "In10.Cu"
			)
			(hatch edge 0.5)
			(connect_pads
				(clearance 0)
			)
			(min_thickness 0.25)
			(filled_areas_thickness no)
			(keepout
				(tracks not_allowed)
				(vias not_allowed)
				(pads allowed)
				(copperpour not_allowed)
				(footprints allowed)
			)
			(placement
				(enabled no)
				(sheetname "")
			)
			(fill
				(thermal_gap 0.5)
				(thermal_bridge_width 0.5)
			)
			(polygon
				(pts
					(xy 212.520357 130.48463) (xy 212.5 130.2) (xy 212.439343 129.921165) (xy 212.339621 129.6538)
					(xy 212.202864 129.403348) (xy 212.031856 129.174909) (xy 211.830078 128.973131) (xy 211.601639 128.802123)
					(xy 211.351187 128.665366) (xy 211.083822 128.565644) (xy 210.804987 128.504987) (xy 210.520357 128.48463)
					(xy 210.235727 128.504987) (xy 209.956892 128.565644) (xy 209.689527 128.665366) (xy 209.439075 128.802123)
					(xy 209.210636 128.973131) (xy 209.008858 129.174909) (xy 208.83785 129.403348) (xy 208.701093 129.6538)
					(xy 208.601371 129.921165) (xy 208.540714 130.2) (xy 208.520357 130.48463) (xy 208.540714 130.76926)
					(xy 208.601371 131.048095) (xy 208.701093 131.31546) (xy 208.83785 131.565912) (xy 209.008858 131.794351)
					(xy 209.210636 131.996129) (xy 209.439075 132.167137) (xy 209.689527 132.303894) (xy 209.956892 132.403616)
					(xy 210.235727 132.464273) (xy 210.520357 132.48463) (xy 210.804987 132.464273) (xy 211.083822 132.403616)
					(xy 211.351187 132.303894) (xy 211.601639 132.167137) (xy 211.830078 131.996129) (xy 212.031856 131.794351)
					(xy 212.202864 131.565912) (xy 212.339621 131.31546) (xy 212.439343 131.048095) (xy 212.5 130.76926)
				)
			)
		)
	)
	(footprint "antmicro-footprints:BGA-676_27x27mm_Layout26x26_P1x1mm_FFVB676"
		(layer "F.Cu")
		(at 188.5 152.5 90)
		(property "Reference" "U34"
			(at -14.72 12.46 180)
			(layer "F.SilkS")
			(effects
				(font
					(size 0.7 0.7)
					(thickness 0.15)
				)
				(justify left bottom)
			)
		)
		(property "Value" "XCAU25P-2FFVB676I"
			(at 0 15.5 90)
			(layer "F.Fab")
			(effects
				(font
					(size 0.7 0.7)
					(thickness 0.15)
				)
				(justify left bottom)
			)
		)
		(property "Datasheet" "https://docs.xilinx.com/viewer/book-attachment/2PXOpPtpaABIt0fkzeBLnw/hvbsEUaOT0OxFhln7VEVyA"
			(at 0 0 90)
			(layer "F.Fab")
			(hide yes)
			(effects
				(font
					(size 1.27 1.27)
					(thickness 0.15)
				)
			)
		)
		(property "MPN" "XCAU25P-2FFVB676I"
			(at 0 0 90)
			(unlocked yes)
			(layer "F.Fab")
			(hide yes)
			(effects
				(font
					(size 1 1)
					(thickness 0.15)
				)
			)
		)
		(property "Manufacturer" "AMD-Xilinx"
			(at 0 0 90)
			(unlocked yes)
			(layer "F.Fab")
			(hide yes)
			(effects
				(font
					(size 1 1)
					(thickness 0.15)
				)
			)
		)
		(property "Author" "Antmicro"
			(at 0 0 90)
			(unlocked yes)
			(layer "F.Fab")
			(hide yes)
			(effects
				(font
					(size 1 1)
					(thickness 0.15)
				)
			)
		)
		(property "License" "Apache-2.0"
			(at 0 0 90)
			(unlocked yes)
			(layer "F.Fab")
			(hide yes)
			(effects
				(font
					(size 1 1)
					(thickness 0.15)
				)
			)
		)
		(sheetname "/FPGA Config/")
		(sheetfile "fpga-config.kicad_sch")
		(attr smd)
		(fp_line
			(start 13.499 -13.5)
			(end 6.749 -13.5)
			(stroke
				(width 0.15)
				(type solid)
			)
			(layer "F.SilkS")
		)
		(fp_line
			(start 13.499 -13.5)
			(end 13.499 -6.75)
			(stroke
				(width 0.15)
				(type solid)
			)
			(layer "F.SilkS")
		)
		(fp_line
			(start -13.5 -13.5)
			(end -6.75 -13.5)
			(stroke
				(width 0.15)
				(type solid)
			)
			(layer "F.SilkS")
		)
		(fp_line
			(start -13.5 -13.5)
			(end -13.5 -6.75)
			(stroke
				(width 0.15)
				(type solid)
			)
			(layer "F.SilkS")
		)
		(fp_line
			(start 13.499 13.499)
			(end 13.499 6.749)
			(stroke
				(width 0.15)
				(type solid)
			)
			(layer "F.SilkS")
		)
		(fp_line
			(start 13.499 13.499)
			(end 6.749 13.499)
			(stroke
				(width 0.15)
				(type solid)
			)
			(layer "F.SilkS")
		)
		(fp_line
			(start -13.5 13.499)
			(end -13.5 6.749)
			(stroke
				(width 0.15)
				(type solid)
			)
			(layer "F.SilkS")
		)
		(fp_line
			(start -13.5 13.499)
			(end -6.75 13.499)
			(stroke
				(width 0.15)
				(type solid)
			)
			(layer "F.SilkS")
		)
		(fp_circle
			(center -13.8 -13.8)
			(end -13.75 -13.8)
			(stroke
				(width 0.15)
				(type solid)
			)
			(fill yes)
			(layer "F.SilkS")
		)
		(fp_rect
			(start -14.5 -14.5)
			(end 14.5 14.5)
			(stroke
				(width 0.05)
				(type solid)
			)
			(fill no)
			(layer "F.CrtYd")
		)
		(fp_rect
			(start -13.5 -13.5)
			(end 13.499 13.499)
			(stroke
				(width 0.15)
				(type solid)
			)
			(fill no)
			(layer "F.Fab")
		)
		(fp_text user "License: Apache-2.0"
			(at -14.5 17.5 90)
			(layer "F.Fab")
			(effects
				(font
					(size 0.7 0.7)
					(thickness 0.15)
				)
				(justify left bottom)
			)
		)
		(fp_text user "${REFERENCE}"
			(at -14.5 19.9 90)
			(layer "F.Fab")
			(effects
				(font
					(size 0.7 0.7)
					(thickness 0.15)
				)
				(justify left bottom)
			)
		)
		(fp_text user "Author: Antmicro"
			(at -14.5 18.7 90)
			(layer "F.Fab")
			(effects
				(font
					(size 0.7 0.7)
					(thickness 0.15)
				)
				(justify left bottom)
			)
		)
		(pad "A1" smd circle
			(at -12.5 -12.5 90)
			(size 0.5 0.5)
			(layers "F.Cu" "F.Mask" "F.Paste")
			(net 1 "GND")
			(pinfunction "GND")
			(pintype "power_in")
			(solder_mask_margin 0.075)
		)
		(pad "A2" smd circle
			(at -11.5 -12.5 90)
			(size 0.5 0.5)
			(layers "F.Cu" "F.Mask" "F.Paste")
			(net 1 "GND")
			(pinfunction "GND")
			(pintype "passive")
			(solder_mask_margin 0.075)
		)
		(pad "A3" smd circle
			(at -10.5 -12.5 90)
			(size 0.5 0.5)
			(layers "F.Cu" "F.Mask" "F.Paste")
			(net 463 "unconnected-(U34L-NC-PadA3)")
			(pinfunction "NC")
			(pintype "no_connect")
			(solder_mask_margin 0.075)
		)
		(pad "A4" smd circle
			(at -9.5 -12.5 90)
			(size 0.5 0.5)
			(layers "F.Cu" "F.Mask" "F.Paste")
			(net 464 "unconnected-(U34L-NC-PadA4)")
			(pinfunction "NC")
			(pintype "no_connect")
			(solder_mask_margin 0.075)
		)
		(pad "A5" smd circle
			(at -8.5 -12.5 90)
			(size 0.5 0.5)
			(layers "F.Cu" "F.Mask" "F.Paste")
			(net 1 "GND")
			(pinfunction "GND")
			(pintype "passive")
			(solder_mask_margin 0.075)
		)
		(pad "A6" smd circle
			(at -7.5 -12.5 90)
			(size 0.5 0.5)
			(layers "F.Cu" "F.Mask" "F.Paste")
			(net 1 "GND")
			(pinfunction "GND")
			(pintype "passive")
			(solder_mask_margin 0.075)
		)
		(pad "A7" smd circle
			(at -6.5 -12.5 90)
			(size 0.5 0.5)
			(layers "F.Cu" "F.Mask" "F.Paste")
			(net 172 "+1V2_MGTAVTT")
			(pinfunction "MGTAVTT_R")
			(pintype "input")
			(solder_mask_margin 0.075)
		)
		(pad "A8" smd circle
			(at -5.5 -12.5 90)
			(size 0.5 0.5)
			(layers "F.Cu" "F.Mask" "F.Paste")
			(net 1 "GND")
			(pinfunction "GND")
			(pintype "passive")
			(solder_mask_margin 0.075)
		)
		(pad "A9" smd circle
			(at -4.5 -12.5 90)
			(size 0.5 0.5)
			(layers "F.Cu" "F.Mask" "F.Paste")
			(net 406 "/Debug FTDI + VNA/AUX.TDO")
			(pinfunction "IO_L10N_AD2N_86")
			(pintype "bidirectional")
			(die_length 19.481)
			(solder_mask_margin 0.075)
		)
		(pad "A10" smd circle
			(at -3.5 -12.5 90)
			(size 0.5 0.5)
			(layers "F.Cu" "F.Mask" "F.Paste")
			(net 98 "PCIE.PWRGD")
			(pinfunction "IO_L11N_AD1N_86")
			(pintype "bidirectional")
			(die_length 18.317)
			(solder_mask_margin 0.075)
		)
		(pad "A11" smd circle
			(at -2.5 -12.5 90)
			(size 0.5 0.5)
			(layers "F.Cu" "F.Mask" "F.Paste")
			(net 1 "GND")
			(pinfunction "GND")
			(pintype "passive")
			(solder_mask_margin 0.075)
		)
		(pad "A12" smd circle
			(at -1.5 -12.5 90)
			(size 0.5 0.5)
			(layers "F.Cu" "F.Mask" "F.Paste")
			(net 762 "INT_CB")
			(pinfunction "IO_L11N_AD9N_87")
			(pintype "bidirectional")
			(die_length 15.339)
			(solder_mask_margin 0.075)
		)
		(pad "A13" smd circle
			(at -0.5 -12.5 90)
			(size 0.5 0.5)
			(layers "F.Cu" "F.Mask" "F.Paste")
			(net 531 "~{SI_5319_RST}")
			(pinfunction "IO_L11P_AD9P_87")
			(pintype "bidirectional")
			(die_length 14.63)
			(solder_mask_margin 0.075)
		)
		(pad "A14" smd circle
			(at 0.5 -12.5 90)
			(size 0.5 0.5)
			(layers "F.Cu" "F.Mask" "F.Paste")
			(net 767 "LOL")
			(pinfunction "IO_L12N_AD8N_87")
			(pintype "bidirectional")
			(die_length 13.531)
			(solder_mask_margin 0.075)
		)
		(pad "A15" smd circle
			(at 1.5 -12.5 90)
			(size 0.5 0.5)
			(layers "F.Cu" "F.Mask" "F.Paste")
			(net 396 "/Ethernet/ETH.RXD3")
			(pinfunction "IO_L17N_T2U_N9_AD10N_67")
			(pintype "bidirectional")
			(die_length 17.775)
			(solder_mask_margin 0.075)
		)
		(pad "A16" smd circle
			(at 2.5 -12.5 90)
			(size 0.5 0.5)
			(layers "F.Cu" "F.Mask" "F.Paste")
			(net 1 "GND")
			(pinfunction "GND")
			(pintype "passive")
			(solder_mask_margin 0.075)
		)
		(pad "A17" smd circle
			(at 3.5 -12.5 90)
			(size 0.5 0.5)
			(layers "F.Cu" "F.Mask" "F.Paste")
			(net 438 "/Ethernet/ETH.TXD3")
			(pinfunction "IO_L16P_T2U_N6_QBC_AD3P_67")
			(pintype "bidirectional")
			(die_length 17.349)
			(solder_mask_margin 0.075)
		)
		(pad "A18" smd circle
			(at 4.5 -12.5 90)
			(size 0.5 0.5)
			(layers "F.Cu" "F.Mask" "F.Paste")
			(net 440 "/Ethernet/ETH.TXD1")
			(pinfunction "IO_L16N_T2U_N7_QBC_AD3N_67")
			(pintype "bidirectional")
			(die_length 17.459)
			(solder_mask_margin 0.075)
		)
		(pad "A19" smd circle
			(at 5.5 -12.5 90)
			(size 0.5 0.5)
			(layers "F.Cu" "F.Mask" "F.Paste")
			(net 393 "/Ethernet/ETH.RXD0")
			(pinfunction "IO_L18P_T2U_N10_AD2P_67")
			(pintype "bidirectional")
			(die_length 15.262)
			(solder_mask_margin 0.075)
		)
		(pad "A20" smd circle
			(at 6.5 -12.5 90)
			(size 0.5 0.5)
			(layers "F.Cu" "F.Mask" "F.Paste")
			(net 439 "/Ethernet/ETH.TXD2")
			(pinfunction "IO_L18N_T2U_N11_AD2N_67")
			(pintype "bidirectional")
			(die_length 15.054)
			(solder_mask_margin 0.075)
		)
		(pad "A21" smd circle
			(at 7.5 -12.5 90)
			(size 0.5 0.5)
			(layers "F.Cu" "F.Mask" "F.Paste")
			(net 1 "GND")
			(pinfunction "GND")
			(pintype "passive")
			(solder_mask_margin 0.075)
		)
		(pad "A22" smd circle
			(at 8.5 -12.5 90)
			(size 0.5 0.5)
			(layers "F.Cu" "F.Mask" "F.Paste")
			(net 665 "unconnected-(U34E-IO_L19P_T3L_N0_DBC_AD9P_67-PadA22)")
			(pinfunction "IO_L19P_T3L_N0_DBC_AD9P_67")
			(pintype "bidirectional+no_connect")
			(die_length 14.598)
			(solder_mask_margin 0.075)
		)
		(pad "A23" smd circle
			(at 9.5 -12.5 90)
			(size 0.5 0.5)
			(layers "F.Cu" "F.Mask" "F.Paste")
			(net 469 "unconnected-(U34E-IO_L19N_T3L_N1_DBC_AD9N_67-PadA23)")
			(pinfunction "IO_L19N_T3L_N1_DBC_AD9N_67")
			(pintype "bidirectional+no_connect")
			(die_length 14.59)
			(solder_mask_margin 0.075)
		)
		(pad "A24" smd circle
			(at 10.5 -12.5 90)
			(size 0.5 0.5)
			(layers "F.Cu" "F.Mask" "F.Paste")
			(net 400 "/Ethernet/ETH.MDIO")
			(pinfunction "IO_L23P_T3U_N8_67")
			(pintype "bidirectional")
			(die_length 15.06)
			(solder_mask_margin 0.075)
		)
		(pad "A25" smd circle
			(at 11.5 -12.5 90)
			(size 0.5 0.5)
			(layers "F.Cu" "F.Mask" "F.Paste")
			(net 437 "/Ethernet/ETH.~{INT}")
			(pinfunction "IO_L23N_T3U_N9_67")
			(pintype "bidirectional")
			(die_length 15.012)
			(solder_mask_margin 0.075)
		)
		(pad "A26" smd circle
			(at 12.5 -12.5 90)
			(size 0.5 0.5)
			(layers "F.Cu" "F.Mask" "F.Paste")
			(net 1 "GND")
			(pinfunction "GND")
			(pintype "passive")
			(solder_mask_margin 0.075)
		)
		(pad "AA1" smd circle
			(at -12.5 7.5 90)
			(size 0.5 0.5)
			(layers "F.Cu" "F.Mask" "F.Paste")
			(net 1 "GND")
			(pinfunction "GND")
			(pintype "passive")
			(solder_mask_margin 0.075)
		)
		(pad "AA2" smd circle
			(at -11.5 7.5 90)
			(size 0.5 0.5)
			(layers "F.Cu" "F.Mask" "F.Paste")
			(net 1 "GND")
			(pinfunction "GND")
			(pintype "passive")
			(solder_mask_margin 0.075)
		)
		(pad "AA3" smd circle
			(at -10.5 7.5 90)
			(size 0.5 0.5)
			(layers "F.Cu" "F.Mask" "F.Paste")
			(net 1 "GND")
			(pinfunction "GND")
			(pintype "passive")
			(solder_mask_margin 0.075)
		)
		(pad "AA4" smd circle
			(at -9.5 7.5 90)
			(size 0.5 0.5)
			(layers "F.Cu" "F.Mask" "F.Paste")
			(net 24 "/FPGA MGT Interface/GTY_225_TX0_N")
			(pinfunction "MGTYTXN0_225")
			(pintype "output")
			(die_length 9.827)
			(solder_mask_margin 0.075)
		)
		(pad "AA5" smd circle
			(at -8.5 7.5 90)
			(size 0.5 0.5)
			(layers "F.Cu" "F.Mask" "F.Paste")
			(net 16 "/FPGA MGT Interface/GTY_225_TX0_P")
			(pinfunction "MGTYTXP0_225")
			(pintype "output")
			(die_length 9.852)
			(solder_mask_margin 0.075)
		)
		(pad "AA6" smd circle
			(at -7.5 7.5 90)
			(size 0.5 0.5)
			(layers "F.Cu" "F.Mask" "F.Paste")
			(net 1 "GND")
			(pinfunction "GND")
			(pintype "passive")
			(solder_mask_margin 0.075)
		)
		(pad "AA7" smd circle
			(at -6.5 7.5 90)
			(size 0.5 0.5)
			(layers "F.Cu" "F.Mask" "F.Paste")
			(net 820 "+0V9_MGTAVCC")
			(pinfunction "MGTAVCC_R")
			(pintype "power_in")
			(solder_mask_margin 0.075)
		)
		(pad "AA8" smd circle
			(at -5.5 7.5 90)
			(size 0.5 0.5)
			(layers "F.Cu" "F.Mask" "F.Paste")
			(net 1 "GND")
			(pinfunction "GND")
			(pintype "passive")
			(solder_mask_margin 0.075)
		)
		(pad "AA9" smd circle
			(at -4.5 7.5 90)
			(size 0.5 0.5)
			(layers "F.Cu" "F.Mask" "F.Paste")
			(net 1 "GND")
			(pinfunction "M1_0")
			(pintype "input")
			(die_length 14.72)
			(solder_mask_margin 0.075)
		)
		(pad "AA10" smd circle
			(at -3.5 7.5 90)
			(size 0.5 0.5)
			(layers "F.Cu" "F.Mask" "F.Paste")
			(net 356 "/FPGA Config/MODE0")
			(pinfunction "M0_0")
			(pintype "input")
			(die_length 14.957)
			(solder_mask_margin 0.075)
		)
		(pad "AA11" smd circle
			(at -2.5 7.5 90)
			(size 0.5 0.5)
			(layers "F.Cu" "F.Mask" "F.Paste")
			(net 797 "+1V8")
			(pinfunction "VCCO_0")
			(pintype "power_in")
			(solder_mask_margin 0.075)
		)
		(pad "AA12" smd circle
			(at -1.5 7.5 90)
			(size 0.5 0.5)
			(layers "F.Cu" "F.Mask" "F.Paste")
			(net 350 "/FPGA Config/FLASH.~{CS}")
			(pinfunction "RDWR_FCS_B_0")
			(pintype "bidirectional")
			(die_length 15.712)
			(solder_mask_margin 0.075)
		)
		(pad "AA13" smd circle
			(at -0.5 7.5 90)
			(size 0.5 0.5)
			(layers "F.Cu" "F.Mask" "F.Paste")
			(net 471 "unconnected-(U34F-IO_L11N_AD1N_84-PadAA13)")
			(pinfunction "IO_L11N_AD1N_84")
			(pintype "bidirectional+no_connect")
			(die_length 13.282)
			(solder_mask_margin 0.075)
		)
		(pad "AA14" smd circle
			(at 0.5 7.5 90)
			(size 0.5 0.5)
			(layers "F.Cu" "F.Mask" "F.Paste")
			(net 206 "FAN_PWM")
			(pinfunction "IO_L8P_HDGC_AD4P_84")
			(pintype "bidirectional")
			(die_length 12.153)
			(solder_mask_margin 0.075)
		)
		(pad "AA15" smd circle
			(at 1.5 7.5 90)
			(size 0.5 0.5)
			(layers "F.Cu" "F.Mask" "F.Paste")
			(net 184 "FPGA_POWER_CYCLE")
			(pinfunction "IO_L7N_HDGC_AD5N_84")
			(pintype "bidirectional")
			(die_length 12.163)
			(solder_mask_margin 0.075)
		)
		(pad "AA16" smd circle
			(at 2.5 7.5 90)
			(size 0.5 0.5)
			(layers "F.Cu" "F.Mask" "F.Paste")
			(net 1 "GND")
			(pinfunction "GND")
			(pintype "passive")
			(solder_mask_margin 0.075)
		)
		(pad "AA17" smd circle
			(at 3.5 7.5 90)
			(size 0.5 0.5)
			(layers "F.Cu" "F.Mask" "F.Paste")
			(net 134 "/DDR5 RDIMM/A.DQ6")
			(pinfunction "IO_L23N_T3U_N9_64")
			(pintype "bidirectional")
			(die_length 13.433)
			(solder_mask_margin 0.075)
		)
		(pad "AA18" smd circle
			(at 4.5 7.5 90)
			(size 0.5 0.5)
			(layers "F.Cu" "F.Mask" "F.Paste")
			(net 53 "/DDR5 RDIMM/A.DQ4")
			(pinfunction "IO_L24N_T3U_N11_64")
			(pintype "bidirectional")
			(die_length 14.564)
			(solder_mask_margin 0.075)
		)
		(pad "AA19" smd circle
			(at 5.5 7.5 90)
			(size 0.5 0.5)
			(layers "F.Cu" "F.Mask" "F.Paste")
			(net 51 "/DDR5 RDIMM/A.DQ0")
			(pinfunction "IO_L20P_T3L_N2_AD1P_64")
			(pintype "bidirectional")
			(die_length 12.184)
			(solder_mask_margin 0.075)
		)
		(pad "AA20" smd circle
			(at 6.5 7.5 90)
			(size 0.5 0.5)
			(layers "F.Cu" "F.Mask" "F.Paste")
			(net 52 "/DDR5 RDIMM/A.DQ1")
			(pinfunction "IO_L21P_T3L_N4_AD8P_64")
			(pintype "bidirectional")
			(die_length 14.796)
			(solder_mask_margin 0.075)
		)
		(pad "AA21" smd circle
			(at 7.5 7.5 90)
			(size 0.5 0.5)
			(layers "F.Cu" "F.Mask" "F.Paste")
			(net 687 "VDDQ")
			(pinfunction "VCCO_64")
			(pintype "power_in")
			(solder_mask_margin 0.075)
		)
		(pad "AA22" smd circle
			(at 8.5 7.5 90)
			(size 0.5 0.5)
			(layers "F.Cu" "F.Mask" "F.Paste")
			(net 209 "/DDR5 RDIMM/A.DQS7_P")
			(pinfunction "IO_L10P_T1U_N6_QBC_AD4P_64")
			(pintype "bidirectional")
			(die_length 13.153)
			(solder_mask_margin 0.075)
		)
		(pad "AA23" smd circle
			(at 9.5 7.5 90)
			(size 0.5 0.5)
			(layers "F.Cu" "F.Mask" "F.Paste")
			(net 72 "/DDR5 RDIMM/CTRL.~{ALERT}")
			(pinfunction "IO_T1U_N12_SMBALERT_65")
			(pintype "bidirectional")
			(die_length 13.037)
			(solder_mask_margin 0.075)
		)
		(pad "AA24" smd circle
			(at 10.5 7.5 90)
			(size 0.5 0.5)
			(layers "F.Cu" "F.Mask" "F.Paste")
			(net 75 "/DDR5 RDIMM/A.CA2")
			(pinfunction "IO_L9P_T1L_N4_AD12P_A14_D30_65")
			(pintype "bidirectional")
			(die_length 14.273)
			(solder_mask_margin 0.075)
		)
		(pad "AA25" smd circle
			(at 11.5 7.5 90)
			(size 0.5 0.5)
			(layers "F.Cu" "F.Mask" "F.Paste")
			(net 193 "/DDR5 RDIMM/A.CA3")
			(pinfunction "IO_L9N_T1L_N5_AD12N_A15_D31_65")
			(pintype "bidirectional")
			(die_length 14.349)
			(solder_mask_margin 0.075)
		)
		(pad "AA26" smd circle
			(at 12.5 7.5 90)
			(size 0.5 0.5)
			(layers "F.Cu" "F.Mask" "F.Paste")
			(net 1 "GND")
			(pinfunction "GND")
			(pintype "passive")
			(solder_mask_margin 0.075)
		)
		(pad "AB1" smd circle
			(at -12.5 8.5 90)
			(size 0.5 0.5)
			(layers "F.Cu" "F.Mask" "F.Paste")
			(net 584 "/FPGA MGT Interface/PCIE.RXD4_N")
			(pinfunction "MGTYRXN3_224")
			(pintype "input")
			(die_length 13.412)
			(solder_mask_margin 0.075)
		)
		(pad "AB2" smd circle
			(at -11.5 8.5 90)
			(size 0.5 0.5)
			(layers "F.Cu" "F.Mask" "F.Paste")
			(net 583 "/FPGA MGT Interface/PCIE.RXD4_P")
			(pinfunction "MGTYRXP3_224")
			(pintype "input")
			(die_length 13.41)
			(solder_mask_margin 0.075)
		)
		(pad "AB3" smd circle
			(at -10.5 8.5 90)
			(size 0.5 0.5)
			(layers "F.Cu" "F.Mask" "F.Paste")
			(net 1 "GND")
			(pinfunction "GND")
			(pintype "passive")
			(solder_mask_margin 0.075)
		)
		(pad "AB4" smd circle
			(at -9.5 8.5 90)
			(size 0.5 0.5)
			(layers "F.Cu" "F.Mask" "F.Paste")
			(net 1 "GND")
			(pinfunction "GND")
			(pintype "passive")
			(solder_mask_margin 0.075)
		)
		(pad "AB5" smd circle
			(at -8.5 8.5 90)
			(size 0.5 0.5)
			(layers "F.Cu" "F.Mask" "F.Paste")
			(net 172 "+1V2_MGTAVTT")
			(pinfunction "MGTAVTT_R")
			(pintype "passive")
			(solder_mask_margin 0.075)
		)
		(pad "AB6" smd circle
			(at -7.5 8.5 90)
			(size 0.5 0.5)
			(layers "F.Cu" "F.Mask" "F.Paste")
			(net 14 "/FPGA MGT Interface/GTR_REFCLK0_N")
			(pinfunction "MGTREFCLK0N_224")
			(pintype "input")
			(die_length 9.71)
			(solder_mask_margin 0.075)
		)
		(pad "AB7" smd circle
			(at -6.5 8.5 90)
			(size 0.5 0.5)
			(layers "F.Cu" "F.Mask" "F.Paste")
			(net 12 "/FPGA MGT Interface/GTR_REFCLK0_P")
			(pinfunction "MGTREFCLK0P_224")
			(pintype "input")
			(die_length 9.721)
			(solder_mask_margin 0.075)
		)
		(pad "AB8" smd circle
			(at -5.5 8.5 90)
			(size 0.5 0.5)
			(layers "F.Cu" "F.Mask" "F.Paste")
			(net 1 "GND")
			(pinfunction "GND")
			(pintype "passive")
			(solder_mask_margin 0.075)
		)
		(pad "AB9" smd circle
			(at -4.5 8.5 90)
			(size 0.5 0.5)
			(layers "F.Cu" "F.Mask" "F.Paste")
			(net 357 "/FPGA Config/PROGRAM_B")
			(pinfunction "PROGRAM_B_0")
			(pintype "input")
			(die_length 15.843)
			(solder_mask_margin 0.075)
		)
		(pad "AB10" smd circle
			(at -3.5 8.5 90)
			(size 0.5 0.5)
			(layers "F.Cu" "F.Mask" "F.Paste")
			(net 238 "/Debug FTDI + VNA/JTAG.TMS")
			(pinfunction "TMS_0")
			(pintype "input")
			(die_length 14.392)
			(solder_mask_margin 0.075)
		)
		(pad "AB11" smd circle
			(at -2.5 8.5 90)
			(size 0.5 0.5)
			(layers "F.Cu" "F.Mask" "F.Paste")
			(net 340 "/FPGA Config/DONE")
			(pinfunction "DONE_0")
			(pintype "bidirectional")
			(die_length 16.256)
			(solder_mask_margin 0.075)
		)
		(pad "AB12" smd circle
			(at -1.5 8.5 90)
			(size 0.5 0.5)
			(layers "F.Cu" "F.Mask" "F.Paste")
			(net 244 "/Debug FTDI + VNA/JTAG.TDI")
			(pinfunction "TDI_0")
			(pintype "input")
			(die_length 15.226)
			(solder_mask_margin 0.075)
		)
		(pad "AB13" smd circle
			(at -0.5 8.5 90)
			(size 0.5 0.5)
			(layers "F.Cu" "F.Mask" "F.Paste")
			(net 1 "GND")
			(pinfunction "GND")
			(pintype "passive")
			(solder_mask_margin 0.075)
		)
		(pad "AB14" smd circle
			(at 0.5 8.5 90)
			(size 0.5 0.5)
			(layers "F.Cu" "F.Mask" "F.Paste")
			(net 478 "unconnected-(U34F-IO_L8N_HDGC_AD4N_84-PadAB14)")
			(pinfunction "IO_L8N_HDGC_AD4N_84")
			(pintype "bidirectional+no_connect")
			(die_length 12.152)
			(solder_mask_margin 0.075)
		)
		(pad "AB15" smd circle
			(at 1.5 8.5 90)
			(size 0.5 0.5)
			(layers "F.Cu" "F.Mask" "F.Paste")
			(net 479 "unconnected-(U34F-IO_L6P_HDGC_AD6P_84-PadAB15)")
			(pinfunction "IO_L6P_HDGC_AD6P_84")
			(pintype "bidirectional+no_connect")
			(die_length 12.373)
			(solder_mask_margin 0.075)
		)
		(pad "AB16" smd circle
			(at 2.5 8.5 90)
			(size 0.5 0.5)
			(layers "F.Cu" "F.Mask" "F.Paste")
			(net 812 "Heater_PWM")
			(pinfunction "IO_L6N_HDGC_AD6N_84")
			(pintype "bidirectional")
			(die_length 12.413)
			(solder_mask_margin 0.075)
		)
		(pad "AB17" smd circle
			(at 3.5 8.5 90)
			(size 0.5 0.5)
			(layers "F.Cu" "F.Mask" "F.Paste")
			(net 178 "/DDR5 RDIMM/A.DQS5_P")
			(pinfunction "IO_L22P_T3U_N6_DBC_AD0P_64")
			(pintype "bidirectional")
			(die_length 15.653)
			(solder_mask_margin 0.075)
		)
		(pad "AB18" smd circle
			(at 4.5 8.5 90)
			(size 0.5 0.5)
			(layers "F.Cu" "F.Mask" "F.Paste")
			(net 687 "VDDQ")
			(pinfunction "VCCO_64")
			(pintype "passive")
			(solder_mask_margin 0.075)
		)
		(pad "AB19" smd circle
			(at 5.5 8.5 90)
			(size 0.5 0.5)
			(layers "F.Cu" "F.Mask" "F.Paste")
			(net 130 "/DDR5 RDIMM/A.DQ2")
			(pinfunction "IO_L20N_T3L_N3_AD1N_64")
			(pintype "bidirectional")
			(die_length 12.739)
			(solder_mask_margin 0.075)
		)
		(pad "AB20" smd circle
			(at 6.5 8.5 90)
			(size 0.5 0.5)
			(layers "F.Cu" "F.Mask" "F.Paste")
			(net 131 "/DDR5 RDIMM/A.DQ3")
			(pinfunction "IO_L21N_T3L_N5_AD8N_64")
			(pintype "bidirectional")
			(die_length 15.087)
			(solder_mask_margin 0.075)
		)
		(pad "AB21" smd circle
			(at 7.5 8.5 90)
			(size 0.5 0.5)
			(layers "F.Cu" "F.Mask" "F.Paste")
			(net 149 "/DDR5 RDIMM/A.DQ22")
			(pinfunction "IO_L12P_T1U_N10_GC_64")
			(pintype "bidirectional")
			(die_length 13.162)
			(solder_mask_margin 0.075)
		)
		(pad "AB22" smd circle
			(at 8.5 8.5 90)
			(size 0.5 0.5)
			(layers "F.Cu" "F.Mask" "F.Paste")
			(net 208 "/DDR5 RDIMM/A.DQS7_N")
			(pinfunction "IO_L10N_T1U_N7_QBC_AD4N_64")
			(pintype "bidirectional")
			(die_length 13.098)
			(solder_mask_margin 0.075)
		)
		(pad "AB23" smd circle
			(at 9.5 8.5 90)
			(size 0.5 0.5)
			(layers "F.Cu" "F.Mask" "F.Paste")
			(net 1 "GND")
			(pinfunction "GND")
			(pintype "passive")
			(solder_mask_margin 0.075)
		)
		(pad "AB24" smd circle
			(at 10.5 8.5 90)
			(size 0.5 0.5)
			(layers "F.Cu" "F.Mask" "F.Paste")
			(net 166 "/DDR5 RDIMM/A.DQ31")
			(pinfunction "IO_L6P_T0U_N10_AD6P_64")
			(pintype "bidirectional")
			(die_length 12.857)
			(solder_mask_margin 0.075)
		)
		(pad "AB25" smd circle
			(at 11.5 8.5 90)
			(size 0.5 0.5)
			(layers "F.Cu" "F.Mask" "F.Paste")
			(net 63 "/DDR5 RDIMM/A.DQ24")
			(pinfunction "IO_L2P_T0L_N2_64")
			(pintype "bidirectional")
			(die_length 12.779)
			(solder_mask_margin 0.075)
		)
		(pad "AB26" smd circle
			(at 12.5 8.5 90)
			(size 0.5 0.5)
			(layers "F.Cu" "F.Mask" "F.Paste")
			(net 154 "/DDR5 RDIMM/A.DQ26")
			(pinfunction "IO_L2N_T0L_N3_64")
			(pintype "bidirectional")
			(die_length 13.643)
			(solder_mask_margin 0.075)
		)
		(pad "AC1" smd circle
			(at -12.5 9.5 90)
			(size 0.5 0.5)
			(layers "F.Cu" "F.Mask" "F.Paste")
			(net 1 "GND")
			(pinfunction "GND")
			(pintype "passive")
			(solder_mask_margin 0.075)
		)
		(pad "AC2" smd circle
			(at -11.5 9.5 90)
			(size 0.5 0.5)
			(layers "F.Cu" "F.Mask" "F.Paste")
			(net 1 "GND")
			(pinfunction "GND")
			(pintype "passive")
			(solder_mask_margin 0.075)
		)
		(pad "AC3" smd circle
			(at -10.5 9.5 90)
			(size 0.5 0.5)
			(layers "F.Cu" "F.Mask" "F.Paste")
			(net 1 "GND")
			(pinfunction "GND")
			(pintype "passive")
			(solder_mask_margin 0.075)
		)
		(pad "AC4" smd circle
			(at -9.5 9.5 90)
			(size 0.5 0.5)
			(layers "F.Cu" "F.Mask" "F.Paste")
			(net 568 "/FPGA MGT Interface/GTY_224_TX3_N")
			(pinfunction "MGTYTXN3_224")
			(pintype "output")
			(die_length 12.023)
			(solder_mask_margin 0.075)
		)
		(pad "AC5" smd circle
			(at -8.5 9.5 90)
			(size 0.5 0.5)
			(layers "F.Cu" "F.Mask" "F.Paste")
			(net 566 "/FPGA MGT Interface/GTY_224_TX3_P")
			(pinfunction "MGTYTXP3_224")
			(pintype "output")
			(die_length 11.995)
			(solder_mask_margin 0.075)
		)
		(pad "AC6" smd circle
			(at -7.5 9.5 90)
			(size 0.5 0.5)
			(layers "F.Cu" "F.Mask" "F.Paste")
			(net 1 "GND")
			(pinfunction "GND")
			(pintype "passive")
			(solder_mask_margin 0.075)
		)
		(pad "AC7" smd circle
			(at -6.5 9.5 90)
			(size 0.5 0.5)
			(layers "F.Cu" "F.Mask" "F.Paste")
			(net 820 "+0V9_MGTAVCC")
			(pinfunction "MGTAVCC_R")
			(pintype "passive")
			(solder_mask_margin 0.075)
		)
		(pad "AC8" smd circle
			(at -5.5 9.5 90)
			(size 0.5 0.5)
			(layers "F.Cu" "F.Mask" "F.Paste")
			(net 1 "GND")
			(pinfunction "GND")
			(pintype "passive")
			(solder_mask_margin 0.075)
		)
		(pad "AC9" smd circle
			(at -4.5 9.5 90)
			(size 0.5 0.5)
			(layers "F.Cu" "F.Mask" "F.Paste")
			(net 1 "GND")
			(pinfunction "GND")
			(pintype "passive")
			(solder_mask_margin 0.075)
		)
		(pad "AC10" smd circle
			(at -3.5 9.5 90)
			(size 0.5 0.5)
			(layers "F.Cu" "F.Mask" "F.Paste")
			(net 1 "GND")
			(pinfunction "GND")
			(pintype "passive")
			(solder_mask_margin 0.075)
		)
		(pad "AC11" smd circle
			(at -2.5 9.5 90)
			(size 0.5 0.5)
			(layers "F.Cu" "F.Mask" "F.Paste")
			(net 353 "/FPGA Config/FLASH.IO2")
			(pinfunction "D02_0")
			(pintype "bidirectional")
			(die_length 16.69)
			(solder_mask_margin 0.075)
		)
		(pad "AC12" smd circle
			(at -1.5 9.5 90)
			(size 0.5 0.5)
			(layers "F.Cu" "F.Mask" "F.Paste")
			(net 352 "/FPGA Config/FLASH.IO1")
			(pinfunction "D01_DIN_0")
			(pintype "bidirectional")
			(die_length 16.061)
			(solder_mask_margin 0.075)
		)
		(pad "AC13" smd circle
			(at -0.5 9.5 90)
			(size 0.5 0.5)
			(layers "F.Cu" "F.Mask" "F.Paste")
			(net 481 "unconnected-(U34F-IO_L5P_HDGC_AD7P_84-PadAC13)")
			(pinfunction "IO_L5P_HDGC_AD7P_84")
			(pintype "bidirectional+no_connect")
			(die_length 13.414)
			(solder_mask_margin 0.075)
		)
		(pad "AC14" smd circle
			(at 0.5 9.5 90)
			(size 0.5 0.5)
			(layers "F.Cu" "F.Mask" "F.Paste")
			(net 466 "unconnected-(U34F-IO_L5N_HDGC_AD7N_84-PadAC14)")
			(pinfunction "IO_L5N_HDGC_AD7N_84")
			(pintype "bidirectional+no_connect")
			(die_length 13.472)
			(solder_mask_margin 0.075)
		)
		(pad "AC15" smd circle
			(at 1.5 9.5 90)
			(size 0.5 0.5)
			(layers "F.Cu" "F.Mask" "F.Paste")
			(net 151 "+3V3")
			(pinfunction "VCCO_84")
			(pintype "power_in")
			(solder_mask_margin 0.075)
		)
		(pad "AC16" smd circle
			(at 2.5 9.5 90)
			(size 0.5 0.5)
			(layers "F.Cu" "F.Mask" "F.Paste")
			(net 483 "unconnected-(U34B-IO_T3U_N12_64-PadAC16)")
			(pinfunction "IO_T3U_N12_64")
			(pintype "bidirectional+no_connect")
			(die_length 16.232)
			(solder_mask_margin 0.075)
		)
		(pad "AC17" smd circle
			(at 3.5 9.5 90)
			(size 0.5 0.5)
			(layers "F.Cu" "F.Mask" "F.Paste")
			(net 177 "/DDR5 RDIMM/A.DQS5_N")
			(pinfunction "IO_L22N_T3U_N7_DBC_AD0N_64")
			(pintype "bidirectional")
			(die_length 15.676)
			(solder_mask_margin 0.075)
		)
		(pad "AC18" smd circle
			(at 4.5 9.5 90)
			(size 0.5 0.5)
			(layers "F.Cu" "F.Mask" "F.Paste")
			(net 182 "/DDR5 RDIMM/A.DQS6_P")
			(pinfunction "IO_L16P_T2U_N6_QBC_AD3P_64")
			(pintype "bidirectional")
			(die_length 15.141)
			(solder_mask_margin 0.075)
		)
		(pad "AC19" smd circle
			(at 5.5 9.5 90)
			(size 0.5 0.5)
			(layers "F.Cu" "F.Mask" "F.Paste")
			(net 136 "/DDR5 RDIMM/A.DQ10")
			(pinfunction "IO_L14P_T2L_N2_GC_64")
			(pintype "bidirectional")
			(die_length 14.095)
			(solder_mask_margin 0.075)
		)
		(pad "AC20" smd circle
			(at 6.5 9.5 90)
			(size 0.5 0.5)
			(layers "F.Cu" "F.Mask" "F.Paste")
			(net 1 "GND")
			(pinfunction "GND")
			(pintype "passive")
			(solder_mask_margin 0.075)
		)
		(pad "AC21" smd circle
			(at 7.5 9.5 90)
			(size 0.5 0.5)
			(layers "F.Cu" "F.Mask" "F.Paste")
			(net 153 "/DDR5 RDIMM/A.DQ23")
			(pinfunction "IO_L12N_T1U_N11_GC_64")
			(pintype "bidirectional")
			(die_length 13.25)
			(solder_mask_margin 0.075)
		)
		(pad "AC22" smd circle
			(at 8.5 9.5 90)
			(size 0.5 0.5)
			(layers "F.Cu" "F.Mask" "F.Paste")
			(net 145 "/DDR5 RDIMM/A.DQ18")
			(pinfunction "IO_L9P_T1L_N4_AD12P_64")
			(pintype "bidirectional")
			(die_length 12.927)
			(solder_mask_margin 0.075)
		)
		(pad "AC23" smd circle
			(at 9.5 9.5 90)
			(size 0.5 0.5)
			(layers "F.Cu" "F.Mask" "F.Paste")
			(net 146 "/DDR5 RDIMM/A.DQ19")
			(pinfunction "IO_L9N_T1L_N5_AD12N_64")
			(pintype "bidirectional")
			(die_length 13.489)
			(solder_mask_margin 0.075)
		)
		(pad "AC24" smd circle
			(at 10.5 9.5 90)
			(size 0.5 0.5)
			(layers "F.Cu" "F.Mask" "F.Paste")
			(net 66 "/DDR5 RDIMM/A.DQ29")
			(pinfunction "IO_L6N_T0U_N11_AD6N_64")
			(pintype "bidirectional")
			(die_length 13.512)
			(solder_mask_margin 0.075)
		)
		(pad "AC25" smd circle
			(at 11.5 9.5 90)
			(size 0.5 0.5)
			(layers "F.Cu" "F.Mask" "F.Paste")
			(net 1 "GND")
			(pinfunction "GND")
			(pintype "passive")
			(solder_mask_margin 0.075)
		)
		(pad "AC26" smd circle
			(at 12.5 9.5 90)
			(size 0.5 0.5)
			(layers "F.Cu" "F.Mask" "F.Paste")
			(net 216 "/DDR5 RDIMM/A.DQS8_P")
			(pinfunction "IO_L4P_T0U_N6_DBC_AD7P_64")
			(pintype "bidirectional")
			(die_length 15.88)
			(solder_mask_margin 0.075)
		)
		(pad "AD1" smd circle
			(at -12.5 10.5 90)
			(size 0.5 0.5)
			(layers "F.Cu" "F.Mask" "F.Paste")
			(net 586 "/FPGA MGT Interface/PCIE.RXD5_N")
			(pinfunction "MGTYRXN2_224")
			(pintype "input")
			(die_length 14.364)
			(solder_mask_margin 0.075)
		)
		(pad "AD2" smd circle
			(at -11.5 10.5 90)
			(size 0.5 0.5)
			(layers "F.Cu" "F.Mask" "F.Paste")
			(net 585 "/FPGA MGT Interface/PCIE.RXD5_P")
			(pinfunction "MGTYRXP2_224")
			(pintype "input")
			(die_length 14.346)
			(solder_mask_margin 0.075)
		)
		(pad "AD3" smd circle
			(at -10.5 10.5 90)
			(size 0.5 0.5)
			(layers "F.Cu" "F.Mask" "F.Paste")
			(net 1 "GND")
			(pinfunction "GND")
			(pintype "passive")
			(solder_mask_margin 0.075)
		)
		(pad "AD4" smd circle
			(at -9.5 10.5 90)
			(size 0.5 0.5)
			(layers "F.Cu" "F.Mask" "F.Paste")
			(net 1 "GND")
			(pinfunction "GND")
			(pintype "passive")
			(solder_mask_margin 0.075)
		)
		(pad "AD5" smd circle
			(at -8.5 10.5 90)
			(size 0.5 0.5)
			(layers "F.Cu" "F.Mask" "F.Paste")
			(net 1 "GND")
			(pinfunction "GND")
			(pintype "passive")
			(solder_mask_margin 0.075)
		)
		(pad "AD6" smd circle
			(at -7.5 10.5 90)
			(size 0.5 0.5)
			(layers "F.Cu" "F.Mask" "F.Paste")
			(net 470 "/FPGA MGT Interface/GTY_224_TX2_N")
			(pinfunction "MGTYTXN2_224")
			(pintype "output")
			(die_length 11.99)
			(solder_mask_margin 0.075)
		)
		(pad "AD7" smd circle
			(at -6.5 10.5 90)
			(size 0.5 0.5)
			(layers "F.Cu" "F.Mask" "F.Paste")
			(net 563 "/FPGA MGT Interface/GTY_224_TX2_P")
			(pinfunction "MGTYTXP2_224")
			(pintype "output")
			(die_length 12.01)
			(solder_mask_margin 0.075)
		)
		(pad "AD8" smd circle
			(at -5.5 10.5 90)
			(size 0.5 0.5)
			(layers "F.Cu" "F.Mask" "F.Paste")
			(net 172 "+1V2_MGTAVTT")
			(pinfunction "MGTAVTTRCAL_R")
			(pintype "input")
			(die_length 15.825)
			(solder_mask_margin 0.075)
		)
		(pad "AD9" smd circle
			(at -4.5 10.5 90)
			(size 0.5 0.5)
			(layers "F.Cu" "F.Mask" "F.Paste")
			(net 288 "Net-(U34L-MGTRREF_R)")
			(pinfunction "MGTRREF_R")
			(pintype "input")
			(die_length 15.768)
			(solder_mask_margin 0.075)
		)
		(pad "AD10" smd circle
			(at -3.5 10.5 90)
			(size 0.5 0.5)
			(layers "F.Cu" "F.Mask" "F.Paste")
			(net 1 "GND")
			(pinfunction "GND")
			(pintype "passive")
			(solder_mask_margin 0.075)
		)
		(pad "AD11" smd circle
			(at -2.5 10.5 90)
			(size 0.5 0.5)
			(layers "F.Cu" "F.Mask" "F.Paste")
			(net 351 "/FPGA Config/FLASH.IO0")
			(pinfunction "D00_MOSI_0")
			(pintype "bidirectional")
			(die_length 16.602)
			(solder_mask_margin 0.075)
		)
		(pad "AD12" smd circle
			(at -1.5 10.5 90)
			(size 0.5 0.5)
			(layers "F.Cu" "F.Mask" "F.Paste")
			(net 797 "+1V8")
			(pinfunction "VCCO_0")
			(pintype "passive")
			(solder_mask_margin 0.075)
		)
		(pad "AD13" smd circle
			(at -0.5 10.5 90)
			(size 0.5 0.5)
			(layers "F.Cu" "F.Mask" "F.Paste")
			(net 704 "~{DDR_PRESENCE}")
			(pinfunction "IO_L4P_AD8P_84")
			(pintype "bidirectional")
			(die_length 13.923)
			(solder_mask_margin 0.075)
		)
		(pad "AD14" smd circle
			(at 0.5 10.5 90)
			(size 0.5 0.5)
			(layers "F.Cu" "F.Mask" "F.Paste")
			(net 809 "VIN_MGMT_EN")
			(pinfunction "IO_L4N_AD8N_84")
			(pintype "bidirectional")
			(die_length 13.917)
			(solder_mask_margin 0.075)
		)
		(pad "AD15" smd circle
			(at 1.5 10.5 90)
			(size 0.5 0.5)
			(layers "F.Cu" "F.Mask" "F.Paste")
			(net 808 "VIN_BULK_EN")
			(pinfunction "IO_L3P_AD9P_84")
			(pintype "bidirectional")
			(die_length 12.603)
			(solder_mask_margin 0.075)
		)
		(pad "AD16" smd circle
			(at 2.5 10.5 90)
			(size 0.5 0.5)
			(layers "F.Cu" "F.Mask" "F.Paste")
			(net 58 "/DDR5 RDIMM/A.DQ13")
			(pinfunction "IO_L18P_T2U_N10_AD2P_64")
			(pintype "bidirectional")
			(die_length 17.061)
			(solder_mask_margin 0.075)
		)
		(pad "AD17" smd circle
			(at 3.5 10.5 90)
			(size 0.5 0.5)
			(layers "F.Cu" "F.Mask" "F.Paste")
			(net 1 "GND")
			(pinfunction "GND")
			(pintype "passive")
			(solder_mask_margin 0.075)
		)
		(pad "AD18" smd circle
			(at 4.5 10.5 90)
			(size 0.5 0.5)
			(layers "F.Cu" "F.Mask" "F.Paste")
			(net 181 "/DDR5 RDIMM/A.DQS6_N")
			(pinfunction "IO_L16N_T2U_N7_QBC_AD3N_64")
			(pintype "bidirectional")
			(die_length 15.07)
			(solder_mask_margin 0.075)
		)
		(pad "AD19" smd circle
			(at 5.5 10.5 90)
			(size 0.5 0.5)
			(layers "F.Cu" "F.Mask" "F.Paste")
			(net 140 "/DDR5 RDIMM/A.DQ11")
			(pinfunction "IO_L14N_T2L_N3_GC_64")
			(pintype "bidirectional")
			(die_length 14.076)
			(solder_mask_margin 0.075)
		)
		(pad "AD20" smd circle
			(at 6.5 10.5 90)
			(size 0.5 0.5)
			(layers "F.Cu" "F.Mask" "F.Paste")
			(net 102 "/DDR5 RDIMM/A.DQS1_P")
			(pinfunction "IO_L13P_T2L_N0_GC_QBC_64")
			(pintype "bidirectional")
			(die_length 15.279)
			(solder_mask_margin 0.075)
		)
		(pad "AD21" smd circle
			(at 7.5 10.5 90)
			(size 0.5 0.5)
			(layers "F.Cu" "F.Mask" "F.Paste")
			(net 61 "/DDR5 RDIMM/A.DQ20")
			(pinfunction "IO_L11P_T1U_N8_GC_64")
			(pintype "bidirectional")
			(die_length 14.797)
			(solder_mask_margin 0.075)
		)
		(pad "AD22" smd circle
			(at 8.5 10.5 90)
			(size 0.5 0.5)
			(layers "F.Cu" "F.Mask" "F.Paste")
			(net 687 "VDDQ")
			(pinfunction "VCCO_64")
			(pintype "passive")
			(solder_mask_margin 0.075)
		)
		(pad "AD23" smd circle
			(at 9.5 10.5 90)
			(size 0.5 0.5)
			(layers "F.Cu" "F.Mask" "F.Paste")
			(net 59 "/DDR5 RDIMM/A.DQ16")
			(pinfunction "IO_L8P_T1L_N2_AD5P_64")
			(pintype "bidirectional")
			(die_length 13.63)
			(solder_mask_margin 0.075)
		)
		(pad "AD24" smd circle
			(at 10.5 10.5 90)
			(size 0.5 0.5)
			(layers "F.Cu" "F.Mask" "F.Paste")
			(net 65 "/DDR5 RDIMM/A.DQ28")
			(pinfunction "IO_L5P_T0U_N8_AD14P_64")
			(pintype "bidirectional")
			(die_length 14.419)
			(solder_mask_margin 0.075)
		)
		(pad "AD25" smd circle
			(at 11.5 10.5 90)
			(size 0.5 0.5)
			(layers "F.Cu" "F.Mask" "F.Paste")
			(net 162 "/DDR5 RDIMM/A.DQ30")
			(pinfunction "IO_L5N_T0U_N9_AD14N_64")
			(pintype "bidirectional")
			(die_length 14.911)
			(solder_mask_margin 0.075)
		)
		(pad "AD26" smd circle
			(at 12.5 10.5 90)
			(size 0.5 0.5)
			(layers "F.Cu" "F.Mask" "F.Paste")
			(net 214 "/DDR5 RDIMM/A.DQS8_N")
			(pinfunction "IO_L4N_T0U_N7_DBC_AD7N_64")
			(pintype "bidirectional")
			(die_length 15.787)
			(solder_mask_margin 0.075)
		)
		(pad "AE1" smd circle
			(at -12.5 11.5 90)
			(size 0.5 0.5)
			(layers "F.Cu" "F.Mask" "F.Paste")
			(net 1 "GND")
			(pinfunction "GND")
			(pintype "passive")
			(solder_mask_margin 0.075)
		)
		(pad "AE2" smd circle
			(at -11.5 11.5 90)
			(size 0.5 0.5)
			(layers "F.Cu" "F.Mask" "F.Paste")
			(net 1 "GND")
			(pinfunction "GND")
			(pintype "passive")
			(solder_mask_margin 0.075)
		)
		(pad "AE3" smd circle
			(at -10.5 11.5 90)
			(size 0.5 0.5)
			(layers "F.Cu" "F.Mask" "F.Paste")
			(net 588 "/FPGA MGT Interface/PCIE.RXD6_N")
			(pinfunction "MGTYRXN1_224")
			(pintype "input")
			(die_length 13.961)
			(solder_mask_margin 0.075)
		)
		(pad "AE4" smd circle
			(at -9.5 11.5 90)
			(size 0.5 0.5)
			(layers "F.Cu" "F.Mask" "F.Paste")
			(net 587 "/FPGA MGT Interface/PCIE.RXD6_P")
			(pinfunction "MGTYRXP1_224")
			(pintype "input")
			(die_length 13.957)
			(solder_mask_margin 0.075)
		)
		(pad "AE5" smd circle
			(at -8.5 11.5 90)
			(size 0.5 0.5)
			(layers "F.Cu" "F.Mask" "F.Paste")
			(net 1 "GND")
			(pinfunction "GND")
			(pintype "passive")
			(solder_mask_margin 0.075)
		)
		(pad "AE6" smd circle
			(at -7.5 11.5 90)
			(size 0.5 0.5)
			(layers "F.Cu" "F.Mask" "F.Paste")
			(net 1 "GND")
			(pinfunction "GND")
			(pintype "passive")
			(solder_mask_margin 0.075)
		)
		(pad "AE7" smd circle
			(at -6.5 11.5 90)
			(size 0.5 0.5)
			(layers "F.Cu" "F.Mask" "F.Paste")
			(net 172 "+1V2_MGTAVTT")
			(pinfunction "MGTAVTT_R")
			(pintype "passive")
			(solder_mask_margin 0.075)
		)
		(pad "AE8" smd circle
			(at -5.5 11.5 90)
			(size 0.5 0.5)
			(layers "F.Cu" "F.Mask" "F.Paste")
			(net 562 "/FPGA MGT Interface/GTY_224_TX1_N")
			(pinfunction "MGTYTXN1_224")
			(pintype "output")
			(die_length 13.144)
			(solder_mask_margin 0.075)
		)
		(pad "AE9" smd circle
			(at -4.5 11.5 90)
			(size 0.5 0.5)
			(layers "F.Cu" "F.Mask" "F.Paste")
			(net 559 "/FPGA MGT Interface/GTY_224_TX1_P")
			(pinfunction "MGTYTXP1_224")
			(pintype "output")
			(die_length 13.169)
			(solder_mask_margin 0.075)
		)
		(pad "AE10" smd circle
			(at -3.5 11.5 90)
			(size 0.5 0.5)
			(layers "F.Cu" "F.Mask" "F.Paste")
			(net 1 "GND")
			(pinfunction "GND")
			(pintype "passive")
			(solder_mask_margin 0.075)
		)
		(pad "AE11" smd circle
			(at -2.5 11.5 90)
			(size 0.5 0.5)
			(layers "F.Cu" "F.Mask" "F.Paste")
			(net 354 "/FPGA Config/FLASH.IO3")
			(pinfunction "D03_0")
			(pintype "bidirectional")
			(die_length 17.943)
			(solder_mask_margin 0.075)
		)
		(pad "AE12" smd circle
			(at -1.5 11.5 90)
			(size 0.5 0.5)
			(layers "F.Cu" "F.Mask" "F.Paste")
			(net 239 "/Debug FTDI + VNA/JTAG.TCK")
			(pinfunction "TCK_0")
			(pintype "input")
			(die_length 17.51)
			(solder_mask_margin 0.075)
		)
		(pad "AE13" smd circle
			(at -0.5 11.5 90)
			(size 0.5 0.5)
			(layers "F.Cu" "F.Mask" "F.Paste")
			(net 180 "HOT_SWAP_GREEN")
			(pinfunction "IO_L2P_AD10P_84")
			(pintype "bidirectional")
			(die_length 16.056)
			(solder_mask_margin 0.075)
		)
		(pad "AE14" smd circle
			(at 0.5 11.5 90)
			(size 0.5 0.5)
			(layers "F.Cu" "F.Mask" "F.Paste")
			(net 1 "GND")
			(pinfunction "GND")
			(pintype "passive")
			(solder_mask_margin 0.075)
		)
		(pad "AE15" smd circle
			(at 1.5 11.5 90)
			(size 0.5 0.5)
			(layers "F.Cu" "F.Mask" "F.Paste")
			(net 626 "USER_IN")
			(pinfunction "IO_L3N_AD9N_84")
			(pintype "bidirectional")
			(die_length 12.961)
			(solder_mask_margin 0.075)
		)
		(pad "AE16" smd circle
			(at 2.5 11.5 90)
			(size 0.5 0.5)
			(layers "F.Cu" "F.Mask" "F.Paste")
			(net 57 "/DDR5 RDIMM/A.DQ12")
			(pinfunction "IO_L18N_T2U_N11_AD2N_64")
			(pintype "bidirectional")
			(die_length 17.823)
			(solder_mask_margin 0.075)
		)
		(pad "AE17" smd circle
			(at 3.5 11.5 90)
			(size 0.5 0.5)
			(layers "F.Cu" "F.Mask" "F.Paste")
			(net 144 "/DDR5 RDIMM/A.DQ15")
			(pinfunction "IO_L17P_T2U_N8_AD10P_64")
			(pintype "bidirectional")
			(die_length 16.857)
			(solder_mask_margin 0.075)
		)
		(pad "AE18" smd circle
			(at 4.5 11.5 90)
			(size 0.5 0.5)
			(layers "F.Cu" "F.Mask" "F.Paste")
			(net 487 "unconnected-(U34B-IO_T2U_N12_64-PadAE18)")
			(pinfunction "IO_T2U_N12_64")
			(pintype "bidirectional+no_connect")
			(die_length 15.893)
			(solder_mask_margin 0.075)
		)
		(pad "AE19" smd circle
			(at 5.5 11.5 90)
			(size 0.5 0.5)
			(layers "F.Cu" "F.Mask" "F.Paste")
			(net 1 "GND")
			(pinfunction "GND")
			(pintype "passive")
			(solder_mask_margin 0.075)
		)
		(pad "AE20" smd circle
			(at 6.5 11.5 90)
			(size 0.5 0.5)
			(layers "F.Cu" "F.Mask" "F.Paste")
			(net 104 "/DDR5 RDIMM/A.DQS1_N")
			(pinfunction "IO_L13N_T2L_N1_GC_QBC_64")
			(pintype "bidirectional")
			(die_length 15.203)
			(solder_mask_margin 0.075)
		)
		(pad "AE21" smd circle
			(at 7.5 11.5 90)
			(size 0.5 0.5)
			(layers "F.Cu" "F.Mask" "F.Paste")
			(net 62 "/DDR5 RDIMM/A.DQ21")
			(pinfunction "IO_L11N_T1U_N9_GC_64")
			(pintype "bidirectional")
			(die_length 14.796)
			(solder_mask_margin 0.075)
		)
		(pad "AE22" smd circle
			(at 8.5 11.5 90)
			(size 0.5 0.5)
			(layers "F.Cu" "F.Mask" "F.Paste")
			(net 108 "/DDR5 RDIMM/A.DQS2_P")
			(pinfunction "IO_L7P_T1L_N0_QBC_AD13P_64")
			(pintype "bidirectional")
			(die_length 17.07)
			(solder_mask_margin 0.075)
		)
		(pad "AE23" smd circle
			(at 9.5 11.5 90)
			(size 0.5 0.5)
			(layers "F.Cu" "F.Mask" "F.Paste")
			(net 60 "/DDR5 RDIMM/A.DQ17")
			(pinfunction "IO_L8N_T1L_N3_AD5N_64")
			(pintype "bidirectional")
			(die_length 14.312)
			(solder_mask_margin 0.075)
		)
		(pad "AE24" smd circle
			(at 10.5 11.5 90)
			(size 0.5 0.5)
			(layers "F.Cu" "F.Mask" "F.Paste")
			(net 1 "GND")
			(pinfunction "GND")
			(pintype "passive")
			(solder_mask_margin 0.075)
		)
		(pad "AE25" smd circle
			(at 11.5 11.5 90)
			(size 0.5 0.5)
			(layers "F.Cu" "F.Mask" "F.Paste")
			(net 114 "/DDR5 RDIMM/A.DQS3_P")
			(pinfunction "IO_L1P_T0L_N0_DBC_64")
			(pintype "bidirectional")
			(die_length 15.008)
			(solder_mask_margin 0.075)
		)
		(pad "AE26" smd circle
			(at 12.5 11.5 90)
			(size 0.5 0.5)
			(layers "F.Cu" "F.Mask" "F.Paste")
			(net 115 "/DDR5 RDIMM/A.DQS3_N")
			(pinfunction "IO_L1N_T0L_N1_DBC_64")
			(pintype "bidirectional")
			(die_length 15.074)
			(solder_mask_margin 0.075)
		)
		(pad "AF1" smd circle
			(at -12.5 12.5 90)
			(size 0.5 0.5)
			(layers "F.Cu" "F.Mask" "F.Paste")
			(net 590 "/FPGA MGT Interface/PCIE.RXD7_N")
			(pinfunction "MGTYRXN0_224")
			(pintype "input")
			(die_length 16.143)
			(solder_mask_margin 0.075)
		)
		(pad "AF2" smd circle
			(at -11.5 12.5 90)
			(size 0.5 0.5)
			(layers "F.Cu" "F.Mask" "F.Paste")
			(net 589 "/FPGA MGT Interface/PCIE.RXD7_P")
			(pinfunction "MGTYRXP0_224")
			(pintype "input")
			(die_length 16.128)
			(solder_mask_margin 0.075)
		)
		(pad "AF3" smd circle
			(at -10.5 12.5 90)
			(size 0.5 0.5)
			(layers "F.Cu" "F.Mask" "F.Paste")
			(net 1 "GND")
			(pinfunction "GND")
			(pintype "passive")
			(solder_mask_margin 0.075)
		)
		(pad "AF4" smd circle
			(at -9.5 12.5 90)
			(size 0.5 0.5)
			(layers "F.Cu" "F.Mask" "F.Paste")
			(net 1 "GND")
			(pinfunction "GND")
			(pintype "passive")
			(solder_mask_margin 0.075)
		)
		(pad "AF5" smd circle
			(at -8.5 12.5 90)
			(size 0.5 0.5)
			(layers "F.Cu" "F.Mask" "F.Paste")
			(net 1 "GND")
			(pinfunction "GND")
			(pintype "passive")
			(solder_mask_margin 0.075)
		)
		(pad "AF6" smd circle
			(at -7.5 12.5 90)
			(size 0.5 0.5)
			(layers "F.Cu" "F.Mask" "F.Paste")
			(net 558 "/FPGA MGT Interface/GTY_224_TX0_N")
			(pinfunction "MGTYTXN0_224")
			(pintype "output")
			(die_length 16.305)
			(solder_mask_margin 0.075)
		)
		(pad "AF7" smd circle
			(at -6.5 12.5 90)
			(size 0.5 0.5)
			(layers "F.Cu" "F.Mask" "F.Paste")
			(net 557 "/FPGA MGT Interface/GTY_224_TX0_P")
			(pinfunction "MGTYTXP0_224")
			(pintype "output")
			(die_length 16.298)
			(solder_mask_margin 0.075)
		)
		(pad "AF8" smd circle
			(at -5.5 12.5 90)
			(size 0.5 0.5)
			(layers "F.Cu" "F.Mask" "F.Paste")
			(net 1 "GND")
			(pinfunction "GND")
			(pintype "passive")
			(solder_mask_margin 0.075)
		)
		(pad "AF9" smd circle
			(at -4.5 12.5 90)
			(size 0.5 0.5)
			(layers "F.Cu" "F.Mask" "F.Paste")
			(net 1 "GND")
			(pinfunction "GND")
			(pintype "passive")
			(solder_mask_margin 0.075)
		)
		(pad "AF10" smd circle
			(at -3.5 12.5 90)
			(size 0.5 0.5)
			(layers "F.Cu" "F.Mask" "F.Paste")
			(net 1 "GND")
			(pinfunction "GND")
			(pintype "passive")
			(solder_mask_margin 0.075)
		)
		(pad "AF11" smd circle
			(at -2.5 12.5 90)
			(size 0.5 0.5)
			(layers "F.Cu" "F.Mask" "F.Paste")
			(net 1 "GND")
			(pinfunction "GND")
			(pintype "passive")
			(solder_mask_margin 0.075)
		)
		(pad "AF12" smd circle
			(at -1.5 12.5 90)
			(size 0.5 0.5)
			(layers "F.Cu" "F.Mask" "F.Paste")
			(net 773 "MODE2")
			(pinfunction "M2_0")
			(pintype "input")
			(die_length 20.09)
			(solder_mask_margin 0.075)
		)
		(pad "AF13" smd circle
			(at -0.5 12.5 90)
			(size 0.5 0.5)
			(layers "F.Cu" "F.Mask" "F.Paste")
			(net 69 "HOT_SWAP_BUTTON")
			(pinfunction "IO_L2N_AD10N_84")
			(pintype "bidirectional")
			(die_length 16.382)
			(solder_mask_margin 0.075)
		)
		(pad "AF14" smd circle
			(at 0.5 12.5 90)
			(size 0.5 0.5)
			(layers "F.Cu" "F.Mask" "F.Paste")
			(net 179 "HOT_SWAP_YELLOW")
			(pinfunction "IO_L1P_AD11P_84")
			(pintype "bidirectional")
			(die_length 14.637)
			(solder_mask_margin 0.075)
		)
		(pad "AF15" smd circle
			(at 1.5 12.5 90)
			(size 0.5 0.5)
			(layers "F.Cu" "F.Mask" "F.Paste")
			(net 702 "HOT_SWAP_RED")
			(pinfunction "IO_L1N_AD11N_84")
			(pintype "bidirectional")
			(die_length 14.515)
			(solder_mask_margin 0.075)
		)
		(pad "AF16" smd circle
			(at 2.5 12.5 90)
			(size 0.5 0.5)
			(layers "F.Cu" "F.Mask" "F.Paste")
			(net 1 "GND")
			(pinfunction "GND")
			(pintype "passive")
			(solder_mask_margin 0.075)
		)
		(pad "AF17" smd circle
			(at 3.5 12.5 90)
			(size 0.5 0.5)
			(layers "F.Cu" "F.Mask" "F.Paste")
			(net 143 "/DDR5 RDIMM/A.DQ14")
			(pinfunction "IO_L17N_T2U_N9_AD10N_64")
			(pintype "bidirectional")
			(die_length 17.295)
			(solder_mask_margin 0.075)
		)
		(pad "AF18" smd circle
			(at 4.5 12.5 90)
			(size 0.5 0.5)
			(layers "F.Cu" "F.Mask" "F.Paste")
			(net 55 "/DDR5 RDIMM/A.DQ8")
			(pinfunction "IO_L15P_T2L_N4_AD11P_64")
			(pintype "bidirectional")
			(die_length 16.158)
			(solder_mask_margin 0.075)
		)
		(pad "AF19" smd circle
			(at 5.5 12.5 90)
			(size 0.5 0.5)
			(layers "F.Cu" "F.Mask" "F.Paste")
			(net 56 "/DDR5 RDIMM/A.DQ9")
			(pinfunction "IO_L15N_T2L_N5_AD11N_64")
			(pintype "bidirectional")
			(die_length 16.079)
			(solder_mask_margin 0.075)
		)
		(pad "AF20" smd circle
			(at 6.5 12.5 90)
			(size 0.5 0.5)
			(layers "F.Cu" "F.Mask" "F.Paste")
			(net 491 "unconnected-(U34B-IO_T1U_N12_64-PadAF20)")
			(pinfunction "IO_T1U_N12_64")
			(pintype "bidirectional+no_connect")
			(die_length 14.747)
			(solder_mask_margin 0.075)
		)
		(pad "AF21" smd circle
			(at 7.5 12.5 90)
			(size 0.5 0.5)
			(layers "F.Cu" "F.Mask" "F.Paste")
			(net 1 "GND")
			(pinfunction "GND")
			(pintype "passive")
			(solder_mask_margin 0.075)
		)
		(pad "AF22" smd circle
			(at 8.5 12.5 90)
			(size 0.5 0.5)
			(layers "F.Cu" "F.Mask" "F.Paste")
			(net 109 "/DDR5 RDIMM/A.DQS2_N")
			(pinfunction "IO_L7N_T1L_N1_QBC_AD13N_64")
			(pintype "bidirectional")
			(die_length 17.004)
			(solder_mask_margin 0.075)
		)
		(pad "AF23" smd circle
			(at 9.5 12.5 90)
			(size 0.5 0.5)
			(layers "F.Cu" "F.Mask" "F.Paste")
			(net 547 "/FPGA banks HP/VRP_64")
			(pinfunction "IO_T0U_N12_VRP_64")
			(pintype "bidirectional")
			(die_length 16.259)
			(solder_mask_margin 0.075)
		)
		(pad "AF24" smd circle
			(at 10.5 12.5 90)
			(size 0.5 0.5)
			(layers "F.Cu" "F.Mask" "F.Paste")
			(net 64 "/DDR5 RDIMM/A.DQ25")
			(pinfunction "IO_L3P_T0L_N4_AD15P_64")
			(pintype "bidirectional")
			(die_length 16.413)
			(solder_mask_margin 0.075)
		)
		(pad "AF25" smd circle
			(at 11.5 12.5 90)
			(size 0.5 0.5)
			(layers "F.Cu" "F.Mask" "F.Paste")
			(net 155 "/DDR5 RDIMM/A.DQ27")
			(pinfunction "IO_L3N_T0L_N5_AD15N_64")
			(pintype "bidirectional")
			(die_length 16.361)
			(solder_mask_margin 0.075)
		)
		(pad "AF26" smd circle
			(at 12.5 12.5 90)
			(size 0.5 0.5)
			(layers "F.Cu" "F.Mask" "F.Paste")
			(net 1 "GND")
			(pinfunction "GND")
			(pintype "passive")
			(solder_mask_margin 0.075)
		)
		(pad "B1" smd circle
			(at -12.5 -11.5 90)
			(size 0.5 0.5)
			(layers "F.Cu" "F.Mask" "F.Paste")
			(net 492 "unconnected-(U34L-NC-PadB1)")
			(pinfunction "NC")
			(pintype "no_connect")
			(solder_mask_margin 0.075)
		)
		(pad "B2" smd circle
			(at -11.5 -11.5 90)
			(size 0.5 0.5)
			(layers "F.Cu" "F.Mask" "F.Paste")
			(net 493 "unconnected-(U34L-NC-PadB2)")
			(pinfunction "NC")
			(pintype "no_connect")
			(solder_mask_margin 0.075)
		)
		(pad "B3" smd circle
			(at -10.5 -11.5 90)
			(size 0.5 0.5)
			(layers "F.Cu" "F.Mask" "F.Paste")
			(net 1 "GND")
			(pinfunction "GND")
			(pintype "passive")
			(solder_mask_margin 0.075)
		)
		(pad "B4" smd circle
			(at -9.5 -11.5 90)
			(size 0.5 0.5)
			(layers "F.Cu" "F.Mask" "F.Paste")
			(net 1 "GND")
			(pinfunction "GND")
			(pintype "passive")
			(solder_mask_margin 0.075)
		)
		(pad "B5" smd circle
			(at -8.5 -11.5 90)
			(size 0.5 0.5)
			(layers "F.Cu" "F.Mask" "F.Paste")
			(net 1 "GND")
			(pinfunction "GND")
			(pintype "passive")
			(solder_mask_margin 0.075)
		)
		(pad "B6" smd circle
			(at -7.5 -11.5 90)
			(size 0.5 0.5)
			(layers "F.Cu" "F.Mask" "F.Paste")
			(net 494 "unconnected-(U34L-NC-PadB6)")
			(pinfunction "NC")
			(pintype "no_connect")
			(solder_mask_margin 0.075)
		)
		(pad "B7" smd circle
			(at -6.5 -11.5 90)
			(size 0.5 0.5)
			(layers "F.Cu" "F.Mask" "F.Paste")
			(net 495 "unconnected-(U34L-NC-PadB7)")
			(pinfunction "NC")
			(pintype "no_connect")
			(solder_mask_margin 0.075)
		)
		(pad "B8" smd circle
			(at -5.5 -11.5 90)
			(size 0.5 0.5)
			(layers "F.Cu" "F.Mask" "F.Paste")
			(net 1 "GND")
			(pinfunction "GND")
			(pintype "passive")
			(solder_mask_margin 0.075)
		)
		(pad "B9" smd circle
			(at -4.5 -11.5 90)
			(size 0.5 0.5)
			(layers "F.Cu" "F.Mask" "F.Paste")
			(net 391 "/Debug FTDI + VNA/AUX.TDI")
			(pinfunction "IO_L10P_AD2P_86")
			(pintype "bidirectional")
			(die_length 18.904)
			(solder_mask_margin 0.075)
		)
		(pad "B10" smd circle
			(at -3.5 -11.5 90)
			(size 0.5 0.5)
			(layers "F.Cu" "F.Mask" "F.Paste")
			(net 497 "unconnected-(U34G-IO_L11P_AD1P_86-PadB10)")
			(pinfunction "IO_L11P_AD1P_86")
			(pintype "bidirectional+no_connect")
			(die_length 18.046)
			(solder_mask_margin 0.075)
		)
		(pad "B11" smd circle
			(at -2.5 -11.5 90)
			(size 0.5 0.5)
			(layers "F.Cu" "F.Mask" "F.Paste")
			(net 498 "unconnected-(U34G-IO_L12N_AD0N_86-PadB11)")
			(pinfunction "IO_L12N_AD0N_86")
			(pintype "bidirectional+no_connect")
			(die_length 16.738)
			(solder_mask_margin 0.075)
		)
		(pad "B12" smd circle
			(at -1.5 -11.5 90)
			(size 0.5 0.5)
			(layers "F.Cu" "F.Mask" "F.Paste")
			(net 500 "HDMI_IN_HPD")
			(pinfunction "IO_L10N_AD10N_87")
			(pintype "bidirectional")
			(die_length 14.992)
			(solder_mask_margin 0.075)
		)
		(pad "B13" smd circle
			(at -0.5 -11.5 90)
			(size 0.5 0.5)
			(layers "F.Cu" "F.Mask" "F.Paste")
			(net 1 "GND")
			(pinfunction "GND")
			(pintype "passive")
			(solder_mask_margin 0.075)
		)
		(pad "B14" smd circle
			(at 0.5 -11.5 90)
			(size 0.5 0.5)
			(layers "F.Cu" "F.Mask" "F.Paste")
			(net 772 "SD_SEL")
			(pinfunction "IO_L12P_AD8P_87")
			(pintype "bidirectional")
			(die_length 13.138)
			(solder_mask_margin 0.075)
		)
		(pad "B15" smd circle
			(at 1.5 -11.5 90)
			(size 0.5 0.5)
			(layers "F.Cu" "F.Mask" "F.Paste")
			(net 436 "/Ethernet/ETH.TXD0")
			(pinfunction "IO_L17P_T2U_N8_AD10P_67")
			(pintype "bidirectional")
			(die_length 17.648)
			(solder_mask_margin 0.075)
		)
		(pad "B16" smd circle
			(at 2.5 -11.5 90)
			(size 0.5 0.5)
			(layers "F.Cu" "F.Mask" "F.Paste")
			(net 666 "unconnected-(U34E-IO_T2U_N12_67-PadB16)")
			(pinfunction "IO_T2U_N12_67")
			(pintype "bidirectional+no_connect")
			(die_length 16.783)
			(solder_mask_margin 0.075)
		)
		(pad "B17" smd circle
			(at 3.5 -11.5 90)
			(size 0.5 0.5)
			(layers "F.Cu" "F.Mask" "F.Paste")
			(net 394 "/Ethernet/ETH.RXD1")
			(pinfunction "IO_L15N_T2L_N5_AD11N_67")
			(pintype "bidirectional")
			(die_length 15.811)
			(solder_mask_margin 0.075)
		)
		(pad "B18" smd circle
			(at 4.5 -11.5 90)
			(size 0.5 0.5)
			(layers "F.Cu" "F.Mask" "F.Paste")
			(net 1 "GND")
			(pinfunction "GND")
			(pintype "passive")
			(solder_mask_margin 0.075)
		)
		(pad "B19" smd circle
			(at 5.5 -11.5 90)
			(size 0.5 0.5)
			(layers "F.Cu" "F.Mask" "F.Paste")
			(net 543 "/FPGA banks HP/GCLK_100_LVDS+")
			(pinfunction "IO_L14P_T2L_N2_GC_67")
			(pintype "bidirectional")
			(die_length 14.761)
			(solder_mask_margin 0.075)
		)
		(pad "B20" smd circle
			(at 6.5 -11.5 90)
			(size 0.5 0.5)
			(layers "F.Cu" "F.Mask" "F.Paste")
			(net 544 "/FPGA banks HP/GCLK_100_LVDS-")
			(pinfunction "IO_L14N_T2L_N3_GC_67")
			(pintype "bidirectional")
			(die_length 14.716)
			(solder_mask_margin 0.075)
		)
		(pad "B21" smd circle
			(at 7.5 -11.5 90)
			(size 0.5 0.5)
			(layers "F.Cu" "F.Mask" "F.Paste")
			(net 398 "/Ethernet/ETH.RXC")
			(pinfunction "IO_L22N_T3U_N7_DBC_AD0N_67")
			(pintype "bidirectional")
			(die_length 13.059)
			(solder_mask_margin 0.075)
		)
		(pad "B22" smd circle
			(at 8.5 -11.5 90)
			(size 0.5 0.5)
			(layers "F.Cu" "F.Mask" "F.Paste")
			(net 501 "unconnected-(U34E-IO_L24N_T3U_N11_67-PadB22)")
			(pinfunction "IO_L24N_T3U_N11_67")
			(pintype "bidirectional+no_connect")
			(die_length 12.209)
			(solder_mask_margin 0.075)
		)
		(pad "B23" smd circle
			(at 9.5 -11.5 90)
			(size 0.5 0.5)
			(layers "F.Cu" "F.Mask" "F.Paste")
			(net 1 "GND")
			(pinfunction "GND")
			(pintype "passive")
			(solder_mask_margin 0.075)
		)
		(pad "B24" smd circle
			(at 10.5 -11.5 90)
			(size 0.5 0.5)
			(layers "F.Cu" "F.Mask" "F.Paste")
			(net 399 "/Ethernet/ETH.REF_CLK")
			(pinfunction "IO_L21N_T3L_N5_AD8N_67")
			(pintype "bidirectional")
			(die_length 13.648)
			(solder_mask_margin 0.075)
		)
		(pad "B25" smd circle
			(at 11.5 -11.5 90)
			(size 0.5 0.5)
			(layers "F.Cu" "F.Mask" "F.Paste")
			(net 129 "/DDR5 RDIMM/B.DQ29")
			(pinfunction "IO_L24P_T3U_N10_66")
			(pintype "bidirectional")
			(die_length 17.31)
			(solder_mask_margin 0.075)
		)
		(pad "B26" smd circle
			(at 12.5 -11.5 90)
			(size 0.5 0.5)
			(layers "F.Cu" "F.Mask" "F.Paste")
			(net 128 "/DDR5 RDIMM/B.DQ28")
			(pinfunction "IO_L24N_T3U_N11_66")
			(pintype "bidirectional")
			(die_length 17.349)
			(solder_mask_margin 0.075)
		)
		(pad "C1" smd circle
			(at -12.5 -10.5 90)
			(size 0.5 0.5)
			(layers "F.Cu" "F.Mask" "F.Paste")
			(net 1 "GND")
			(pinfunction "GND")
			(pintype "passive")
			(solder_mask_margin 0.075)
		)
		(pad "C2" smd circle
			(at -11.5 -10.5 90)
			(size 0.5 0.5)
			(layers "F.Cu" "F.Mask" "F.Paste")
			(net 1 "GND")
			(pinfunction "GND")
			(pintype "passive")
			(solder_mask_margin 0.075)
		)
		(pad "C3" smd circle
			(at -10.5 -10.5 90)
			(size 0.5 0.5)
			(layers "F.Cu" "F.Mask" "F.Paste")
			(net 502 "unconnected-(U34L-NC-PadC3)")
			(pinfunction "NC")
			(pintype "no_connect")
			(solder_mask_margin 0.075)
		)
		(pad "C4" smd circle
			(at -9.5 -10.5 90)
			(size 0.5 0.5)
			(layers "F.Cu" "F.Mask" "F.Paste")
			(net 503 "unconnected-(U34L-NC-PadC4)")
			(pinfunction "NC")
			(pintype "no_connect")
			(solder_mask_margin 0.075)
		)
		(pad "C5" smd circle
			(at -8.5 -10.5 90)
			(size 0.5 0.5)
			(layers "F.Cu" "F.Mask" "F.Paste")
			(net 1 "GND")
			(pinfunction "GND")
			(pintype "passive")
			(solder_mask_margin 0.075)
		)
		(pad "C6" smd circle
			(at -7.5 -10.5 90)
			(size 0.5 0.5)
			(layers "F.Cu" "F.Mask" "F.Paste")
			(net 1 "GND")
			(pinfunction "GND")
			(pintype "passive")
			(solder_mask_margin 0.075)
		)
		(pad "C7" smd circle
			(at -6.5 -10.5 90)
			(size 0.5 0.5)
			(layers "F.Cu" "F.Mask" "F.Paste")
			(net 172 "+1V2_MGTAVTT")
			(pinfunction "MGTAVTT_R")
			(pintype "passive")
			(solder_mask_margin 0.075)
		)
		(pad "C8" smd circle
			(at -5.5 -10.5 90)
			(size 0.5 0.5)
			(layers "F.Cu" "F.Mask" "F.Paste")
			(net 1 "GND")
			(pinfunction "GND")
			(pintype "passive")
			(solder_mask_margin 0.075)
		)
		(pad "C9" smd circle
			(at -4.5 -10.5 90)
			(size 0.5 0.5)
			(layers "F.Cu" "F.Mask" "F.Paste")
			(net 388 "/Debug FTDI + VNA/AUX.TCK")
			(pinfunction "IO_L9N_AD3N_86")
			(pintype "bidirectional")
			(die_length 18.411)
			(solder_mask_margin 0.075)
		)
		(pad "C10" smd circle
			(at -3.5 -10.5 90)
			(size 0.5 0.5)
			(layers "F.Cu" "F.Mask" "F.Paste")
			(net 1 "GND")
			(pinfunction "GND")
			(pintype "passive")
			(solder_mask_margin 0.075)
		)
		(pad "C11" smd circle
			(at -2.5 -10.5 90)
			(size 0.5 0.5)
			(layers "F.Cu" "F.Mask" "F.Paste")
			(net 505 "unconnected-(U34G-IO_L12P_AD0P_86-PadC11)")
			(pinfunction "IO_L12P_AD0P_86")
			(pintype "bidirectional+no_connect")
			(die_length 16.261)
			(solder_mask_margin 0.075)
		)
		(pad "C12" smd circle
			(at -1.5 -10.5 90)
			(size 0.5 0.5)
			(layers "F.Cu" "F.Mask" "F.Paste")
			(net 385 "HDMI_OE")
			(pinfunction "IO_L10P_AD10P_87")
			(pintype "bidirectional")
			(die_length 14.414)
			(solder_mask_margin 0.075)
		)
		(pad "C13" smd circle
			(at -0.5 -10.5 90)
			(size 0.5 0.5)
			(layers "F.Cu" "F.Mask" "F.Paste")
			(net 549 "HDMI_OUT_HPD")
			(pinfunction "IO_L9N_AD11N_87")
			(pintype "bidirectional")
			(die_length 13.612)
			(solder_mask_margin 0.075)
		)
		(pad "C14" smd circle
			(at 0.5 -10.5 90)
			(size 0.5 0.5)
			(layers "F.Cu" "F.Mask" "F.Paste")
			(net 768 "/FPGA MGT Interface/HDMI_CTL.SCL")
			(pinfunction "IO_L9P_AD11P_87")
			(pintype "bidirectional")
			(die_length 12.719)
			(solder_mask_margin 0.075)
		)
		(pad "C15" smd circle
			(at 1.5 -10.5 90)
			(size 0.5 0.5)
			(layers "F.Cu" "F.Mask" "F.Paste")
			(net 1 "GND")
			(pinfunction "GND")
			(pintype "passive")
			(solder_mask_margin 0.075)
		)
		(pad "C16" smd circle
			(at 2.5 -10.5 90)
			(size 0.5 0.5)
			(layers "F.Cu" "F.Mask" "F.Paste")
			(net 620 "/FPGA banks HP/HyperRAM.DQ1")
			(pinfunction "IO_L6N_T0U_N11_AD6N_67")
			(pintype "bidirectional")
			(die_length 16.954)
			(solder_mask_margin 0.075)
		)
		(pad "C17" smd circle
			(at 3.5 -10.5 90)
			(size 0.5 0.5)
			(layers "F.Cu" "F.Mask" "F.Paste")
			(net 395 "/Ethernet/ETH.RXD2")
			(pinfunction "IO_L15P_T2L_N4_AD11P_67")
			(pintype "bidirectional")
			(die_length 15.597)
			(solder_mask_margin 0.075)
		)
		(pad "C18" smd circle
			(at 4.5 -10.5 90)
			(size 0.5 0.5)
			(layers "F.Cu" "F.Mask" "F.Paste")
			(net 508 "unconnected-(U34E-IO_L13P_T2L_N0_GC_QBC_67-PadC18)")
			(pinfunction "IO_L13P_T2L_N0_GC_QBC_67")
			(pintype "bidirectional+no_connect")
			(die_length 14.663)
			(solder_mask_margin 0.075)
		)
		(pad "C19" smd circle
			(at 5.5 -10.5 90)
			(size 0.5 0.5)
			(layers "F.Cu" "F.Mask" "F.Paste")
			(net 509 "unconnected-(U34E-IO_L13N_T2L_N1_GC_QBC_67-PadC19)")
			(pinfunction "IO_L13N_T2L_N1_GC_QBC_67")
			(pintype "bidirectional+no_connect")
			(die_length 14.647)
			(solder_mask_margin 0.075)
		)
		(pad "C20" smd circle
			(at 6.5 -10.5 90)
			(size 0.5 0.5)
			(layers "F.Cu" "F.Mask" "F.Paste")
			(net 797 "+1V8")
			(pinfunction "VCCO_67")
			(pintype "power_in")
			(solder_mask_margin 0.075)
		)
		(pad "C21" smd circle
			(at 7.5 -10.5 90)
			(size 0.5 0.5)
			(layers "F.Cu" "F.Mask" "F.Paste")
			(net 397 "/Ethernet/ETH.RX_CTL")
			(pinfunction "IO_L22P_T3U_N6_DBC_AD0P_67")
			(pintype "bidirectional")
			(die_length 13.059)
			(solder_mask_margin 0.075)
		)
		(pad "C22" smd circle
			(at 8.5 -10.5 90)
			(size 0.5 0.5)
			(layers "F.Cu" "F.Mask" "F.Paste")
			(net 410 "/Ethernet/ETH.MDC")
			(pinfunction "IO_L24P_T3U_N10_67")
			(pintype "bidirectional")
			(die_length 11.885)
			(solder_mask_margin 0.075)
		)
		(pad "C23" smd circle
			(at 9.5 -10.5 90)
			(size 0.5 0.5)
			(layers "F.Cu" "F.Mask" "F.Paste")
			(net 401 "/Ethernet/ETH.~{RESET}")
			(pinfunction "IO_L21P_T3L_N4_AD8P_67")
			(pintype "bidirectional")
			(die_length 13.582)
			(solder_mask_margin 0.075)
		)
		(pad "C24" smd circle
			(at 10.5 -10.5 90)
			(size 0.5 0.5)
			(layers "F.Cu" "F.Mask" "F.Paste")
			(net 596 "/DDR5 RDIMM/B.DQS8_N")
			(pinfunction "IO_L22N_T3U_N7_DBC_AD0N_66")
			(pintype "bidirectional")
			(die_length 14.847)
			(solder_mask_margin 0.075)
		)
		(pad "C25" smd circle
			(at 11.5 -10.5 90)
			(size 0.5 0.5)
			(layers "F.Cu" "F.Mask" "F.Paste")
			(net 1 "GND")
			(pinfunction "GND")
			(pintype "passive")
			(solder_mask_margin 0.075)
		)
		(pad "C26" smd circle
			(at 12.5 -10.5 90)
			(size 0.5 0.5)
			(layers "F.Cu" "F.Mask" "F.Paste")
			(net 475 "/DDR5 RDIMM/B.DQ30")
			(pinfunction "IO_L23N_T3U_N9_66")
			(pintype "bidirectional")
			(die_length 17.439)
			(solder_mask_margin 0.075)
		)
		(pad "D1" smd circle
			(at -12.5 -9.5 90)
			(size 0.5 0.5)
			(layers "F.Cu" "F.Mask" "F.Paste")
			(net 510 "unconnected-(U34L-NC-PadD1)")
			(pinfunction "NC")
			(pintype "no_connect")
			(solder_mask_margin 0.075)
		)
		(pad "D2" smd circle
			(at -11.5 -9.5 90)
			(size 0.5 0.5)
			(layers "F.Cu" "F.Mask" "F.Paste")
			(net 511 "unconnected-(U34L-NC-PadD2)")
			(pinfunction "NC")
			(pintype "no_connect")
			(solder_mask_margin 0.075)
		)
		(pad "D3" smd circle
			(at -10.5 -9.5 90)
			(size 0.5 0.5)
			(layers "F.Cu" "F.Mask" "F.Paste")
			(net 1 "GND")
			(pinfunction "GND")
			(pintype "passive")
			(solder_mask_margin 0.075)
		)
		(pad "D4" smd circle
			(at -9.5 -9.5 90)
			(size 0.5 0.5)
			(layers "F.Cu" "F.Mask" "F.Paste")
			(net 1 "GND")
			(pinfunction "GND")
			(pintype "passive")
			(solder_mask_margin 0.075)
		)
		(pad "D5" smd circle
			(at -8.5 -9.5 90)
			(size 0.5 0.5)
			(layers "F.Cu" "F.Mask" "F.Paste")
			(net 1 "GND")
			(pinfunction "GND")
			(pintype "passive")
			(solder_mask_margin 0.075)
		)
		(pad "D6" smd circle
			(at -7.5 -9.5 90)
			(size 0.5 0.5)
			(layers "F.Cu" "F.Mask" "F.Paste")
			(net 512 "unconnected-(U34L-NC-PadD6)")
			(pinfunction "NC")
			(pintype "no_connect")
			(solder_mask_margin 0.075)
		)
		(pad "D7" smd circle
			(at -6.5 -9.5 90)
			(size 0.5 0.5)
			(layers "F.Cu" "F.Mask" "F.Paste")
			(net 513 "unconnected-(U34L-NC-PadD7)")
			(pinfunction "NC")
			(pintype "no_connect")
			(solder_mask_margin 0.075)
		)
		(pad "D8" smd circle
			(at -5.5 -9.5 90)
			(size 0.5 0.5)
			(layers "F.Cu" "F.Mask" "F.Paste")
			(net 1 "GND")
			(pinfunction "GND")
			(pintype "passive")
			(solder_mask_margin 0.075)
		)
		(pad "D9" smd circle
			(at -4.5 -9.5 90)
			(size 0.5 0.5)
			(layers "F.Cu" "F.Mask" "F.Paste")
			(net 408 "/Debug FTDI + VNA/AUX.TMS")
			(pinfunction "IO_L9P_AD3P_86")
			(pintype "bidirectional")
			(die_length 17.841)
			(solder_mask_margin 0.075)
		)
		(pad "D10" smd circle
			(at -3.5 -9.5 90)
			(size 0.5 0.5)
			(layers "F.Cu" "F.Mask" "F.Paste")
			(net 442 "/Debug FTDI + VNA/AUX.RST")
			(pinfunction "IO_L8N_HDGC_AD4N_86")
			(pintype "bidirectional")
			(die_length 16.776)
			(solder_mask_margin 0.075)
		)
		(pad "D11" smd circle
			(at -2.5 -9.5 90)
			(size 0.5 0.5)
			(layers "F.Cu" "F.Mask" "F.Paste")
			(net 514 "unconnected-(U34G-IO_L8P_HDGC_AD4P_86-PadD11)")
			(pinfunction "IO_L8P_HDGC_AD4P_86")
			(pintype "bidirectional+no_connect")
			(die_length 16.7)
			(solder_mask_margin 0.075)
		)
		(pad "D12" smd circle
			(at -1.5 -9.5 90)
			(size 0.5 0.5)
			(layers "F.Cu" "F.Mask" "F.Paste")
			(net 1 "GND")
			(pinfunction "GND")
			(pintype "passive")
			(solder_mask_margin 0.075)
		)
		(pad "D13" smd circle
			(at -0.5 -9.5 90)
			(size 0.5 0.5)
			(layers "F.Cu" "F.Mask" "F.Paste")
			(net 515 "unconnected-(U34H-IO_L8N_HDGC_87-PadD13)")
			(pinfunction "IO_L8N_HDGC_87")
			(pintype "bidirectional+no_connect")
			(die_length 12.81)
			(solder_mask_margin 0.075)
		)
		(pad "D14" smd circle
			(at 0.5 -9.5 90)
			(size 0.5 0.5)
			(layers "F.Cu" "F.Mask" "F.Paste")
			(net 769 "/FPGA MGT Interface/HDMI_CTL.SDA")
			(pinfunction "IO_L8P_HDGC_87")
			(pintype "bidirectional")
			(die_length 12.921)
			(solder_mask_margin 0.075)
		)
		(pad "D15" smd circle
			(at 1.5 -9.5 90)
			(size 0.5 0.5)
			(layers "F.Cu" "F.Mask" "F.Paste")
			(net 613 "/FPGA banks HP/HyperRAM.DQ3")
			(pinfunction "IO_L3N_T0L_N5_AD15N_67")
			(pintype "bidirectional")
			(die_length 16.228)
			(solder_mask_margin 0.075)
		)
		(pad "D16" smd circle
			(at 2.5 -9.5 90)
			(size 0.5 0.5)
			(layers "F.Cu" "F.Mask" "F.Paste")
			(net 614 "/FPGA banks HP/HyperRAM.DQ6")
			(pinfunction "IO_L6P_T0U_N10_AD6P_67")
			(pintype "bidirectional")
			(die_length 16.691)
			(solder_mask_margin 0.075)
		)
		(pad "D17" smd circle
			(at 3.5 -9.5 90)
			(size 0.5 0.5)
			(layers "F.Cu" "F.Mask" "F.Paste")
			(net 797 "+1V8")
			(pinfunction "VCCO_67")
			(pintype "passive")
			(solder_mask_margin 0.075)
		)
		(pad "D18" smd circle
			(at 4.5 -9.5 90)
			(size 0.5 0.5)
			(layers "F.Cu" "F.Mask" "F.Paste")
			(net 643 "unconnected-(U34E-IO_L11N_T1U_N9_GC_67-PadD18)")
			(pinfunction "IO_L11N_T1U_N9_GC_67")
			(pintype "bidirectional+no_connect")
			(die_length 13.119)
			(solder_mask_margin 0.075)
		)
		(pad "D19" smd circle
			(at 5.5 -9.5 90)
			(size 0.5 0.5)
			(layers "F.Cu" "F.Mask" "F.Paste")
			(net 403 "HDMI_REC_CLK_P")
			(pinfunction "IO_L12P_T1U_N10_GC_67")
			(pintype "bidirectional")
			(die_length 14.406)
			(solder_mask_margin 0.075)
		)
		(pad "D20" smd circle
			(at 6.5 -9.5 90)
			(size 0.5 0.5)
			(layers "F.Cu" "F.Mask" "F.Paste")
			(net 458 "HDMI_REC_CLK_N")
			(pinfunction "IO_L12N_T1U_N11_GC_67")
			(pintype "bidirectional")
			(die_length 14.428)
			(solder_mask_margin 0.075)
		)
		(pad "D21" smd circle
			(at 7.5 -9.5 90)
			(size 0.5 0.5)
			(layers "F.Cu" "F.Mask" "F.Paste")
			(net 435 "/Ethernet/ETH.TX_CTL")
			(pinfunction "IO_L20N_T3L_N3_AD1N_67")
			(pintype "bidirectional")
			(die_length 11.044)
			(solder_mask_margin 0.075)
		)
		(pad "D22" smd circle
			(at 8.5 -9.5 90)
			(size 0.5 0.5)
			(layers "F.Cu" "F.Mask" "F.Paste")
			(net 1 "GND")
			(pinfunction "GND")
			(pintype "passive")
			(solder_mask_margin 0.075)
		)
		(pad "D23" smd circle
			(at 9.5 -9.5 90)
			(size 0.5 0.5)
			(layers "F.Cu" "F.Mask" "F.Paste")
			(net 597 "/DDR5 RDIMM/B.DQS8_P")
			(pinfunction "IO_L22P_T3U_N6_DBC_AD0P_66")
			(pintype "bidirectional")
			(die_length 14.897)
			(solder_mask_margin 0.075)
		)
		(pad "D24" smd circle
			(at 10.5 -9.5 90)
			(size 0.5 0.5)
			(layers "F.Cu" "F.Mask" "F.Paste")
			(net 125 "/DDR5 RDIMM/B.DQ25")
			(pinfunction "IO_L21P_T3L_N4_AD8P_66")
			(pintype "bidirectional")
			(die_length 15.819)
			(solder_mask_margin 0.075)
		)
		(pad "D25" smd circle
			(at 11.5 -9.5 90)
			(size 0.5 0.5)
			(layers "F.Cu" "F.Mask" "F.Paste")
			(net 456 "/DDR5 RDIMM/B.DQ27")
			(pinfunction "IO_L21N_T3L_N5_AD8N_66")
			(pintype "bidirectional")
			(die_length 16.046)
			(solder_mask_margin 0.075)
		)
		(pad "D26" smd circle
			(at 12.5 -9.5 90)
			(size 0.5 0.5)
			(layers "F.Cu" "F.Mask" "F.Paste")
			(net 476 "/DDR5 RDIMM/B.DQ31")
			(pinfunction "IO_L23P_T3U_N8_66")
			(pintype "bidirectional")
			(die_length 17.602)
			(solder_mask_margin 0.075)
		)
		(pad "E1" smd circle
			(at -12.5 -8.5 90)
			(size 0.5 0.5)
			(layers "F.Cu" "F.Mask" "F.Paste")
			(net 1 "GND")
			(pinfunction "GND")
			(pintype "passive")
			(solder_mask_margin 0.075)
		)
		(pad "E2" smd circle
			(at -11.5 -8.5 90)
			(size 0.5 0.5)
			(layers "F.Cu" "F.Mask" "F.Paste")
			(net 1 "GND")
			(pinfunction "GND")
			(pintype "passive")
			(solder_mask_margin 0.075)
		)
		(pad "E3" smd circle
			(at -10.5 -8.5 90)
			(size 0.5 0.5)
			(layers "F.Cu" "F.Mask" "F.Paste")
			(net 1 "GND")
			(pinfunction "GND")
			(pintype "passive")
			(solder_mask_margin 0.075)
		)
		(pad "E4" smd circle
			(at -9.5 -8.5 90)
			(size 0.5 0.5)
			(layers "F.Cu" "F.Mask" "F.Paste")
			(net 516 "unconnected-(U34L-NC-PadE4)")
			(pinfunction "NC")
			(pintype "no_connect")
			(solder_mask_margin 0.075)
		)
		(pad "E5" smd circle
			(at -8.5 -8.5 90)
			(size 0.5 0.5)
			(layers "F.Cu" "F.Mask" "F.Paste")
			(net 517 "unconnected-(U34L-NC-PadE5)")
			(pinfunction "NC")
			(pintype "no_connect")
			(solder_mask_margin 0.075)
		)
		(pad "E6" smd circle
			(at -7.5 -8.5 90)
			(size 0.5 0.5)
			(layers "F.Cu" "F.Mask" "F.Paste")
			(net 1 "GND")
			(pinfunction "GND")
			(pintype "passive")
			(solder_mask_margin 0.075)
		)
		(pad "E7" smd circle
			(at -6.5 -8.5 90)
			(size 0.5 0.5)
			(layers "F.Cu" "F.Mask" "F.Paste")
			(net 172 "+1V2_MGTAVTT")
			(pinfunction "MGTAVTT_R")
			(pintype "passive")
			(solder_mask_margin 0.075)
		)
		(pad "E8" smd circle
			(at -5.5 -8.5 90)
			(size 0.5 0.5)
			(layers "F.Cu" "F.Mask" "F.Paste")
			(net 1 "GND")
			(pinfunction "GND")
			(pintype "passive")
			(solder_mask_margin 0.075)
		)
		(pad "E9" smd circle
			(at -4.5 -8.5 90)
			(size 0.5 0.5)
			(layers "F.Cu" "F.Mask" "F.Paste")
			(net 151 "+3V3")
			(pinfunction "VCCO_86")
			(pintype "power_in")
			(solder_mask_margin 0.075)
		)
		(pad "E10" smd circle
			(at -3.5 -8.5 90)
			(size 0.5 0.5)
			(layers "F.Cu" "F.Mask" "F.Paste")
			(net 518 "unconnected-(U34G-IO_L7N_HDGC_AD5N_86-PadE10)")
			(pinfunction "IO_L7N_HDGC_AD5N_86")
			(pintype "bidirectional+no_connect")
			(die_length 15.887)
			(solder_mask_margin 0.075)
		)
		(pad "E11" smd circle
			(at -2.5 -8.5 90)
			(size 0.5 0.5)
			(layers "F.Cu" "F.Mask" "F.Paste")
			(net 519 "unconnected-(U34G-IO_L7P_HDGC_AD5P_86-PadE11)")
			(pinfunction "IO_L7P_HDGC_AD5P_86")
			(pintype "bidirectional+no_connect")
			(die_length 15.718)
			(solder_mask_margin 0.075)
		)
		(pad "E12" smd circle
			(at -1.5 -8.5 90)
			(size 0.5 0.5)
			(layers "F.Cu" "F.Mask" "F.Paste")
			(net 520 "unconnected-(U34H-IO_L7N_HDGC_87-PadE12)")
			(pinfunction "IO_L7N_HDGC_87")
			(pintype "bidirectional+no_connect")
			(die_length 13.416)
			(solder_mask_margin 0.075)
		)
		(pad "E13" smd circle
			(at -0.5 -8.5 90)
			(size 0.5 0.5)
			(layers "F.Cu" "F.Mask" "F.Paste")
			(net 779 "~{I3C_EXT_PU}")
			(pinfunction "IO_L7P_HDGC_87")
			(pintype "bidirectional")
			(die_length 13.324)
			(solder_mask_margin 0.075)
		)
		(pad "E14" smd circle
			(at 0.5 -8.5 90)
			(size 0.5 0.5)
			(layers "F.Cu" "F.Mask" "F.Paste")
			(net 151 "+3V3")
			(pinfunction "VCCO_87")
			(pintype "power_in")
			(solder_mask_margin 0.075)
		)
		(pad "E15" smd circle
			(at 1.5 -8.5 90)
			(size 0.5 0.5)
			(layers "F.Cu" "F.Mask" "F.Paste")
			(net 615 "/FPGA banks HP/HyperRAM.DQ2")
			(pinfunction "IO_L3P_T0L_N4_AD15P_67")
			(pintype "bidirectional")
			(die_length 15.891)
			(solder_mask_margin 0.075)
		)
		(pad "E16" smd circle
			(at 2.5 -8.5 90)
			(size 0.5 0.5)
			(layers "F.Cu" "F.Mask" "F.Paste")
			(net 616 "/FPGA banks HP/HyperRAM.CK_P")
			(pinfunction "IO_L4P_T0U_N6_DBC_AD7P_67")
			(pintype "bidirectional")
			(die_length 15.758)
			(solder_mask_margin 0.075)
		)
		(pad "E17" smd circle
			(at 3.5 -8.5 90)
			(size 0.5 0.5)
			(layers "F.Cu" "F.Mask" "F.Paste")
			(net 617 "/FPGA banks HP/HyperRAM.CK_N")
			(pinfunction "IO_L4N_T0U_N7_DBC_AD7N_67")
			(pintype "bidirectional")
			(die_length 15.815)
			(solder_mask_margin 0.075)
		)
		(pad "E18" smd circle
			(at 4.5 -8.5 90)
			(size 0.5 0.5)
			(layers "F.Cu" "F.Mask" "F.Paste")
			(net 646 "unconnected-(U34E-IO_L11P_T1U_N8_GC_67-PadE18)")
			(pinfunction "IO_L11P_T1U_N8_GC_67")
			(pintype "bidirectional+no_connect")
			(die_length 12.991)
			(solder_mask_margin 0.075)
		)
		(pad "E19" smd circle
			(at 5.5 -8.5 90)
			(size 0.5 0.5)
			(layers "F.Cu" "F.Mask" "F.Paste")
			(net 1 "GND")
			(pinfunction "GND")
			(pintype "passive")
			(solder_mask_margin 0.075)
		)
		(pad "E20" smd circle
			(at 6.5 -8.5 90)
			(size 0.5 0.5)
			(layers "F.Cu" "F.Mask" "F.Paste")
			(net 635 "/FPGA banks HP/SD.CD")
			(pinfunction "IO_L10N_T1U_N7_QBC_AD4N_67")
			(pintype "bidirectional")
			(die_length 12.829)
			(solder_mask_margin 0.075)
		)
		(pad "E21" smd circle
			(at 7.5 -8.5 90)
			(size 0.5 0.5)
			(layers "F.Cu" "F.Mask" "F.Paste")
			(net 409 "/Ethernet/ETH.TXC")
			(pinfunction "IO_L20P_T3L_N2_AD1P_67")
			(pintype "bidirectional")
			(die_length 11.169)
			(solder_mask_margin 0.075)
		)
		(pad "E22" smd circle
			(at 8.5 -8.5 90)
			(size 0.5 0.5)
			(layers "F.Cu" "F.Mask" "F.Paste")
			(net 521 "unconnected-(U34E-IO_T3U_N12_67-PadE22)")
			(pinfunction "IO_T3U_N12_67")
			(pintype "bidirectional+no_connect")
			(die_length 11.166)
			(solder_mask_margin 0.075)
		)
		(pad "E23" smd circle
			(at 9.5 -8.5 90)
			(size 0.5 0.5)
			(layers "F.Cu" "F.Mask" "F.Paste")
			(net 455 "/DDR5 RDIMM/B.DQ26")
			(pinfunction "IO_L20N_T3L_N3_AD1N_66")
			(pintype "bidirectional")
			(die_length 13.567)
			(solder_mask_margin 0.075)
		)
		(pad "E24" smd circle
			(at 10.5 -8.5 90)
			(size 0.5 0.5)
			(layers "F.Cu" "F.Mask" "F.Paste")
			(net 687 "VDDQ")
			(pinfunction "VCCO_66")
			(pintype "power_in")
			(solder_mask_margin 0.075)
		)
		(pad "E25" smd circle
			(at 11.5 -8.5 90)
			(size 0.5 0.5)
			(layers "F.Cu" "F.Mask" "F.Paste")
			(net 156 "/DDR5 RDIMM/B.DQS3_P")
			(pinfunction "IO_L19P_T3L_N0_DBC_AD9P_66")
			(pintype "bidirectional")
			(die_length 16.51)
			(solder_mask_margin 0.075)
		)
		(pad "E26" smd circle
			(at 12.5 -8.5 90)
			(size 0.5 0.5)
			(layers "F.Cu" "F.Mask" "F.Paste")
			(net 161 "/DDR5 RDIMM/B.DQS3_N")
			(pinfunction "IO_L19N_T3L_N1_DBC_AD9N_66")
			(pintype "bidirectional")
			(die_length 16.508)
			(solder_mask_margin 0.075)
		)
		(pad "F1" smd circle
			(at -12.5 -7.5 90)
			(size 0.5 0.5)
			(layers "F.Cu" "F.Mask" "F.Paste")
			(net 522 "unconnected-(U34K-MGTYRXN3_226-PadF1)")
			(pinfunction "MGTYRXN3_226")
			(pintype "input+no_connect")
			(die_length 12.078)
			(solder_mask_margin 0.075)
		)
		(pad "F2" smd circle
			(at -11.5 -7.5 90)
			(size 0.5 0.5)
			(layers "F.Cu" "F.Mask" "F.Paste")
			(net 523 "unconnected-(U34K-MGTYRXP3_226-PadF2)")
			(pinfunction "MGTYRXP3_226")
			(pintype "input+no_connect")
			(die_length 12.056)
			(solder_mask_margin 0.075)
		)
		(pad "F3" smd circle
			(at -10.5 -7.5 90)
			(size 0.5 0.5)
			(layers "F.Cu" "F.Mask" "F.Paste")
			(net 1 "GND")
			(pinfunction "GND")
			(pintype "passive")
			(solder_mask_margin 0.075)
		)
		(pad "F4" smd circle
			(at -9.5 -7.5 90)
			(size 0.5 0.5)
			(layers "F.Cu" "F.Mask" "F.Paste")
			(net 1 "GND")
			(pinfunction "GND")
			(pintype "passive")
			(solder_mask_margin 0.075)
		)
		(pad "F5" smd circle
			(at -8.5 -7.5 90)
			(size 0.5 0.5)
			(layers "F.Cu" "F.Mask" "F.Paste")
			(net 172 "+1V2_MGTAVTT")
			(pinfunction "MGTAVTT_R")
			(pintype "passive")
			(solder_mask_margin 0.075)
		)
		(pad "F6" smd circle
			(at -7.5 -7.5 90)
			(size 0.5 0.5)
			(layers "F.Cu" "F.Mask" "F.Paste")
			(net 524 "unconnected-(U34L-NC-PadF6)")
			(pinfunction "NC")
			(pintype "no_connect")
			(solder_mask_margin 0.075)
		)
		(pad "F7" smd circle
			(at -6.5 -7.5 90)
			(size 0.5 0.5)
			(layers "F.Cu" "F.Mask" "F.Paste")
			(net 525 "unconnected-(U34L-NC-PadF7)")
			(pinfunction "NC")
			(pintype "no_connect")
			(solder_mask_margin 0.075)
		)
		(pad "F8" smd circle
			(at -5.5 -7.5 90)
			(size 0.5 0.5)
			(layers "F.Cu" "F.Mask" "F.Paste")
			(net 1 "GND")
			(pinfunction "GND")
			(pintype "passive")
			(solder_mask_margin 0.075)
		)
		(pad "F9" smd circle
			(at -4.5 -7.5 90)
			(size 0.5 0.5)
			(layers "F.Cu" "F.Mask" "F.Paste")
			(net 378 "/Debug FTDI + VNA/UART1.RX")
			(pinfunction "IO_L6N_HDGC_AD6N_86")
			(pintype "bidirectional")
			(die_length 16.849)
			(solder_mask_margin 0.075)
		)
		(pad "F10" smd circle
			(at -3.5 -7.5 90)
			(size 0.5 0.5)
			(layers "F.Cu" "F.Mask" "F.Paste")
			(net 377 "/Debug FTDI + VNA/UART1.TX")
			(pinfunction "IO_L6P_HDGC_AD6P_86")
			(pintype "bidirectional")
			(die_length 16.648)
			(solder_mask_margin 0.075)
		)
		(pad "F11" smd circle
			(at -2.5 -7.5 90)
			(size 0.5 0.5)
			(layers "F.Cu" "F.Mask" "F.Paste")
			(net 1 "GND")
			(pinfunction "GND")
			(pintype "passive")
			(solder_mask_margin 0.075)
		)
		(pad "F12" smd circle
			(at -1.5 -7.5 90)
			(size 0.5 0.5)
			(layers "F.Cu" "F.Mask" "F.Paste")
			(net 771 "/FPGA banks HD/FPGA_I3C.SCL")
			(pinfunction "IO_L5N_HDGC_87")
			(pintype "bidirectional")
			(die_length 13.397)
			(solder_mask_margin 0.075)
		)
		(pad "F13" smd circle
			(at -0.5 -7.5 90)
			(size 0.5 0.5)
			(layers "F.Cu" "F.Mask" "F.Paste")
			(net 778 "~{FPGA_I3C_EXT_PU}")
			(pinfunction "IO_L6N_HDGC_87")
			(pintype "bidirectional")
			(die_length 12.316)
			(solder_mask_margin 0.075)
		)
		(pad "F14" smd circle
			(at 0.5 -7.5 90)
			(size 0.5 0.5)
			(layers "F.Cu" "F.Mask" "F.Paste")
			(net 507 "HDMI_IN_CD")
			(pinfunction "IO_L6P_HDGC_87")
			(pintype "bidirectional")
			(die_length 12.245)
			(solder_mask_margin 0.075)
		)
		(pad "F15" smd circle
			(at 1.5 -7.5 90)
			(size 0.5 0.5)
			(layers "F.Cu" "F.Mask" "F.Paste")
			(net 623 "/FPGA banks HP/HyperRAM.~{RESET}")
			(pinfunction "IO_L1N_T0L_N1_DBC_67")
			(pintype "bidirectional")
			(die_length 16.19)
			(solder_mask_margin 0.075)
		)
		(pad "F16" smd circle
			(at 2.5 -7.5 90)
			(size 0.5 0.5)
			(layers "F.Cu" "F.Mask" "F.Paste")
			(net 1 "GND")
			(pinfunction "GND")
			(pintype "passive")
			(solder_mask_margin 0.075)
		)
		(pad "F17" smd circle
			(at 3.5 -7.5 90)
			(size 0.5 0.5)
			(layers "F.Cu" "F.Mask" "F.Paste")
			(net 601 "/FPGA banks HP/VRP_67")
			(pinfunction "IO_T0U_N12_VRP_67")
			(pintype "bidirectional")
			(die_length 13.09)
			(solder_mask_margin 0.075)
		)
		(pad "F18" smd circle
			(at 4.5 -7.5 90)
			(size 0.5 0.5)
			(layers "F.Cu" "F.Mask" "F.Paste")
			(net 636 "/FPGA banks HP/SD.CLK")
			(pinfunction "IO_L8P_T1L_N2_AD5P_67")
			(pintype "bidirectional")
			(die_length 16)
			(solder_mask_margin 0.075)
		)
		(pad "F19" smd circle
			(at 5.5 -7.5 90)
			(size 0.5 0.5)
			(layers "F.Cu" "F.Mask" "F.Paste")
			(net 640 "/FPGA banks HP/SD.DAT2")
			(pinfunction "IO_L8N_T1L_N3_AD5N_67")
			(pintype "bidirectional")
			(die_length 14.855)
			(solder_mask_margin 0.075)
		)
		(pad "F20" smd circle
			(at 6.5 -7.5 90)
			(size 0.5 0.5)
			(layers "F.Cu" "F.Mask" "F.Paste")
			(net 641 "/FPGA banks HP/SD.DAT3")
			(pinfunction "IO_L10P_T1U_N6_QBC_AD4P_67")
			(pintype "bidirectional")
			(die_length 12.765)
			(solder_mask_margin 0.075)
		)
		(pad "F21" smd circle
			(at 7.5 -7.5 90)
			(size 0.5 0.5)
			(layers "F.Cu" "F.Mask" "F.Paste")
			(net 1 "GND")
			(pinfunction "GND")
			(pintype "passive")
			(solder_mask_margin 0.075)
		)
		(pad "F22" smd circle
			(at 8.5 -7.5 90)
			(size 0.5 0.5)
			(layers "F.Cu" "F.Mask" "F.Paste")
			(net 529 "unconnected-(U34D-IO_T3U_N12_66-PadF22)")
			(pinfunction "IO_T3U_N12_66")
			(pintype "bidirectional+no_connect")
			(die_length 13.582)
			(solder_mask_margin 0.075)
		)
		(pad "F23" smd circle
			(at 9.5 -7.5 90)
			(size 0.5 0.5)
			(layers "F.Cu" "F.Mask" "F.Paste")
			(net 124 "/DDR5 RDIMM/B.DQ24")
			(pinfunction "IO_L20P_T3L_N2_AD1P_66")
			(pintype "bidirectional")
			(die_length 13.766)
			(solder_mask_margin 0.075)
		)
		(pad "F24" smd circle
			(at 10.5 -7.5 90)
			(size 0.5 0.5)
			(layers "F.Cu" "F.Mask" "F.Paste")
			(net 595 "/DDR5 RDIMM/B.DQS7_P")
			(pinfunction "IO_L16P_T2U_N6_QBC_AD3P_66")
			(pintype "bidirectional")
			(die_length 13.568)
			(solder_mask_margin 0.075)
		)
		(pad "F25" smd circle
			(at 11.5 -7.5 90)
			(size 0.5 0.5)
			(layers "F.Cu" "F.Mask" "F.Paste")
			(net 594 "/DDR5 RDIMM/B.DQS7_N")
			(pinfunction "IO_L16N_T2U_N7_QBC_AD3N_66")
			(pintype "bidirectional")
			(die_length 13.629)
			(solder_mask_margin 0.075)
		)
		(pad "F26" smd circle
			(at 12.5 -7.5 90)
			(size 0.5 0.5)
			(layers "F.Cu" "F.Mask" "F.Paste")
			(net 1 "GND")
			(pinfunction "GND")
			(pintype "passive")
			(solder_mask_margin 0.075)
		)
		(pad "G1" smd circle
			(at -12.5 -6.5 90)
			(size 0.5 0.5)
			(layers "F.Cu" "F.Mask" "F.Paste")
			(net 1 "GND")
			(pinfunction "GND")
			(pintype "passive")
			(solder_mask_margin 0.075)
		)
		(pad "G2" smd circle
			(at -11.5 -6.5 90)
			(size 0.5 0.5)
			(layers "F.Cu" "F.Mask" "F.Paste")
			(net 1 "GND")
			(pinfunction "GND")
			(pintype "passive")
			(solder_mask_margin 0.075)
		)
		(pad "G3" smd circle
			(at -10.5 -6.5 90)
			(size 0.5 0.5)
			(layers "F.Cu" "F.Mask" "F.Paste")
			(net 1 "GND")
			(pinfunction "GND")
			(pintype "passive")
			(solder_mask_margin 0.075)
		)
		(pad "G4" smd circle
			(at -9.5 -6.5 90)
			(size 0.5 0.5)
			(layers "F.Cu" "F.Mask" "F.Paste")
			(net 384 "/FPGA MGT Interface/HDMI_FPGA.TX_CLK_N")
			(pinfunction "MGTYTXN3_226")
			(pintype "output")
			(die_length 8.69)
			(solder_mask_margin 0.075)
		)
		(pad "G5" smd circle
			(at -8.5 -6.5 90)
			(size 0.5 0.5)
			(layers "F.Cu" "F.Mask" "F.Paste")
			(net 382 "/FPGA MGT Interface/HDMI_FPGA.TX_CLK_P")
			(pinfunction "MGTYTXP3_226")
			(pintype "output")
			(die_length 8.707)
			(solder_mask_margin 0.075)
		)
		(pad "G6" smd circle
			(at -7.5 -6.5 90)
			(size 0.5 0.5)
			(layers "F.Cu" "F.Mask" "F.Paste")
			(net 1 "GND")
			(pinfunction "GND")
			(pintype "passive")
			(solder_mask_margin 0.075)
		)
		(pad "G7" smd circle
			(at -6.5 -6.5 90)
			(size 0.5 0.5)
			(layers "F.Cu" "F.Mask" "F.Paste")
			(net 172 "+1V2_MGTAVTT")
			(pinfunction "MGTAVTT_R")
			(pintype "passive")
			(solder_mask_margin 0.075)
		)
		(pad "G8" smd circle
			(at -5.5 -6.5 90)
			(size 0.5 0.5)
			(layers "F.Cu" "F.Mask" "F.Paste")
			(net 1 "GND")
			(pinfunction "GND")
			(pintype "passive")
			(solder_mask_margin 0.075)
		)
		(pad "G9" smd circle
			(at -4.5 -6.5 90)
			(size 0.5 0.5)
			(layers "F.Cu" "F.Mask" "F.Paste")
			(net 374 "/Debug FTDI + VNA/UART0.TX")
			(pinfunction "IO_L5N_HDGC_AD7N_86")
			(pintype "bidirectional")
			(die_length 15.674)
			(solder_mask_margin 0.075)
		)
		(pad "G10" smd circle
			(at -3.5 -6.5 90)
			(size 0.5 0.5)
			(layers "F.Cu" "F.Mask" "F.Paste")
			(net 376 "/Debug FTDI + VNA/UART0.RX")
			(pinfunction "IO_L5P_HDGC_AD7P_86")
			(pintype "bidirectional")
			(die_length 15.718)
			(solder_mask_margin 0.075)
		)
		(pad "G11" smd circle
			(at -2.5 -6.5 90)
			(size 0.5 0.5)
			(layers "F.Cu" "F.Mask" "F.Paste")
			(net 532 "unconnected-(U34G-IO_L4N_AD8N_86-PadG11)")
			(pinfunction "IO_L4N_AD8N_86")
			(pintype "bidirectional+no_connect")
			(die_length 13.832)
			(solder_mask_margin 0.075)
		)
		(pad "G12" smd circle
			(at -1.5 -6.5 90)
			(size 0.5 0.5)
			(layers "F.Cu" "F.Mask" "F.Paste")
			(net 528 "/FPGA banks HD/FPGA_I3C.SDA")
			(pinfunction "IO_L5P_HDGC_87")
			(pintype "bidirectional")
			(die_length 13.4)
			(solder_mask_margin 0.075)
		)
		(pad "G13" smd circle
			(at -0.5 -6.5 90)
			(size 0.5 0.5)
			(layers "F.Cu" "F.Mask" "F.Paste")
			(net 1 "GND")
			(pinfunction "GND")
			(pintype "passive")
			(solder_mask_margin 0.075)
		)
		(pad "G14" smd circle
			(at 0.5 -6.5 90)
			(size 0.5 0.5)
			(layers "F.Cu" "F.Mask" "F.Paste")
			(net 798 "unconnected-(U34H-IO_L3N_AD13N_87-PadG14)")
			(pinfunction "IO_L3N_AD13N_87")
			(pintype "bidirectional+no_connect")
			(die_length 10.216)
			(solder_mask_margin 0.075)
		)
		(pad "G15" smd circle
			(at 1.5 -6.5 90)
			(size 0.5 0.5)
			(layers "F.Cu" "F.Mask" "F.Paste")
			(net 624 "/FPGA banks HP/HyperRAM.RWDS")
			(pinfunction "IO_L1P_T0L_N0_DBC_67")
			(pintype "bidirectional")
			(die_length 16.059)
			(solder_mask_margin 0.075)
		)
		(pad "G16" smd circle
			(at 2.5 -6.5 90)
			(size 0.5 0.5)
			(layers "F.Cu" "F.Mask" "F.Paste")
			(net 621 "/FPGA banks HP/HyperRAM.DQ4")
			(pinfunction "IO_L5N_T0U_N9_AD14N_67")
			(pintype "bidirectional")
			(die_length 13.156)
			(solder_mask_margin 0.075)
		)
		(pad "G17" smd circle
			(at 3.5 -6.5 90)
			(size 0.5 0.5)
			(layers "F.Cu" "F.Mask" "F.Paste")
			(net 610 "/FPGA banks HP/HyperRAM.DQ7")
			(pinfunction "IO_L2N_T0L_N3_67")
			(pintype "bidirectional")
			(die_length 13.048)
			(solder_mask_margin 0.075)
		)
		(pad "G18" smd circle
			(at 4.5 -6.5 90)
			(size 0.5 0.5)
			(layers "F.Cu" "F.Mask" "F.Paste")
			(net 797 "+1V8")
			(pinfunction "VCCO_67")
			(pintype "passive")
			(solder_mask_margin 0.075)
		)
		(pad "G19" smd circle
			(at 5.5 -6.5 90)
			(size 0.5 0.5)
			(layers "F.Cu" "F.Mask" "F.Paste")
			(net 672 "unconnected-(U34E-IO_T1U_N12_67-PadG19)")
			(pinfunction "IO_T1U_N12_67")
			(pintype "bidirectional+no_connect")
			(die_length 13.435)
			(solder_mask_margin 0.075)
		)
		(pad "G20" smd circle
			(at 6.5 -6.5 90)
			(size 0.5 0.5)
			(layers "F.Cu" "F.Mask" "F.Paste")
			(net 638 "/FPGA banks HP/SD.DAT0")
			(pinfunction "IO_L9P_T1L_N4_AD12P_67")
			(pintype "bidirectional")
			(die_length 12.173)
			(solder_mask_margin 0.075)
		)
		(pad "G21" smd circle
			(at 7.5 -6.5 90)
			(size 0.5 0.5)
			(layers "F.Cu" "F.Mask" "F.Paste")
			(net 639 "/FPGA banks HP/SD.DAT1")
			(pinfunction "IO_L9N_T1L_N5_AD12N_67")
			(pintype "bidirectional")
			(die_length 12.273)
			(solder_mask_margin 0.075)
		)
		(pad "G22" smd circle
			(at 8.5 -6.5 90)
			(size 0.5 0.5)
			(layers "F.Cu" "F.Mask" "F.Paste")
			(net 537 "unconnected-(U34D-IO_T2U_N12_66-PadG22)")
			(pinfunction "IO_T2U_N12_66")
			(pintype "bidirectional+no_connect")
			(die_length 11.631)
			(solder_mask_margin 0.075)
		)
		(pad "G23" smd circle
			(at 9.5 -6.5 90)
			(size 0.5 0.5)
			(layers "F.Cu" "F.Mask" "F.Paste")
			(net 1 "GND")
			(pinfunction "GND")
			(pintype "passive")
			(solder_mask_margin 0.075)
		)
		(pad "G24" smd circle
			(at 10.5 -6.5 90)
			(size 0.5 0.5)
			(layers "F.Cu" "F.Mask" "F.Paste")
			(net 147 "/DDR5 RDIMM/B.DQS2_P")
			(pinfunction "IO_L13P_T2L_N0_GC_QBC_66")
			(pintype "bidirectional")
			(die_length 13.798)
			(solder_mask_margin 0.075)
		)
		(pad "G25" smd circle
			(at 11.5 -6.5 90)
			(size 0.5 0.5)
			(layers "F.Cu" "F.Mask" "F.Paste")
			(net 148 "/DDR5 RDIMM/B.DQS2_N")
			(pinfunction "IO_L13N_T2L_N1_GC_QBC_66")
			(pintype "bidirectional")
			(die_length 13.716)
			(solder_mask_margin 0.075)
		)
		(pad "G26" smd circle
			(at 12.5 -6.5 90)
			(size 0.5 0.5)
			(layers "F.Cu" "F.Mask" "F.Paste")
			(net 122 "/DDR5 RDIMM/B.DQ20")
			(pinfunction "IO_L17N_T2U_N9_AD10N_66")
			(pintype "bidirectional")
			(die_length 14.685)
			(solder_mask_margin 0.075)
		)
		(pad "H1" smd circle
			(at -12.5 -5.5 90)
			(size 0.5 0.5)
			(layers "F.Cu" "F.Mask" "F.Paste")
			(net 648 "/FPGA MGT Interface/HDMI_FPGA.RX2_N")
			(pinfunction "MGTYRXN2_226")
			(pintype "input")
			(die_length 11.057)
			(solder_mask_margin 0.075)
		)
		(pad "H2" smd circle
			(at -11.5 -5.5 90)
			(size 0.5 0.5)
			(layers "F.Cu" "F.Mask" "F.Paste")
			(net 649 "/FPGA MGT Interface/HDMI_FPGA.RX2_P")
			(pinfunction "MGTYRXP2_226")
			(pintype "input")
			(die_length 11.047)
			(solder_mask_margin 0.075)
		)
		(pad "H3" smd circle
			(at -10.5 -5.5 90)
			(size 0.5 0.5)
			(layers "F.Cu" "F.Mask" "F.Paste")
			(net 1 "GND")
			(pinfunction "GND")
			(pintype "passive")
			(solder_mask_margin 0.075)
		)
		(pad "H4" smd circle
			(at -9.5 -5.5 90)
			(size 0.5 0.5)
			(layers "F.Cu" "F.Mask" "F.Paste")
			(net 1 "GND")
			(pinfunction "GND")
			(pintype "passive")
			(solder_mask_margin 0.075)
		)
		(pad "H5" smd circle
			(at -8.5 -5.5 90)
			(size 0.5 0.5)
			(layers "F.Cu" "F.Mask" "F.Paste")
			(net 172 "+1V2_MGTAVTT")
			(pinfunction "MGTAVTT_R")
			(pintype "passive")
			(solder_mask_margin 0.075)
		)
		(pad "H6" smd circle
			(at -7.5 -5.5 90)
			(size 0.5 0.5)
			(layers "F.Cu" "F.Mask" "F.Paste")
			(net 538 "unconnected-(U34L-NC-PadH6)")
			(pinfunction "NC")
			(pintype "no_connect")
			(solder_mask_margin 0.075)
		)
		(pad "H7" smd circle
			(at -6.5 -5.5 90)
			(size 0.5 0.5)
			(layers "F.Cu" "F.Mask" "F.Paste")
			(net 539 "unconnected-(U34L-NC-PadH7)")
			(pinfunction "NC")
			(pintype "no_connect")
			(solder_mask_margin 0.075)
		)
		(pad "H8" smd circle
			(at -5.5 -5.5 90)
			(size 0.5 0.5)
			(layers "F.Cu" "F.Mask" "F.Paste")
			(net 1 "GND")
			(pinfunction "GND")
			(pintype "passive")
			(solder_mask_margin 0.075)
		)
		(pad "H9" smd circle
			(at -4.5 -5.5 90)
			(size 0.5 0.5)
			(layers "F.Cu" "F.Mask" "F.Paste")
			(net 540 "unconnected-(U34G-IO_L3N_AD9N_86-PadH9)")
			(pinfunction "IO_L3N_AD9N_86")
			(pintype "bidirectional+no_connect")
			(die_length 15.853)
			(solder_mask_margin 0.075)
		)
		(pad "H10" smd circle
			(at -3.5 -5.5 90)
			(size 0.5 0.5)
			(layers "F.Cu" "F.Mask" "F.Paste")
			(net 151 "+3V3")
			(pinfunction "VCCO_86")
			(pintype "passive")
			(solder_mask_margin 0.075)
		)
		(pad "H11" smd circle
			(at -2.5 -5.5 90)
			(size 0.5 0.5)
			(layers "F.Cu" "F.Mask" "F.Paste")
			(net 541 "unconnected-(U34G-IO_L4P_AD8P_86-PadH11)")
			(pinfunction "IO_L4P_AD8P_86")
			(pintype "bidirectional+no_connect")
			(die_length 13.526)
			(solder_mask_margin 0.075)
		)
		(pad "H12" smd circle
			(at -1.5 -5.5 90)
			(size 0.5 0.5)
			(layers "F.Cu" "F.Mask" "F.Paste")
			(net 550 "/FPGA banks HD/HDMI_IN_I2C.SCL")
			(pinfunction "IO_L1N_AD15N_87")
			(pintype "bidirectional")
			(die_length 11.289)
			(solder_mask_margin 0.075)
		)
		(pad "H13" smd circle
			(at -0.5 -5.5 90)
			(size 0.5 0.5)
			(layers "F.Cu" "F.Mask" "F.Paste")
			(net 554 "/FPGA banks HD/HDMI_OUT_I2C.SCL")
			(pinfunction "IO_L2N_AD14N_87")
			(pintype "bidirectional")
			(die_length 9.307)
			(solder_mask_margin 0.075)
		)
		(pad "H14" smd circle
			(at 0.5 -5.5 90)
			(size 0.5 0.5)
			(layers "F.Cu" "F.Mask" "F.Paste")
			(net 799 "unconnected-(U34H-IO_L3P_AD13P_87-PadH14)")
			(pinfunction "IO_L3P_AD13P_87")
			(pintype "bidirectional+no_connect")
			(die_length 9.918)
			(solder_mask_margin 0.075)
		)
		(pad "H15" smd circle
			(at 1.5 -5.5 90)
			(size 0.5 0.5)
			(layers "F.Cu" "F.Mask" "F.Paste")
			(net 151 "+3V3")
			(pinfunction "VCCO_87")
			(pintype "passive")
			(solder_mask_margin 0.075)
		)
		(pad "H16" smd circle
			(at 2.5 -5.5 90)
			(size 0.5 0.5)
			(layers "F.Cu" "F.Mask" "F.Paste")
			(net 622 "/FPGA banks HP/HyperRAM.DQ0")
			(pinfunction "IO_L5P_T0U_N8_AD14P_67")
			(pintype "bidirectional")
			(die_length 12.856)
			(solder_mask_margin 0.075)
		)
		(pad "H17" smd circle
			(at 3.5 -5.5 90)
			(size 0.5 0.5)
			(layers "F.Cu" "F.Mask" "F.Paste")
			(net 619 "/FPGA banks HP/HyperRAM.DQ5")
			(pinfunction "IO_L2P_T0L_N2_67")
			(pintype "bidirectional")
			(die_length 12.955)
			(solder_mask_margin 0.075)
		)
		(pad "H18" smd circle
			(at 4.5 -5.5 90)
			(size 0.5 0.5)
			(layers "F.Cu" "F.Mask" "F.Paste")
			(net 618 "/FPGA banks HP/HyperRAM.~{CS}")
			(pinfunction "IO_L7P_T1L_N0_QBC_AD13P_67")
			(pintype "bidirectional")
			(die_length 12.354)
			(solder_mask_margin 0.075)
		)
		(pad "H19" smd circle
			(at 5.5 -5.5 90)
			(size 0.5 0.5)
			(layers "F.Cu" "F.Mask" "F.Paste")
			(net 637 "/FPGA banks HP/SD.CMD")
			(pinfunction "IO_L7N_T1L_N1_QBC_AD13N_67")
			(pintype "bidirectional")
			(die_length 12.276)
			(solder_mask_margin 0.075)
		)
		(pad "H20" smd circle
			(at 6.5 -5.5 90)
			(size 0.5 0.5)
			(layers "F.Cu" "F.Mask" "F.Paste")
			(net 1 "GND")
			(pinfunction "GND")
			(pintype "passive")
			(solder_mask_margin 0.075)
		)
		(pad "H21" smd circle
			(at 7.5 -5.5 90)
			(size 0.5 0.5)
			(layers "F.Cu" "F.Mask" "F.Paste")
			(net 454 "/DDR5 RDIMM/B.DQ23")
			(pinfunction "IO_L18P_T2U_N10_AD2P_66")
			(pintype "bidirectional")
			(die_length 11.698)
			(solder_mask_margin 0.075)
		)
		(pad "H22" smd circle
			(at 8.5 -5.5 90)
			(size 0.5 0.5)
			(layers "F.Cu" "F.Mask" "F.Paste")
			(net 123 "/DDR5 RDIMM/B.DQ21")
			(pinfunction "IO_L18N_T2U_N11_AD2N_66")
			(pintype "bidirectional")
			(die_length 11.516)
			(solder_mask_margin 0.075)
		)
		(pad "H23" smd circle
			(at 9.5 -5.5 90)
			(size 0.5 0.5)
			(layers "F.Cu" "F.Mask" "F.Paste")
			(net 118 "/DDR5 RDIMM/B.DQ16")
			(pinfunction "IO_L14P_T2L_N2_GC_66")
			(pintype "bidirectional")
			(die_length 11.537)
			(solder_mask_margin 0.075)
		)
		(pad "H24" smd circle
			(at 10.5 -5.5 90)
			(size 0.5 0.5)
			(layers "F.Cu" "F.Mask" "F.Paste")
			(net 360 "/DDR5 RDIMM/B.DQ18")
			(pinfunction "IO_L14N_T2L_N3_GC_66")
			(pintype "bidirectional")
			(die_length 11.55)
			(solder_mask_margin 0.075)
		)
		(pad "H25" smd circle
			(at 11.5 -5.5 90)
			(size 0.5 0.5)
			(layers "F.Cu" "F.Mask" "F.Paste")
			(net 687 "VDDQ")
			(pinfunction "VCCO_66")
			(pintype "passive")
			(solder_mask_margin 0.075)
		)
		(pad "H26" smd circle
			(at 12.5 -5.5 90)
			(size 0.5 0.5)
			(layers "F.Cu" "F.Mask" "F.Paste")
			(net 453 "/DDR5 RDIMM/B.DQ22")
			(pinfunction "IO_L17P_T2U_N8_AD10P_66")
			(pintype "bidirectional")
			(die_length 14.98)
			(solder_mask_margin 0.075)
		)
		(pad "J1" smd circle
			(at -12.5 -4.5 90)
			(size 0.5 0.5)
			(layers "F.Cu" "F.Mask" "F.Paste")
			(net 1 "GND")
			(pinfunction "GND")
			(pintype "passive")
			(solder_mask_margin 0.075)
		)
		(pad "J2" smd circle
			(at -11.5 -4.5 90)
			(size 0.5 0.5)
			(layers "F.Cu" "F.Mask" "F.Paste")
			(net 1 "GND")
			(pinfunction "GND")
			(pintype "passive")
			(solder_mask_margin 0.075)
		)
		(pad "J3" smd circle
			(at -10.5 -4.5 90)
			(size 0.5 0.5)
			(layers "F.Cu" "F.Mask" "F.Paste")
			(net 1 "GND")
			(pinfunction "GND")
			(pintype "passive")
			(solder_mask_margin 0.075)
		)
		(pad "J4" smd circle
			(at -9.5 -4.5 90)
			(size 0.5 0.5)
			(layers "F.Cu" "F.Mask" "F.Paste")
			(net 627 "/FPGA MGT Interface/HDMI_FPGA.TX2_N")
			(pinfunction "MGTYTXN2_226")
			(pintype "output")
			(die_length 9.068)
			(solder_mask_margin 0.075)
		)
		(pad "J5" smd circle
			(at -8.5 -4.5 90)
			(size 0.5 0.5)
			(layers "F.Cu" "F.Mask" "F.Paste")
			(net 628 "/FPGA MGT Interface/HDMI_FPGA.TX2_P")
			(pinfunction "MGTYTXP2_226")
			(pintype "output")
			(die_length 9.085)
			(solder_mask_margin 0.075)
		)
		(pad "J6" smd circle
			(at -7.5 -4.5 90)
			(size 0.5 0.5)
			(layers "F.Cu" "F.Mask" "F.Paste")
			(net 1 "GND")
			(pinfunction "GND")
			(pintype "passive")
			(solder_mask_margin 0.075)
		)
		(pad "J7" smd circle
			(at -6.5 -4.5 90)
			(size 0.5 0.5)
			(layers "F.Cu" "F.Mask" "F.Paste")
			(net 820 "+0V9_MGTAVCC")
			(pinfunction "MGTAVCC_R")
			(pintype "passive")
			(solder_mask_margin 0.075)
		)
		(pad "J8" smd circle
			(at -5.5 -4.5 90)
			(size 0.5 0.5)
			(layers "F.Cu" "F.Mask" "F.Paste")
			(net 1 "GND")
			(pinfunction "GND")
			(pintype "passive")
			(solder_mask_margin 0.075)
		)
		(pad "J9" smd circle
			(at -4.5 -4.5 90)
			(size 0.5 0.5)
			(layers "F.Cu" "F.Mask" "F.Paste")
			(net 697 "/FPGA banks HD/USR_LED1")
			(pinfunction "IO_L3P_AD9P_86")
			(pintype "bidirectional")
			(die_length 15.627)
			(solder_mask_margin 0.075)
		)
		(pad "J10" smd circle
			(at -3.5 -4.5 90)
			(size 0.5 0.5)
			(layers "F.Cu" "F.Mask" "F.Paste")
			(net 698 "/FPGA banks HD/USR_LED2")
			(pinfunction "IO_L2N_AD10N_86")
			(pintype "bidirectional")
			(die_length 14.793)
			(solder_mask_margin 0.075)
		)
		(pad "J11" smd circle
			(at -2.5 -4.5 90)
			(size 0.5 0.5)
			(layers "F.Cu" "F.Mask" "F.Paste")
			(net 699 "/FPGA banks HD/USR_LED3")
			(pinfunction "IO_L2P_AD10P_86")
			(pintype "bidirectional")
			(die_length 14.115)
			(solder_mask_margin 0.075)
		)
		(pad "J12" smd circle
			(at -1.5 -4.5 90)
			(size 0.5 0.5)
			(layers "F.Cu" "F.Mask" "F.Paste")
			(net 555 "/FPGA banks HD/HDMI_IN_I2C.SDA")
			(pinfunction "IO_L1P_AD15P_87")
			(pintype "bidirectional")
			(die_length 11.407)
			(solder_mask_margin 0.075)
		)
		(pad "J13" smd circle
			(at -0.5 -4.5 90)
			(size 0.5 0.5)
			(layers "F.Cu" "F.Mask" "F.Paste")
			(net 644 "/FPGA banks HD/HDMI_OUT_I2C.SDA")
			(pinfunction "IO_L2P_AD14P_87")
			(pintype "bidirectional")
			(die_length 9.54)
			(solder_mask_margin 0.075)
		)
		(pad "J14" smd circle
			(at 0.5 -4.5 90)
			(size 0.5 0.5)
			(layers "F.Cu" "F.Mask" "F.Paste")
			(net 800 "unconnected-(U34H-IO_L4N_AD12N_87-PadJ14)")
			(pinfunction "IO_L4N_AD12N_87")
			(pintype "bidirectional+no_connect")
			(die_length 9.364)
			(solder_mask_margin 0.075)
		)
		(pad "J15" smd circle
			(at 1.5 -4.5 90)
			(size 0.5 0.5)
			(layers "F.Cu" "F.Mask" "F.Paste")
			(net 801 "unconnected-(U34H-IO_L4P_AD12P_87-PadJ15)")
			(pinfunction "IO_L4P_AD12P_87")
			(pintype "bidirectional+no_connect")
			(die_length 9.373)
			(solder_mask_margin 0.075)
		)
		(pad "J16" smd circle
			(at 2.5 -4.5 90)
			(size 0.5 0.5)
			(layers "F.Cu" "F.Mask" "F.Paste")
			(net 546 "/FPGA banks HP/VREF_67")
			(pinfunction "VREF_67")
			(pintype "input")
			(solder_mask_margin 0.075)
		)
		(pad "J17" smd circle
			(at 3.5 -4.5 90)
			(size 0.5 0.5)
			(layers "F.Cu" "F.Mask" "F.Paste")
			(net 1 "GND")
			(pinfunction "GND")
			(pintype "passive")
			(solder_mask_margin 0.075)
		)
		(pad "J18" smd circle
			(at 4.5 -4.5 90)
			(size 0.5 0.5)
			(layers "F.Cu" "F.Mask" "F.Paste")
			(net 545 "/FPGA banks HP/VREF_66")
			(pinfunction "VREF_66")
			(pintype "input")
			(solder_mask_margin 0.075)
		)
		(pad "J19" smd circle
			(at 5.5 -4.5 90)
			(size 0.5 0.5)
			(layers "F.Cu" "F.Mask" "F.Paste")
			(net 212 "/DDR5 RDIMM/B.DQ2")
			(pinfunction "IO_L3P_T0L_N4_AD15P_66")
			(pintype "bidirectional")
			(die_length 18.466)
			(solder_mask_margin 0.075)
		)
		(pad "J20" smd circle
			(at 6.5 -4.5 90)
			(size 0.5 0.5)
			(layers "F.Cu" "F.Mask" "F.Paste")
			(net 213 "/DDR5 RDIMM/B.DQ3")
			(pinfunction "IO_L3N_T0L_N5_AD15N_66")
			(pintype "bidirectional")
			(die_length 16.89)
			(solder_mask_margin 0.075)
		)
		(pad "J21" smd circle
			(at 7.5 -4.5 90)
			(size 0.5 0.5)
			(layers "F.Cu" "F.Mask" "F.Paste")
			(net 218 "/DDR5 RDIMM/B.DQ7")
			(pinfunction "IO_L5N_T0U_N9_AD14N_66")
			(pintype "bidirectional")
			(die_length 15.754)
			(solder_mask_margin 0.075)
		)
		(pad "J22" smd circle
			(at 8.5 -4.5 90)
			(size 0.5 0.5)
			(layers "F.Cu" "F.Mask" "F.Paste")
			(net 687 "VDDQ")
			(pinfunction "VCCO_66")
			(pintype "passive")
			(solder_mask_margin 0.075)
		)
		(pad "J23" smd circle
			(at 9.5 -4.5 90)
			(size 0.5 0.5)
			(layers "F.Cu" "F.Mask" "F.Paste")
			(net 358 "/DDR5 RDIMM/B.DQ14")
			(pinfunction "IO_L12P_T1U_N10_GC_66")
			(pintype "bidirectional")
			(die_length 11.034)
			(solder_mask_margin 0.075)
		)
		(pad "J24" smd circle
			(at 10.5 -4.5 90)
			(size 0.5 0.5)
			(layers "F.Cu" "F.Mask" "F.Paste")
			(net 116 "/DDR5 RDIMM/B.DQ12")
			(pinfunction "IO_L12N_T1U_N11_GC_66")
			(pintype "bidirectional")
			(die_length 10.935)
			(solder_mask_margin 0.075)
		)
		(pad "J25" smd circle
			(at 11.5 -4.5 90)
			(size 0.5 0.5)
			(layers "F.Cu" "F.Mask" "F.Paste")
			(net 119 "/DDR5 RDIMM/B.DQ17")
			(pinfunction "IO_L15P_T2L_N4_AD11P_66")
			(pintype "bidirectional")
			(die_length 15.524)
			(solder_mask_margin 0.075)
		)
		(pad "J26" smd circle
			(at 12.5 -4.5 90)
			(size 0.5 0.5)
			(layers "F.Cu" "F.Mask" "F.Paste")
			(net 450 "/DDR5 RDIMM/B.DQ19")
			(pinfunction "IO_L15N_T2L_N5_AD11N_66")
			(pintype "bidirectional")
			(die_length 15.495)
			(solder_mask_margin 0.075)
		)
		(pad "K1" smd circle
			(at -12.5 -3.5 90)
			(size 0.5 0.5)
			(layers "F.Cu" "F.Mask" "F.Paste")
			(net 650 "/FPGA MGT Interface/HDMI_FPGA.RX1_N")
			(pinfunction "MGTYRXN1_226")
			(pintype "input")
			(die_length 9.924)
			(solder_mask_margin 0.075)
		)
		(pad "K2" smd circle
			(at -11.5 -3.5 90)
			(size 0.5 0.5)
			(layers "F.Cu" "F.Mask" "F.Paste")
			(net 651 "/FPGA MGT Interface/HDMI_FPGA.RX1_P")
			(pinfunction "MGTYRXP1_226")
			(pintype "input")
			(die_length 9.903)
			(solder_mask_margin 0.075)
		)
		(pad "K3" smd circle
			(at -10.5 -3.5 90)
			(size 0.5 0.5)
			(layers "F.Cu" "F.Mask" "F.Paste")
			(net 1 "GND")
			(pinfunction "GND")
			(pintype "passive")
			(solder_mask_margin 0.075)
		)
		(pad "K4" smd circle
			(at -9.5 -3.5 90)
			(size 0.5 0.5)
			(layers "F.Cu" "F.Mask" "F.Paste")
			(net 1 "GND")
			(pinfunction "GND")
			(pintype "passive")
			(solder_mask_margin 0.075)
		)
		(pad "K5" smd circle
			(at -8.5 -3.5 90)
			(size 0.5 0.5)
			(layers "F.Cu" "F.Mask" "F.Paste")
			(net 172 "+1V2_MGTAVTT")
			(pinfunction "MGTAVTT_R")
			(pintype "passive")
			(solder_mask_margin 0.075)
		)
		(pad "K6" smd circle
			(at -7.5 -3.5 90)
			(size 0.5 0.5)
			(layers "F.Cu" "F.Mask" "F.Paste")
			(net 551 "unconnected-(U34L-NC-PadK6)")
			(pinfunction "NC")
			(pintype "no_connect")
			(solder_mask_margin 0.075)
		)
		(pad "K7" smd circle
			(at -6.5 -3.5 90)
			(size 0.5 0.5)
			(layers "F.Cu" "F.Mask" "F.Paste")
			(net 552 "unconnected-(U34L-NC-PadK7)")
			(pinfunction "NC")
			(pintype "no_connect")
			(solder_mask_margin 0.075)
		)
		(pad "K8" smd circle
			(at -5.5 -3.5 90)
			(size 0.5 0.5)
			(layers "F.Cu" "F.Mask" "F.Paste")
			(net 1 "GND")
			(pinfunction "GND")
			(pintype "passive")
			(solder_mask_margin 0.075)
		)
		(pad "K9" smd circle
			(at -4.5 -3.5 90)
			(size 0.5 0.5)
			(layers "F.Cu" "F.Mask" "F.Paste")
			(net 700 "/FPGA banks HD/USR_LED4")
			(pinfunction "IO_L1N_AD11N_86")
			(pintype "bidirectional")
			(die_length 16.677)
			(solder_mask_margin 0.075)
		)
		(pad "K10" smd circle
			(at -3.5 -3.5 90)
			(size 0.5 0.5)
			(layers "F.Cu" "F.Mask" "F.Paste")
			(net 701 "/FPGA banks HD/USR_LED5")
			(pinfunction "IO_L1P_AD11P_86")
			(pintype "bidirectional")
			(die_length 15.605)
			(solder_mask_margin 0.075)
		)
		(pad "K11" smd circle
			(at -2.5 -3.5 90)
			(size 0.5 0.5)
			(layers "F.Cu" "F.Mask" "F.Paste")
			(net 553 "+0V85")
			(pinfunction "VCCINT")
			(pintype "power_in")
			(solder_mask_margin 0.075)
		)
		(pad "K12" smd circle
			(at -1.5 -3.5 90)
			(size 0.5 0.5)
			(layers "F.Cu" "F.Mask" "F.Paste")
			(net 1 "GND")
			(pinfunction "GND")
			(pintype "passive")
			(solder_mask_margin 0.075)
		)
		(pad "K13" smd circle
			(at -0.5 -3.5 90)
			(size 0.5 0.5)
			(layers "F.Cu" "F.Mask" "F.Paste")
			(net 553 "+0V85")
			(pinfunction "VCCINT")
			(pintype "passive")
			(solder_mask_margin 0.075)
		)
		(pad "K14" smd circle
			(at 0.5 -3.5 90)
			(size 0.5 0.5)
			(layers "F.Cu" "F.Mask" "F.Paste")
			(net 1 "GND")
			(pinfunction "GND")
			(pintype "passive")
			(solder_mask_margin 0.075)
		)
		(pad "K15" smd circle
			(at 1.5 -3.5 90)
			(size 0.5 0.5)
			(layers "F.Cu" "F.Mask" "F.Paste")
			(net 553 "+0V85")
			(pinfunction "VCCINT")
			(pintype "passive")
			(solder_mask_margin 0.075)
		)
		(pad "K16" smd circle
			(at 2.5 -3.5 90)
			(size 0.5 0.5)
			(layers "F.Cu" "F.Mask" "F.Paste")
			(net 1 "GND")
			(pinfunction "GND")
			(pintype "passive")
			(solder_mask_margin 0.075)
		)
		(pad "K17" smd circle
			(at 3.5 -3.5 90)
			(size 0.5 0.5)
			(layers "F.Cu" "F.Mask" "F.Paste")
			(net 553 "+0V85")
			(pinfunction "VCCINT")
			(pintype "passive")
			(solder_mask_margin 0.075)
		)
		(pad "K18" smd circle
			(at 4.5 -3.5 90)
			(size 0.5 0.5)
			(layers "F.Cu" "F.Mask" "F.Paste")
			(net 133 "/DDR5 RDIMM/B.DQS0_N")
			(pinfunction "IO_L1N_T0L_N1_DBC_66")
			(pintype "bidirectional")
			(die_length 19.351)
			(solder_mask_margin 0.075)
		)
		(pad "K19" smd circle
			(at 5.5 -3.5 90)
			(size 0.5 0.5)
			(layers "F.Cu" "F.Mask" "F.Paste")
			(net 1 "GND")
			(pinfunction "GND")
			(pintype "passive")
			(solder_mask_margin 0.075)
		)
		(pad "K20" smd circle
			(at 6.5 -3.5 90)
			(size 0.5 0.5)
			(layers "F.Cu" "F.Mask" "F.Paste")
			(net 111 "/DDR5 RDIMM/B.DQ5")
			(pinfunction "IO_L6N_T0U_N11_AD6N_66")
			(pintype "bidirectional")
			(die_length 15.537)
			(solder_mask_margin 0.075)
		)
		(pad "K21" smd circle
			(at 7.5 -3.5 90)
			(size 0.5 0.5)
			(layers "F.Cu" "F.Mask" "F.Paste")
			(net 110 "/DDR5 RDIMM/B.DQ4")
			(pinfunction "IO_L5P_T0U_N8_AD14P_66")
			(pintype "bidirectional")
			(die_length 15.555)
			(solder_mask_margin 0.075)
		)
		(pad "K22" smd circle
			(at 8.5 -3.5 90)
			(size 0.5 0.5)
			(layers "F.Cu" "F.Mask" "F.Paste")
			(net 359 "/DDR5 RDIMM/B.DQ15")
			(pinfunction "IO_L11P_T1U_N8_GC_66")
			(pintype "bidirectional")
			(die_length 11.234)
			(solder_mask_margin 0.075)
		)
		(pad "K23" smd circle
			(at 9.5 -3.5 90)
			(size 0.5 0.5)
			(layers "F.Cu" "F.Mask" "F.Paste")
			(net 117 "/DDR5 RDIMM/B.DQ13")
			(pinfunction "IO_L11N_T1U_N9_GC_66")
			(pintype "bidirectional")
			(die_length 11.109)
			(solder_mask_margin 0.075)
		)
		(pad "K24" smd circle
			(at 10.5 -3.5 90)
			(size 0.5 0.5)
			(layers "F.Cu" "F.Mask" "F.Paste")
			(net 1 "GND")
			(pinfunction "GND")
			(pintype "passive")
			(solder_mask_margin 0.075)
		)
		(pad "K25" smd circle
			(at 11.5 -3.5 90)
			(size 0.5 0.5)
			(layers "F.Cu" "F.Mask" "F.Paste")
			(net 229 "/DDR5 RDIMM/B.DQ11")
			(pinfunction "IO_L9P_T1L_N4_AD12P_66")
			(pintype "bidirectional")
			(die_length 13.374)
			(solder_mask_margin 0.075)
		)
		(pad "K26" smd circle
			(at 12.5 -3.5 90)
			(size 0.5 0.5)
			(layers "F.Cu" "F.Mask" "F.Paste")
			(net 219 "/DDR5 RDIMM/B.DQ10")
			(pinfunction "IO_L9N_T1L_N5_AD12N_66")
			(pintype "bidirectional")
			(die_length 13.552)
			(solder_mask_margin 0.075)
		)
		(pad "L1" smd circle
			(at -12.5 -2.5 90)
			(size 0.5 0.5)
			(layers "F.Cu" "F.Mask" "F.Paste")
			(net 1 "GND")
			(pinfunction "GND")
			(pintype "passive")
			(solder_mask_margin 0.075)
		)
		(pad "L2" smd circle
			(at -11.5 -2.5 90)
			(size 0.5 0.5)
			(layers "F.Cu" "F.Mask" "F.Paste")
			(net 1 "GND")
			(pinfunction "GND")
			(pintype "passive")
			(solder_mask_margin 0.075)
		)
		(pad "L3" smd circle
			(at -10.5 -2.5 90)
			(size 0.5 0.5)
			(layers "F.Cu" "F.Mask" "F.Paste")
			(net 1 "GND")
			(pinfunction "GND")
			(pintype "passive")
			(solder_mask_margin 0.075)
		)
		(pad "L4" smd circle
			(at -9.5 -2.5 90)
			(size 0.5 0.5)
			(layers "F.Cu" "F.Mask" "F.Paste")
			(net 629 "/FPGA MGT Interface/HDMI_FPGA.TX1_N")
			(pinfunction "MGTYTXN1_226")
			(pintype "output")
			(die_length 7.883)
			(solder_mask_margin 0.075)
		)
		(pad "L5" smd circle
			(at -8.5 -2.5 90)
			(size 0.5 0.5)
			(layers "F.Cu" "F.Mask" "F.Paste")
			(net 630 "/FPGA MGT Interface/HDMI_FPGA.TX1_P")
			(pinfunction "MGTYTXP1_226")
			(pintype "output")
			(die_length 7.909)
			(solder_mask_margin 0.075)
		)
		(pad "L6" smd circle
			(at -7.5 -2.5 90)
			(size 0.5 0.5)
			(layers "F.Cu" "F.Mask" "F.Paste")
			(net 1 "GND")
			(pinfunction "GND")
			(pintype "passive")
			(solder_mask_margin 0.075)
		)
		(pad "L7" smd circle
			(at -6.5 -2.5 90)
			(size 0.5 0.5)
			(layers "F.Cu" "F.Mask" "F.Paste")
			(net 820 "+0V9_MGTAVCC")
			(pinfunction "MGTAVCC_R")
			(pintype "passive")
			(solder_mask_margin 0.075)
		)
		(pad "L8" smd circle
			(at -5.5 -2.5 90)
			(size 0.5 0.5)
			(layers "F.Cu" "F.Mask" "F.Paste")
			(net 1 "GND")
			(pinfunction "GND")
			(pintype "passive")
			(solder_mask_margin 0.075)
		)
		(pad "L9" smd circle
			(at -4.5 -2.5 90)
			(size 0.5 0.5)
			(layers "F.Cu" "F.Mask" "F.Paste")
			(net 553 "+0V85")
			(pinfunction "VCCINT_IO")
			(pintype "power_in")
			(solder_mask_margin 0.075)
		)
		(pad "L10" smd circle
			(at -3.5 -2.5 90)
			(size 0.5 0.5)
			(layers "F.Cu" "F.Mask" "F.Paste")
			(net 553 "+0V85")
			(pinfunction "VCCINT")
			(pintype "passive")
			(solder_mask_margin 0.075)
		)
		(pad "L11" smd circle
			(at -2.5 -2.5 90)
			(size 0.5 0.5)
			(layers "F.Cu" "F.Mask" "F.Paste")
			(net 1 "GND")
			(pinfunction "GND")
			(pintype "passive")
			(solder_mask_margin 0.075)
		)
		(pad "L12" smd circle
			(at -1.5 -2.5 90)
			(size 0.5 0.5)
			(layers "F.Cu" "F.Mask" "F.Paste")
			(net 553 "+0V85")
			(pinfunction "VCCINT")
			(pintype "passive")
			(solder_mask_margin 0.075)
		)
		(pad "L13" smd circle
			(at -0.5 -2.5 90)
			(size 0.5 0.5)
			(layers "F.Cu" "F.Mask" "F.Paste")
			(net 1 "GND")
			(pinfunction "GND")
			(pintype "passive")
			(solder_mask_margin 0.075)
		)
		(pad "L14" smd circle
			(at 0.5 -2.5 90)
			(size 0.5 0.5)
			(layers "F.Cu" "F.Mask" "F.Paste")
			(net 553 "+0V85")
			(pinfunction "VCCINT")
			(pintype "passive")
			(solder_mask_margin 0.075)
		)
		(pad "L15" smd circle
			(at 1.5 -2.5 90)
			(size 0.5 0.5)
			(layers "F.Cu" "F.Mask" "F.Paste")
			(net 1 "GND")
			(pinfunction "GND")
			(pintype "passive")
			(solder_mask_margin 0.075)
		)
		(pad "L16" smd circle
			(at 2.5 -2.5 90)
			(size 0.5 0.5)
			(layers "F.Cu" "F.Mask" "F.Paste")
			(net 553 "+0V85")
			(pinfunction "VCCINT")
			(pintype "passive")
			(solder_mask_margin 0.075)
		)
		(pad "L17" smd circle
			(at 3.5 -2.5 90)
			(size 0.5 0.5)
			(layers "F.Cu" "F.Mask" "F.Paste")
			(net 1 "GND")
			(pinfunction "GND")
			(pintype "passive")
			(solder_mask_margin 0.075)
		)
		(pad "L18" smd circle
			(at 4.5 -2.5 90)
			(size 0.5 0.5)
			(layers "F.Cu" "F.Mask" "F.Paste")
			(net 132 "/DDR5 RDIMM/B.DQS0_P")
			(pinfunction "IO_L1P_T0L_N0_DBC_66")
			(pintype "bidirectional")
			(die_length 19.491)
			(solder_mask_margin 0.075)
		)
		(pad "L19" smd circle
			(at 5.5 -2.5 90)
			(size 0.5 0.5)
			(layers "F.Cu" "F.Mask" "F.Paste")
			(net 457 "/DDR5 RDIMM/B.DQS5_N")
			(pinfunction "IO_L4N_T0U_N7_DBC_AD7N_66")
			(pintype "bidirectional")
			(die_length 15.594)
			(solder_mask_margin 0.075)
		)
		(pad "L20" smd circle
			(at 6.5 -2.5 90)
			(size 0.5 0.5)
			(layers "F.Cu" "F.Mask" "F.Paste")
			(net 217 "/DDR5 RDIMM/B.DQ6")
			(pinfunction "IO_L6P_T0U_N10_AD6P_66")
			(pintype "bidirectional")
			(die_length 15.624)
			(solder_mask_margin 0.075)
		)
		(pad "L21" smd circle
			(at 7.5 -2.5 90)
			(size 0.5 0.5)
			(layers "F.Cu" "F.Mask" "F.Paste")
			(net 1 "GND")
			(pinfunction "GND")
			(pintype "passive")
			(solder_mask_margin 0.075)
		)
		(pad "L22" smd circle
			(at 8.5 -2.5 90)
			(size 0.5 0.5)
			(layers "F.Cu" "F.Mask" "F.Paste")
			(net 141 "/DDR5 RDIMM/B.DQS1_P")
			(pinfunction "IO_L7P_T1L_N0_QBC_AD13P_66")
			(pintype "bidirectional")
			(die_length 9.844)
			(solder_mask_margin 0.075)
		)
		(pad "L23" smd circle
			(at 9.5 -2.5 90)
			(size 0.5 0.5)
			(layers "F.Cu" "F.Mask" "F.Paste")
			(net 142 "/DDR5 RDIMM/B.DQS1_N")
			(pinfunction "IO_L7N_T1L_N1_QBC_AD13N_66")
			(pintype "bidirectional")
			(die_length 9.768)
			(solder_mask_margin 0.075)
		)
		(pad "L24" smd circle
			(at 10.5 -2.5 90)
			(size 0.5 0.5)
			(layers "F.Cu" "F.Mask" "F.Paste")
			(net 593 "/DDR5 RDIMM/B.DQS6_P")
			(pinfunction "IO_L10P_T1U_N6_QBC_AD4P_66")
			(pintype "bidirectional")
			(die_length 11.633)
			(solder_mask_margin 0.075)
		)
		(pad "L25" smd circle
			(at 11.5 -2.5 90)
			(size 0.5 0.5)
			(layers "F.Cu" "F.Mask" "F.Paste")
			(net 592 "/DDR5 RDIMM/B.DQS6_N")
			(pinfunction "IO_L10N_T1U_N7_QBC_AD4N_66")
			(pintype "bidirectional")
			(die_length 11.533)
			(solder_mask_margin 0.075)
		)
		(pad "L26" smd circle
			(at 12.5 -2.5 90)
			(size 0.5 0.5)
			(layers "F.Cu" "F.Mask" "F.Paste")
			(net 1 "GND")
			(pinfunction "GND")
			(pintype "passive")
			(solder_mask_margin 0.075)
		)
		(pad "M1" smd circle
			(at -12.5 -1.5 90)
			(size 0.5 0.5)
			(layers "F.Cu" "F.Mask" "F.Paste")
			(net 652 "/FPGA MGT Interface/HDMI_FPGA.RX0_N")
			(pinfunction "MGTYRXN0_226")
			(pintype "input")
			(die_length 9.858)
			(solder_mask_margin 0.075)
		)
		(pad "M2" smd circle
			(at -11.5 -1.5 90)
			(size 0.5 0.5)
			(layers "F.Cu" "F.Mask" "F.Paste")
			(net 653 "/FPGA MGT Interface/HDMI_FPGA.RX0_P")
			(pinfunction "MGTYRXP0_226")
			(pintype "input")
			(die_length 9.85)
			(solder_mask_margin 0.075)
		)
		(pad "M3" smd circle
			(at -10.5 -1.5 90)
			(size 0.5 0.5)
			(layers "F.Cu" "F.Mask" "F.Paste")
			(net 1 "GND")
			(pinfunction "GND")
			(pintype "passive")
			(solder_mask_margin 0.075)
		)
		(pad "M4" smd circle
			(at -9.5 -1.5 90)
			(size 0.5 0.5)
			(layers "F.Cu" "F.Mask" "F.Paste")
			(net 1 "GND")
			(pinfunction "GND")
			(pintype "passive")
			(solder_mask_margin 0.075)
		)
		(pad "M5" smd circle
			(at -8.5 -1.5 90)
			(size 0.5 0.5)
			(layers "F.Cu" "F.Mask" "F.Paste")
			(net 172 "+1V2_MGTAVTT")
			(pinfunction "MGTAVTT_R")
			(pintype "passive")
			(solder_mask_margin 0.075)
		)
		(pad "M6" smd circle
			(at -7.5 -1.5 90)
			(size 0.5 0.5)
			(layers "F.Cu" "F.Mask" "F.Paste")
			(net 291 "/FPGA MGT Interface/HDMI_IN_CLK_C_N")
			(pinfunction "MGTREFCLK1N_226")
			(pintype "input")
			(die_length 5.554)
			(solder_mask_margin 0.075)
		)
		(pad "M7" smd circle
			(at -6.5 -1.5 90)
			(size 0.5 0.5)
			(layers "F.Cu" "F.Mask" "F.Paste")
			(net 268 "/FPGA MGT Interface/HDMI_IN_CLK_C_P")
			(pinfunction "MGTREFCLK1P_226")
			(pintype "input")
			(die_length 5.516)
			(solder_mask_margin 0.075)
		)
		(pad "M8" smd circle
			(at -5.5 -1.5 90)
			(size 0.5 0.5)
			(layers "F.Cu" "F.Mask" "F.Paste")
			(net 1 "GND")
			(pinfunction "GND")
			(pintype "passive")
			(solder_mask_margin 0.075)
		)
		(pad "M9" smd circle
			(at -4.5 -1.5 90)
			(size 0.5 0.5)
			(layers "F.Cu" "F.Mask" "F.Paste")
			(net 553 "+0V85")
			(pinfunction "VCCINT_IO")
			(pintype "passive")
			(solder_mask_margin 0.075)
		)
		(pad "M10" smd circle
			(at -3.5 -1.5 90)
			(size 0.5 0.5)
			(layers "F.Cu" "F.Mask" "F.Paste")
			(net 1 "GND")
			(pinfunction "GND")
			(pintype "passive")
			(solder_mask_margin 0.075)
		)
		(pad "M11" smd circle
			(at -2.5 -1.5 90)
			(size 0.5 0.5)
			(layers "F.Cu" "F.Mask" "F.Paste")
			(net 553 "+0V85")
			(pinfunction "VCCINT")
			(pintype "passive")
			(solder_mask_margin 0.075)
		)
		(pad "M12" smd circle
			(at -1.5 -1.5 90)
			(size 0.5 0.5)
			(layers "F.Cu" "F.Mask" "F.Paste")
			(net 1 "GND")
			(pinfunction "GND")
			(pintype "passive")
			(solder_mask_margin 0.075)
		)
		(pad "M13" smd circle
			(at -0.5 -1.5 90)
			(size 0.5 0.5)
			(layers "F.Cu" "F.Mask" "F.Paste")
			(net 553 "+0V85")
			(pinfunction "VCCINT")
			(pintype "passive")
			(solder_mask_margin 0.075)
		)
		(pad "M14" smd circle
			(at 0.5 -1.5 90)
			(size 0.5 0.5)
			(layers "F.Cu" "F.Mask" "F.Paste")
			(net 1 "GND")
			(pinfunction "GND")
			(pintype "passive")
			(solder_mask_margin 0.075)
		)
		(pad "M15" smd circle
			(at 1.5 -1.5 90)
			(size 0.5 0.5)
			(layers "F.Cu" "F.Mask" "F.Paste")
			(net 553 "+0V85")
			(pinfunction "VCCINT")
			(pintype "passive")
			(solder_mask_margin 0.075)
		)
		(pad "M16" smd circle
			(at 2.5 -1.5 90)
			(size 0.5 0.5)
			(layers "F.Cu" "F.Mask" "F.Paste")
			(net 1 "GND")
			(pinfunction "GND")
			(pintype "passive")
			(solder_mask_margin 0.075)
		)
		(pad "M17" smd circle
			(at 3.5 -1.5 90)
			(size 0.5 0.5)
			(layers "F.Cu" "F.Mask" "F.Paste")
			(net 553 "+0V85")
			(pinfunction "VCCINT")
			(pintype "passive")
			(solder_mask_margin 0.075)
		)
		(pad "M18" smd circle
			(at 4.5 -1.5 90)
			(size 0.5 0.5)
			(layers "F.Cu" "F.Mask" "F.Paste")
			(net 797 "+1V8")
			(pinfunction "VCCAUX")
			(pintype "power_in")
			(solder_mask_margin 0.075)
		)
		(pad "M19" smd circle
			(at 5.5 -1.5 90)
			(size 0.5 0.5)
			(layers "F.Cu" "F.Mask" "F.Paste")
			(net 474 "/DDR5 RDIMM/B.DQS5_P")
			(pinfunction "IO_L4P_T0U_N6_DBC_AD7P_66")
			(pintype "bidirectional")
			(die_length 15.54)
			(solder_mask_margin 0.075)
		)
		(pad "M20" smd circle
			(at 6.5 -1.5 90)
			(size 0.5 0.5)
			(layers "F.Cu" "F.Mask" "F.Paste")
			(net 107 "/DDR5 RDIMM/B.DQ1")
			(pinfunction "IO_L2P_T0L_N2_66")
			(pintype "bidirectional")
			(die_length 15.56)
			(solder_mask_margin 0.075)
		)
		(pad "M21" smd circle
			(at 7.5 -1.5 90)
			(size 0.5 0.5)
			(layers "F.Cu" "F.Mask" "F.Paste")
			(net 106 "/DDR5 RDIMM/B.DQ0")
			(pinfunction "IO_L2N_T0L_N3_66")
			(pintype "bidirectional")
			(die_length 16.141)
			(solder_mask_margin 0.075)
		)
		(pad "M22" smd circle
			(at 8.5 -1.5 90)
			(size 0.5 0.5)
			(layers "F.Cu" "F.Mask" "F.Paste")
			(net 600 "/FPGA banks HP/VRP_66")
			(pinfunction "IO_T0U_N12_VRP_66")
			(pintype "bidirectional")
			(die_length 15.559)
			(solder_mask_margin 0.075)
		)
		(pad "M23" smd circle
			(at 9.5 -1.5 90)
			(size 0.5 0.5)
			(layers "F.Cu" "F.Mask" "F.Paste")
			(net 1 "GND")
			(pinfunction "GND")
			(pintype "passive")
			(solder_mask_margin 0.075)
		)
		(pad "M24" smd circle
			(at 10.5 -1.5 90)
			(size 0.5 0.5)
			(layers "F.Cu" "F.Mask" "F.Paste")
			(net 556 "unconnected-(U34D-IO_T1U_N12_66-PadM24)")
			(pinfunction "IO_T1U_N12_66")
			(pintype "bidirectional+no_connect")
			(die_length 9.663)
			(solder_mask_margin 0.075)
		)
		(pad "M25" smd circle
			(at 11.5 -1.5 90)
			(size 0.5 0.5)
			(layers "F.Cu" "F.Mask" "F.Paste")
			(net 113 "/DDR5 RDIMM/B.DQ9")
			(pinfunction "IO_L8P_T1L_N2_AD5P_66")
			(pintype "bidirectional")
			(die_length 12.154)
			(solder_mask_margin 0.075)
		)
		(pad "M26" smd circle
			(at 12.5 -1.5 90)
			(size 0.5 0.5)
			(layers "F.Cu" "F.Mask" "F.Paste")
			(net 112 "/DDR5 RDIMM/B.DQ8")
			(pinfunction "IO_L8N_T1L_N3_AD5N_66")
			(pintype "bidirectional")
			(die_length 12.064)
			(solder_mask_margin 0.075)
		)
		(pad "N1" smd circle
			(at -12.5 -0.5 90)
			(size 0.5 0.5)
			(layers "F.Cu" "F.Mask" "F.Paste")
			(net 1 "GND")
			(pinfunction "GND")
			(pintype "passive")
			(solder_mask_margin 0.075)
		)
		(pad "N2" smd circle
			(at -11.5 -0.5 90)
			(size 0.5 0.5)
			(layers "F.Cu" "F.Mask" "F.Paste")
			(net 1 "GND")
			(pinfunction "GND")
			(pintype "passive")
			(solder_mask_margin 0.075)
		)
		(pad "N3" smd circle
			(at -10.5 -0.5 90)
			(size 0.5 0.5)
			(layers "F.Cu" "F.Mask" "F.Paste")
			(net 1 "GND")
			(pinfunction "GND")
			(pintype "passive")
			(solder_mask_margin 0.075)
		)
		(pad "N4" smd circle
			(at -9.5 -0.5 90)
			(size 0.5 0.5)
			(layers "F.Cu" "F.Mask" "F.Paste")
			(net 631 "/FPGA MGT Interface/HDMI_FPGA.TX0_N")
			(pinfunction "MGTYTXN0_226")
			(pintype "output")
			(die_length 7.485)
			(solder_mask_margin 0.075)
		)
		(pad "N5" smd circle
			(at -8.5 -0.5 90)
			(size 0.5 0.5)
			(layers "F.Cu" "F.Mask" "F.Paste")
			(net 632 "/FPGA MGT Interface/HDMI_FPGA.TX0_P")
			(pinfunction "MGTYTXP0_226")
			(pintype "output")
			(die_length 7.498)
			(solder_mask_margin 0.075)
		)
		(pad "N6" smd circle
			(at -7.5 -0.5 90)
			(size 0.5 0.5)
			(layers "F.Cu" "F.Mask" "F.Paste")
			(net 1 "GND")
			(pinfunction "GND")
			(pintype "passive")
			(solder_mask_margin 0.075)
		)
		(pad "N7" smd circle
			(at -6.5 -0.5 90)
			(size 0.5 0.5)
			(layers "F.Cu" "F.Mask" "F.Paste")
			(net 820 "+0V9_MGTAVCC")
			(pinfunction "MGTAVCC_R")
			(pintype "passive")
			(solder_mask_margin 0.075)
		)
		(pad "N8" smd circle
			(at -5.5 -0.5 90)
			(size 0.5 0.5)
			(layers "F.Cu" "F.Mask" "F.Paste")
			(net 1 "GND")
			(pinfunction "GND")
			(pintype "passive")
			(solder_mask_margin 0.075)
		)
		(pad "N9" smd circle
			(at -4.5 -0.5 90)
			(size 0.5 0.5)
			(layers "F.Cu" "F.Mask" "F.Paste")
			(net 553 "+0V85")
			(pinfunction "VCCINT_IO")
			(pintype "passive")
			(solder_mask_margin 0.075)
		)
		(pad "N10" smd circle
			(at -3.5 -0.5 90)
			(size 0.5 0.5)
			(layers "F.Cu" "F.Mask" "F.Paste")
			(net 553 "+0V85")
			(pinfunction "VCCINT")
			(pintype "passive")
			(solder_mask_margin 0.075)
		)
		(pad "N11" smd circle
			(at -2.5 -0.5 90)
			(size 0.5 0.5)
			(layers "F.Cu" "F.Mask" "F.Paste")
			(net 1 "GND")
			(pinfunction "GND")
			(pintype "passive")
			(solder_mask_margin 0.075)
		)
		(pad "N12" smd circle
			(at -1.5 -0.5 90)
			(size 0.5 0.5)
			(layers "F.Cu" "F.Mask" "F.Paste")
			(net 553 "+0V85")
			(pinfunction "VCCINT")
			(pintype "passive")
			(solder_mask_margin 0.075)
		)
		(pad "N13" smd circle
			(at -0.5 -0.5 90)
			(size 0.5 0.5)
			(layers "F.Cu" "F.Mask" "F.Paste")
			(net 1 "GND")
			(pinfunction "GNDADC")
			(pintype "input")
			(die_length 9.132)
			(solder_mask_margin 0.075)
		)
		(pad "N14" smd circle
			(at 0.5 -0.5 90)
			(size 0.5 0.5)
			(layers "F.Cu" "F.Mask" "F.Paste")
			(net 797 "+1V8")
			(pinfunction "VCCADC")
			(pintype "power_in")
			(die_length 9.369)
			(solder_mask_margin 0.075)
		)
		(pad "N15" smd circle
			(at 1.5 -0.5 90)
			(size 0.5 0.5)
			(layers "F.Cu" "F.Mask" "F.Paste")
			(net 1 "GND")
			(pinfunction "GND")
			(pintype "passive")
			(solder_mask_margin 0.075)
		)
		(pad "N16" smd circle
			(at 2.5 -0.5 90)
			(size 0.5 0.5)
			(layers "F.Cu" "F.Mask" "F.Paste")
			(net 553 "+0V85")
			(pinfunction "VCCINT")
			(pintype "passive")
			(solder_mask_margin 0.075)
		)
		(pad "N17" smd circle
			(at 3.5 -0.5 90)
			(size 0.5 0.5)
			(layers "F.Cu" "F.Mask" "F.Paste")
			(net 1 "GND")
			(pinfunction "GND")
			(pintype "passive")
			(solder_mask_margin 0.075)
		)
		(pad "N18" smd circle
			(at 4.5 -0.5 90)
			(size 0.5 0.5)
			(layers "F.Cu" "F.Mask" "F.Paste")
			(net 797 "+1V8")
			(pinfunction "VCCAUX")
			(pintype "passive")
			(solder_mask_margin 0.075)
		)
		(pad "N19" smd circle
			(at 5.5 -0.5 90)
			(size 0.5 0.5)
			(layers "F.Cu" "F.Mask" "F.Paste")
			(net 211 "/DDR5 RDIMM/B.CB3")
			(pinfunction "IO_L23P_T3U_N8_I2C_SCLK_65")
			(pintype "bidirectional")
			(die_length 10.827)
			(solder_mask_margin 0.075)
		)
		(pad "N20" smd circle
			(at 6.5 -0.5 90)
			(size 0.5 0.5)
			(layers "F.Cu" "F.Mask" "F.Paste")
			(net 1 "GND")
			(pinfunction "GND")
			(pintype "passive")
			(solder_mask_margin 0.075)
		)
		(pad "N21" smd circle
			(at 7.5 -0.5 90)
			(size 0.5 0.5)
			(layers "F.Cu" "F.Mask" "F.Paste")
			(net 105 "/DDR5 RDIMM/B.CB1")
			(pinfunction "IO_L24P_T3U_N10_EMCCLK_65")
			(pintype "bidirectional")
			(die_length 10.865)
			(solder_mask_margin 0.075)
		)
		(pad "N22" smd circle
			(at 8.5 -0.5 90)
			(size 0.5 0.5)
			(layers "F.Cu" "F.Mask" "F.Paste")
			(net 210 "/DDR5 RDIMM/B.CB2")
			(pinfunction "IO_L24N_T3U_N11_DOUT_CSO_B_65")
			(pintype "bidirectional")
			(die_length 10.705)
			(solder_mask_margin 0.075)
		)
		(pad "N23" smd circle
			(at 9.5 -0.5 90)
			(size 0.5 0.5)
			(layers "F.Cu" "F.Mask" "F.Paste")
			(net 452 "/DDR5 RDIMM/B.DQS4_P")
			(pinfunction "IO_L22P_T3U_N6_DBC_AD0P_D04_65")
			(pintype "bidirectional")
			(die_length 10.749)
			(solder_mask_margin 0.075)
		)
		(pad "N24" smd circle
			(at 10.5 -0.5 90)
			(size 0.5 0.5)
			(layers "F.Cu" "F.Mask" "F.Paste")
			(net 82 "/DDR5 RDIMM/B.CA6")
			(pinfunction "IO_L15P_T2L_N4_AD11P_A02_D18_65")
			(pintype "bidirectional")
			(die_length 12.454)
			(solder_mask_margin 0.075)
		)
		(pad "N25" smd circle
			(at 11.5 -0.5 90)
			(size 0.5 0.5)
			(layers "F.Cu" "F.Mask" "F.Paste")
			(net 1 "GND")
			(pinfunction "GND")
			(pintype "passive")
			(solder_mask_margin 0.075)
		)
		(pad "N26" smd circle
			(at 12.5 -0.5 90)
			(size 0.5 0.5)
			(layers "F.Cu" "F.Mask" "F.Paste")
			(net 602 "/DDR5 RDIMM/CTRL.PWR_GOOD")
			(pinfunction "IO_T2U_N12_CSI_ADV_B_65")
			(pintype "bidirectional")
			(die_length 11.605)
			(solder_mask_margin 0.075)
		)
		(pad "P1" smd circle
			(at -12.5 0.5 90)
			(size 0.5 0.5)
			(layers "F.Cu" "F.Mask" "F.Paste")
			(net 333 "/FPGA MGT Interface/PCIE.RXD0_N")
			(pinfunction "MGTYRXN3_225")
			(pintype "input")
			(die_length 9.421)
			(solder_mask_margin 0.075)
		)
		(pad "P2" smd circle
			(at -11.5 0.5 90)
			(size 0.5 0.5)
			(layers "F.Cu" "F.Mask" "F.Paste")
			(net 332 "/FPGA MGT Interface/PCIE.RXD0_P")
			(pinfunction "MGTYRXP3_225")
			(pintype "input")
			(die_length 9.419)
			(solder_mask_margin 0.075)
		)
		(pad "P3" smd circle
			(at -10.5 0.5 90)
			(size 0.5 0.5)
			(layers "F.Cu" "F.Mask" "F.Paste")
			(net 1 "GND")
			(pinfunction "GND")
			(pintype "passive")
			(solder_mask_margin 0.075)
		)
		(pad "P4" smd circle
			(at -9.5 0.5 90)
			(size 0.5 0.5)
			(layers "F.Cu" "F.Mask" "F.Paste")
			(net 1 "GND")
			(pinfunction "GND")
			(pintype "passive")
			(solder_mask_margin 0.075)
		)
		(pad "P5" smd circle
			(at -8.5 0.5 90)
			(size 0.5 0.5)
			(layers "F.Cu" "F.Mask" "F.Paste")
			(net 172 "+1V2_MGTAVTT")
			(pinfunction "MGTAVTT_R")
			(pintype "passive")
			(solder_mask_margin 0.075)
		)
		(pad "P6" smd circle
			(at -7.5 0.5 90)
			(size 0.5 0.5)
			(layers "F.Cu" "F.Mask" "F.Paste")
			(net 387 "/FPGA MGT Interface/HDMI_SI5319_CLK_N")
			(pinfunction "MGTREFCLK0N_226")
			(pintype "input")
			(die_length 6.1)
			(solder_mask_margin 0.075)
		)
		(pad "P7" smd circle
			(at -6.5 0.5 90)
			(size 0.5 0.5)
			(layers "F.Cu" "F.Mask" "F.Paste")
			(net 402 "/FPGA MGT Interface/HDMI_SI5319_CLK_P")
			(pinfunction "MGTREFCLK0P_226")
			(pintype "input")
			(die_length 6.016)
			(solder_mask_margin 0.075)
		)
		(pad "P8" smd circle
			(at -5.5 0.5 90)
			(size 0.5 0.5)
			(layers "F.Cu" "F.Mask" "F.Paste")
			(net 1 "GND")
			(pinfunction "GND")
			(pintype "passive")
			(solder_mask_margin 0.075)
		)
		(pad "P9" smd circle
			(at -4.5 0.5 90)
			(size 0.5 0.5)
			(layers "F.Cu" "F.Mask" "F.Paste")
			(net 553 "+0V85")
			(pinfunction "VCCINT_IO")
			(pintype "passive")
			(solder_mask_margin 0.075)
		)
		(pad "P10" smd circle
			(at -3.5 0.5 90)
			(size 0.5 0.5)
			(layers "F.Cu" "F.Mask" "F.Paste")
			(net 1 "GND")
			(pinfunction "GND")
			(pintype "passive")
			(solder_mask_margin 0.075)
		)
		(pad "P11" smd circle
			(at -2.5 0.5 90)
			(size 0.5 0.5)
			(layers "F.Cu" "F.Mask" "F.Paste")
			(net 553 "+0V85")
			(pinfunction "VCCINT")
			(pintype "passive")
			(solder_mask_margin 0.075)
		)
		(pad "P12" smd circle
			(at -1.5 0.5 90)
			(size 0.5 0.5)
			(layers "F.Cu" "F.Mask" "F.Paste")
			(net 1 "GND")
			(pinfunction "GND")
			(pintype "passive")
			(solder_mask_margin 0.075)
		)
		(pad "P13" smd circle
			(at -0.5 0.5 90)
			(size 0.5 0.5)
			(layers "F.Cu" "F.Mask" "F.Paste")
			(net 598 "/FPGA Config/VREFN")
			(pinfunction "VREFN")
			(pintype "input")
			(die_length 9.331)
			(solder_mask_margin 0.075)
		)
		(pad "P14" smd circle
			(at 0.5 0.5 90)
			(size 0.5 0.5)
			(layers "F.Cu" "F.Mask" "F.Paste")
			(net 1 "GND")
			(pinfunction "VP")
			(pintype "input")
			(die_length 10.149)
			(solder_mask_margin 0.075)
		)
		(pad "P15" smd circle
			(at 1.5 0.5 90)
			(size 0.5 0.5)
			(layers "F.Cu" "F.Mask" "F.Paste")
			(net 553 "+0V85")
			(pinfunction "VCCINT")
			(pintype "passive")
			(solder_mask_margin 0.075)
		)
		(pad "P16" smd circle
			(at 2.5 0.5 90)
			(size 0.5 0.5)
			(layers "F.Cu" "F.Mask" "F.Paste")
			(net 1 "GND")
			(pinfunction "GND")
			(pintype "passive")
			(solder_mask_margin 0.075)
		)
		(pad "P17" smd circle
			(at 3.5 0.5 90)
			(size 0.5 0.5)
			(layers "F.Cu" "F.Mask" "F.Paste")
			(net 553 "+0V85")
			(pinfunction "VCCINT")
			(pintype "passive")
			(solder_mask_margin 0.075)
		)
		(pad "P18" smd circle
			(at 4.5 0.5 90)
			(size 0.5 0.5)
			(layers "F.Cu" "F.Mask" "F.Paste")
			(net 797 "+1V8")
			(pinfunction "VCCAUX_IO")
			(pintype "power_in")
			(solder_mask_margin 0.075)
		)
		(pad "P19" smd circle
			(at 5.5 0.5 90)
			(size 0.5 0.5)
			(layers "F.Cu" "F.Mask" "F.Paste")
			(net 103 "/DDR5 RDIMM/B.CB0")
			(pinfunction "IO_L23N_T3U_N9_PERSTN1_I2C_SDA_65")
			(pintype "bidirectional")
			(die_length 11.001)
			(solder_mask_margin 0.075)
		)
		(pad "P20" smd circle
			(at 6.5 0.5 90)
			(size 0.5 0.5)
			(layers "F.Cu" "F.Mask" "F.Paste")
			(net 99 "/DDR5 RDIMM/B.CB4")
			(pinfunction "IO_L20P_T3L_N2_AD1P_D08_65")
			(pintype "bidirectional")
			(die_length 10.644)
			(solder_mask_margin 0.075)
		)
		(pad "P21" smd circle
			(at 7.5 0.5 90)
			(size 0.5 0.5)
			(layers "F.Cu" "F.Mask" "F.Paste")
			(net 205 "/DDR5 RDIMM/B.CB7")
			(pinfunction "IO_L20N_T3L_N3_AD1N_D09_65")
			(pintype "bidirectional")
			(die_length 10.758)
			(solder_mask_margin 0.075)
		)
		(pad "P22" smd circle
			(at 8.5 0.5 90)
			(size 0.5 0.5)
			(layers "F.Cu" "F.Mask" "F.Paste")
			(net 687 "VDDQ")
			(pinfunction "VCCO_65")
			(pintype "power_in")
			(solder_mask_margin 0.075)
		)
		(pad "P23" smd circle
			(at 9.5 0.5 90)
			(size 0.5 0.5)
			(layers "F.Cu" "F.Mask" "F.Paste")
			(net 451 "/DDR5 RDIMM/B.DQS4_N")
			(pinfunction "IO_L22N_T3U_N7_DBC_AD0N_D05_65")
			(pintype "bidirectional")
			(die_length 10.717)
			(solder_mask_margin 0.075)
		)
		(pad "P24" smd circle
			(at 10.5 0.5 90)
			(size 0.5 0.5)
			(layers "F.Cu" "F.Mask" "F.Paste")
			(net 200 "/DDR5 RDIMM/B.CA5")
			(pinfunction "IO_L15N_T2L_N5_AD11N_A03_D19_65")
			(pintype "bidirectional")
			(die_length 11.277)
			(solder_mask_margin 0.075)
		)
		(pad "P25" smd circle
			(at 11.5 0.5 90)
			(size 0.5 0.5)
			(layers "F.Cu" "F.Mask" "F.Paste")
			(net 81 "/DDR5 RDIMM/B.CA4")
			(pinfunction "IO_L17P_T2U_N8_AD10P_D14_65")
			(pintype "bidirectional")
			(die_length 11.308)
			(solder_mask_margin 0.075)
		)
		(pad "P26" smd circle
			(at 12.5 0.5 90)
			(size 0.5 0.5)
			(layers "F.Cu" "F.Mask" "F.Paste")
			(net 199 "/DDR5 RDIMM/B.CA3")
			(pinfunction "IO_L17N_T2U_N9_AD10N_D15_65")
			(pintype "bidirectional")
			(die_length 11.915)
			(solder_mask_margin 0.075)
		)
		(pad "R1" smd circle
			(at -12.5 1.5 90)
			(size 0.5 0.5)
			(layers "F.Cu" "F.Mask" "F.Paste")
			(net 1 "GND")
			(pinfunction "GND")
			(pintype "passive")
			(solder_mask_margin 0.075)
		)
		(pad "R2" smd circle
			(at -11.5 1.5 90)
			(size 0.5 0.5)
			(layers "F.Cu" "F.Mask" "F.Paste")
			(net 1 "GND")
			(pinfunction "GND")
			(pintype "passive")
			(solder_mask_margin 0.075)
		)
		(pad "R3" smd circle
			(at -10.5 1.5 90)
			(size 0.5 0.5)
			(layers "F.Cu" "F.Mask" "F.Paste")
			(net 1 "GND")
			(pinfunction "GND")
			(pintype "passive")
			(solder_mask_margin 0.075)
		)
		(pad "R4" smd circle
			(at -9.5 1.5 90)
			(size 0.5 0.5)
			(layers "F.Cu" "F.Mask" "F.Paste")
			(net 28 "/FPGA MGT Interface/GTY_225_TX3_N")
			(pinfunction "MGTYTXN3_225")
			(pintype "output")
			(die_length 7.973)
			(solder_mask_margin 0.075)
		)
		(pad "R5" smd circle
			(at -8.5 1.5 90)
			(size 0.5 0.5)
			(layers "F.Cu" "F.Mask" "F.Paste")
			(net 22 "/FPGA MGT Interface/GTY_225_TX3_P")
			(pinfunction "MGTYTXP3_225")
			(pintype "output")
			(die_length 7.991)
			(solder_mask_margin 0.075)
		)
		(pad "R6" smd circle
			(at -7.5 1.5 90)
			(size 0.5 0.5)
			(layers "F.Cu" "F.Mask" "F.Paste")
			(net 1 "GND")
			(pinfunction "GND")
			(pintype "passive")
			(solder_mask_margin 0.075)
		)
		(pad "R7" smd circle
			(at -6.5 1.5 90)
			(size 0.5 0.5)
			(layers "F.Cu" "F.Mask" "F.Paste")
			(net 573 "+1V8_MGTVCCAUX")
			(pinfunction "MGTVCCAUX_R")
			(pintype "power_in")
			(solder_mask_margin 0.075)
		)
		(pad "R8" smd circle
			(at -5.5 1.5 90)
			(size 0.5 0.5)
			(layers "F.Cu" "F.Mask" "F.Paste")
			(net 1 "GND")
			(pinfunction "GND")
			(pintype "passive")
			(solder_mask_margin 0.075)
		)
		(pad "R9" smd circle
			(at -4.5 1.5 90)
			(size 0.5 0.5)
			(layers "F.Cu" "F.Mask" "F.Paste")
			(net 553 "+0V85")
			(pinfunction "VCCBRAM")
			(pintype "power_in")
			(solder_mask_margin 0.075)
		)
		(pad "R10" smd circle
			(at -3.5 1.5 90)
			(size 0.5 0.5)
			(layers "F.Cu" "F.Mask" "F.Paste")
			(net 553 "+0V85")
			(pinfunction "VCCINT")
			(pintype "passive")
			(solder_mask_margin 0.075)
		)
		(pad "R11" smd circle
			(at -2.5 1.5 90)
			(size 0.5 0.5)
			(layers "F.Cu" "F.Mask" "F.Paste")
			(net 1 "GND")
			(pinfunction "GND")
			(pintype "passive")
			(solder_mask_margin 0.075)
		)
		(pad "R12" smd circle
			(at -1.5 1.5 90)
			(size 0.5 0.5)
			(layers "F.Cu" "F.Mask" "F.Paste")
			(net 553 "+0V85")
			(pinfunction "VCCINT")
			(pintype "passive")
			(solder_mask_margin 0.075)
		)
		(pad "R13" smd circle
			(at -0.5 1.5 90)
			(size 0.5 0.5)
			(layers "F.Cu" "F.Mask" "F.Paste")
			(net 1 "GND")
			(pinfunction "VN")
			(pintype "input")
			(die_length 10.19)
			(solder_mask_margin 0.075)
		)
		(pad "R14" smd circle
			(at 0.5 1.5 90)
			(size 0.5 0.5)
			(layers "F.Cu" "F.Mask" "F.Paste")
			(net 599 "/FPGA Config/VREFP")
			(pinfunction "VREFP")
			(pintype "input")
			(die_length 12.277)
			(solder_mask_margin 0.075)
		)
		(pad "R15" smd circle
			(at 1.5 1.5 90)
			(size 0.5 0.5)
			(layers "F.Cu" "F.Mask" "F.Paste")
			(net 1 "GND")
			(pinfunction "GND")
			(pintype "passive")
			(solder_mask_margin 0.075)
		)
		(pad "R16" smd circle
			(at 2.5 1.5 90)
			(size 0.5 0.5)
			(layers "F.Cu" "F.Mask" "F.Paste")
			(net 553 "+0V85")
			(pinfunction "VCCINT")
			(pintype "passive")
			(solder_mask_margin 0.075)
		)
		(pad "R17" smd circle
			(at 3.5 1.5 90)
			(size 0.5 0.5)
			(layers "F.Cu" "F.Mask" "F.Paste")
			(net 1 "GND")
			(pinfunction "GND")
			(pintype "passive")
			(solder_mask_margin 0.075)
		)
		(pad "R18" smd circle
			(at 4.5 1.5 90)
			(size 0.5 0.5)
			(layers "F.Cu" "F.Mask" "F.Paste")
			(net 797 "+1V8")
			(pinfunction "VCCAUX_IO")
			(pintype "passive")
			(solder_mask_margin 0.075)
		)
		(pad "R19" smd circle
			(at 5.5 1.5 90)
			(size 0.5 0.5)
			(layers "F.Cu" "F.Mask" "F.Paste")
			(net 1 "GND")
			(pinfunction "GND")
			(pintype "passive")
			(solder_mask_margin 0.075)
		)
		(pad "R20" smd circle
			(at 6.5 1.5 90)
			(size 0.5 0.5)
			(layers "F.Cu" "F.Mask" "F.Paste")
			(net 204 "/DDR5 RDIMM/B.CB6")
			(pinfunction "IO_L21P_T3L_N4_AD8P_D06_65")
			(pintype "bidirectional")
			(die_length 14.707)
			(solder_mask_margin 0.075)
		)
		(pad "R21" smd circle
			(at 7.5 1.5 90)
			(size 0.5 0.5)
			(layers "F.Cu" "F.Mask" "F.Paste")
			(net 100 "/DDR5 RDIMM/B.CB5")
			(pinfunction "IO_L21N_T3L_N5_AD8N_D07_65")
			(pintype "bidirectional")
			(die_length 13.954)
			(solder_mask_margin 0.075)
		)
		(pad "R22" smd circle
			(at 8.5 1.5 90)
			(size 0.5 0.5)
			(layers "F.Cu" "F.Mask" "F.Paste")
			(net 126 "/DDR5 RDIMM/B.DQS9_P")
			(pinfunction "IO_L19P_T3L_N0_DBC_AD9P_D10_65")
			(pintype "bidirectional")
			(die_length 10.97)
			(solder_mask_margin 0.075)
		)
		(pad "R23" smd circle
			(at 9.5 1.5 90)
			(size 0.5 0.5)
			(layers "F.Cu" "F.Mask" "F.Paste")
			(net 127 "/DDR5 RDIMM/B.DQS9_N")
			(pinfunction "IO_L19N_T3L_N1_DBC_AD9N_D11_65")
			(pintype "bidirectional")
			(die_length 10.922)
			(solder_mask_margin 0.075)
		)
		(pad "R24" smd circle
			(at 10.5 1.5 90)
			(size 0.5 0.5)
			(layers "F.Cu" "F.Mask" "F.Paste")
			(net 1 "GND")
			(pinfunction "GND")
			(pintype "passive")
			(solder_mask_margin 0.075)
		)
		(pad "R25" smd circle
			(at 11.5 1.5 90)
			(size 0.5 0.5)
			(layers "F.Cu" "F.Mask" "F.Paste")
			(net 80 "/DDR5 RDIMM/B.CA1")
			(pinfunction "IO_L18P_T2U_N10_AD2P_D12_65")
			(pintype "bidirectional")
			(die_length 11.555)
			(solder_mask_margin 0.075)
		)
		(pad "R26" smd circle
			(at 12.5 1.5 90)
			(size 0.5 0.5)
			(layers "F.Cu" "F.Mask" "F.Paste")
			(net 202 "/DDR5 RDIMM/B.PAR")
			(pinfunction "IO_L18N_T2U_N11_AD2N_D13_65")
			(pintype "bidirectional")
			(die_length 11.586)
			(solder_mask_margin 0.075)
		)
		(pad "T1" smd circle
			(at -12.5 2.5 90)
			(size 0.5 0.5)
			(layers "F.Cu" "F.Mask" "F.Paste")
			(net 335 "/FPGA MGT Interface/PCIE.RXD1_N")
			(pinfunction "MGTYRXN2_225")
			(pintype "input")
			(die_length 9.796)
			(solder_mask_margin 0.075)
		)
		(pad "T2" smd circle
			(at -11.5 2.5 90)
			(size 0.5 0.5)
			(layers "F.Cu" "F.Mask" "F.Paste")
			(net 334 "/FPGA MGT Interface/PCIE.RXD1_P")
			(pinfunction "MGTYRXP2_225")
			(pintype "input")
			(die_length 9.777)
			(solder_mask_margin 0.075)
		)
		(pad "T3" smd circle
			(at -10.5 2.5 90)
			(size 0.5 0.5)
			(layers "F.Cu" "F.Mask" "F.Paste")
			(net 1 "GND")
			(pinfunction "GND")
			(pintype "passive")
			(solder_mask_margin 0.075)
		)
		(pad "T4" smd circle
			(at -9.5 2.5 90)
			(size 0.5 0.5)
			(layers "F.Cu" "F.Mask" "F.Paste")
			(net 1 "GND")
			(pinfunction "GND")
			(pintype "passive")
			(solder_mask_margin 0.075)
		)
		(pad "T5" smd circle
			(at -8.5 2.5 90)
			(size 0.5 0.5)
			(layers "F.Cu" "F.Mask" "F.Paste")
			(net 172 "+1V2_MGTAVTT")
			(pinfunction "MGTAVTT_R")
			(pintype "passive")
			(solder_mask_margin 0.075)
		)
		(pad "T6" smd circle
			(at -7.5 2.5 90)
			(size 0.5 0.5)
			(layers "F.Cu" "F.Mask" "F.Paste")
			(net 560 "unconnected-(U34J-MGTREFCLK1N_225-PadT6)")
			(pinfunction "MGTREFCLK1N_225")
			(pintype "input+no_connect")
			(die_length 6.993)
			(solder_mask_margin 0.075)
		)
		(pad "T7" smd circle
			(at -6.5 2.5 90)
			(size 0.5 0.5)
			(layers "F.Cu" "F.Mask" "F.Paste")
			(net 561 "unconnected-(U34J-MGTREFCLK1P_225-PadT7)")
			(pinfunction "MGTREFCLK1P_225")
			(pintype "input+no_connect")
			(die_length 6.98)
			(solder_mask_margin 0.075)
		)
		(pad "T8" smd circle
			(at -5.5 2.5 90)
			(size 0.5 0.5)
			(layers "F.Cu" "F.Mask" "F.Paste")
			(net 1 "GND")
			(pinfunction "GND")
			(pintype "passive")
			(solder_mask_margin 0.075)
		)
		(pad "T9" smd circle
			(at -4.5 2.5 90)
			(size 0.5 0.5)
			(layers "F.Cu" "F.Mask" "F.Paste")
			(net 553 "+0V85")
			(pinfunction "VCCBRAM")
			(pintype "passive")
			(solder_mask_margin 0.075)
		)
		(pad "T10" smd circle
			(at -3.5 2.5 90)
			(size 0.5 0.5)
			(layers "F.Cu" "F.Mask" "F.Paste")
			(net 1 "GND")
			(pinfunction "GND")
			(pintype "passive")
			(solder_mask_margin 0.075)
		)
		(pad "T11" smd circle
			(at -2.5 2.5 90)
			(size 0.5 0.5)
			(layers "F.Cu" "F.Mask" "F.Paste")
			(net 553 "+0V85")
			(pinfunction "VCCINT")
			(pintype "passive")
			(solder_mask_margin 0.075)
		)
		(pad "T12" smd circle
			(at -1.5 2.5 90)
			(size 0.5 0.5)
			(layers "F.Cu" "F.Mask" "F.Paste")
			(net 1 "GND")
			(pinfunction "GND")
			(pintype "passive")
			(solder_mask_margin 0.075)
		)
		(pad "T13" smd circle
			(at -0.5 2.5 90)
			(size 0.5 0.5)
			(layers "F.Cu" "F.Mask" "F.Paste")
			(net 667 "/FPGA Config/DX_N")
			(pinfunction "DXN")
			(pintype "passive")
			(die_length 11.82)
			(solder_mask_margin 0.075)
		)
		(pad "T14" smd circle
			(at 0.5 2.5 90)
			(size 0.5 0.5)
			(layers "F.Cu" "F.Mask" "F.Paste")
			(net 668 "/FPGA Config/DX_P")
			(pinfunction "DXP")
			(pintype "passive")
			(die_length 12.714)
			(solder_mask_margin 0.075)
		)
		(pad "T15" smd circle
			(at 1.5 2.5 90)
			(size 0.5 0.5)
			(layers "F.Cu" "F.Mask" "F.Paste")
			(net 553 "+0V85")
			(pinfunction "VCCINT")
			(pintype "passive")
			(solder_mask_margin 0.075)
		)
		(pad "T16" smd circle
			(at 2.5 2.5 90)
			(size 0.5 0.5)
			(layers "F.Cu" "F.Mask" "F.Paste")
			(net 1 "GND")
			(pinfunction "GND")
			(pintype "passive")
			(solder_mask_margin 0.075)
		)
		(pad "T17" smd circle
			(at 3.5 2.5 90)
			(size 0.5 0.5)
			(layers "F.Cu" "F.Mask" "F.Paste")
			(net 553 "+0V85")
			(pinfunction "VCCINT")
			(pintype "passive")
			(solder_mask_margin 0.075)
		)
		(pad "T18" smd circle
			(at 4.5 2.5 90)
			(size 0.5 0.5)
			(layers "F.Cu" "F.Mask" "F.Paste")
			(net 797 "+1V8")
			(pinfunction "VCCAUX_IO")
			(pintype "passive")
			(solder_mask_margin 0.075)
		)
		(pad "T19" smd circle
			(at 5.5 2.5 90)
			(size 0.5 0.5)
			(layers "F.Cu" "F.Mask" "F.Paste")
			(net 190 "/DDR5 RDIMM/CTRL.~{RESET}")
			(pinfunction "IO_T3U_N12_PERSTN0_65")
			(pintype "bidirectional")
			(die_length 14.756)
			(solder_mask_margin 0.075)
		)
		(pad "T20" smd circle
			(at 6.5 2.5 90)
			(size 0.5 0.5)
			(layers "F.Cu" "F.Mask" "F.Paste")
			(net 171 "/DDR5 RDIMM/A.CB2")
			(pinfunction "IO_L3P_T0L_N4_AD15P_A26_65")
			(pintype "bidirectional")
			(die_length 11.445)
			(solder_mask_margin 0.075)
		)
		(pad "T21" smd circle
			(at 7.5 2.5 90)
			(size 0.5 0.5)
			(layers "F.Cu" "F.Mask" "F.Paste")
			(net 1 "GND")
			(pinfunction "GND")
			(pintype "passive")
			(solder_mask_margin 0.075)
		)
		(pad "T22" smd circle
			(at 8.5 2.5 90)
			(size 0.5 0.5)
			(layers "F.Cu" "F.Mask" "F.Paste")
			(net 186 "/DDR5 RDIMM/A.CB6")
			(pinfunction "IO_L5P_T0U_N8_AD14P_A22_65")
			(pintype "bidirectional")
			(die_length 9.497)
			(solder_mask_margin 0.075)
		)
		(pad "T23" smd circle
			(at 9.5 2.5 90)
			(size 0.5 0.5)
			(layers "F.Cu" "F.Mask" "F.Paste")
			(net 70 "/DDR5 RDIMM/A.CB4")
			(pinfunction "IO_L5N_T0U_N9_AD14N_A23_65")
			(pintype "bidirectional")
			(die_length 9.52)
			(solder_mask_margin 0.075)
		)
		(pad "T24" smd circle
			(at 10.5 2.5 90)
			(size 0.5 0.5)
			(layers "F.Cu" "F.Mask" "F.Paste")
			(net 83 "/DDR5 RDIMM/B.CS0_c")
			(pinfunction "IO_L13P_T2L_N0_GC_QBC_A06_D22_65")
			(pintype "bidirectional")
			(die_length 10.564)
			(solder_mask_margin 0.075)
		)
		(pad "T25" smd circle
			(at 11.5 2.5 90)
			(size 0.5 0.5)
			(layers "F.Cu" "F.Mask" "F.Paste")
			(net 198 "/DDR5 RDIMM/B.CA2")
			(pinfunction "IO_L14P_T2L_N2_GC_A04_D20_65")
			(pintype "bidirectional")
			(die_length 11.424)
			(solder_mask_margin 0.075)
		)
		(pad "T26" smd circle
			(at 12.5 2.5 90)
			(size 0.5 0.5)
			(layers "F.Cu" "F.Mask" "F.Paste")
			(net 1 "GND")
			(pinfunction "GND")
			(pintype "passive")
			(solder_mask_margin 0.075)
		)
		(pad "U1" smd circle
			(at -12.5 3.5 90)
			(size 0.5 0.5)
			(layers "F.Cu" "F.Mask" "F.Paste")
			(net 1 "GND")
			(pinfunction "GND")
			(pintype "passive")
			(solder_mask_margin 0.075)
		)
		(pad "U2" smd circle
			(at -11.5 3.5 90)
			(size 0.5 0.5)
			(layers "F.Cu" "F.Mask" "F.Paste")
			(net 1 "GND")
			(pinfunction "GND")
			(pintype "passive")
			(solder_mask_margin 0.075)
		)
		(pad "U3" smd circle
			(at -10.5 3.5 90)
			(size 0.5 0.5)
			(layers "F.Cu" "F.Mask" "F.Paste")
			(net 1 "GND")
			(pinfunction "GND")
			(pintype "passive")
			(solder_mask_margin 0.075)
		)
		(pad "U4" smd circle
			(at -9.5 3.5 90)
			(size 0.5 0.5)
			(layers "F.Cu" "F.Mask" "F.Paste")
			(net 29 "/FPGA MGT Interface/GTY_225_TX2_N")
			(pinfunction "MGTYTXN2_225")
			(pintype "output")
			(die_length 8.698)
			(solder_mask_margin 0.075)
		)
		(pad "U5" smd circle
			(at -8.5 3.5 90)
			(size 0.5 0.5)
			(layers "F.Cu" "F.Mask" "F.Paste")
			(net 20 "/FPGA MGT Interface/GTY_225_TX2_P")
			(pinfunction "MGTYTXP2_225")
			(pintype "output")
			(die_length 8.717)
			(solder_mask_margin 0.075)
		)
		(pad "U6" smd circle
			(at -7.5 3.5 90)
			(size 0.5 0.5)
			(layers "F.Cu" "F.Mask" "F.Paste")
			(net 1 "GND")
			(pinfunction "GND")
			(pintype "passive")
			(solder_mask_margin 0.075)
		)
		(pad "U7" smd circle
			(at -6.5 3.5 90)
			(size 0.5 0.5)
			(layers "F.Cu" "F.Mask" "F.Paste")
			(net 573 "+1V8_MGTVCCAUX")
			(pinfunction "MGTVCCAUX_R")
			(pintype "passive")
			(solder_mask_margin 0.075)
		)
		(pad "U8" smd circle
			(at -5.5 3.5 90)
			(size 0.5 0.5)
			(layers "F.Cu" "F.Mask" "F.Paste")
			(net 1 "GND")
			(pinfunction "GND")
			(pintype "passive")
			(solder_mask_margin 0.075)
		)
		(pad "U9" smd circle
			(at -4.5 3.5 90)
			(size 0.5 0.5)
			(layers "F.Cu" "F.Mask" "F.Paste")
			(net 553 "+0V85")
			(pinfunction "VCCBRAM")
			(pintype "passive")
			(solder_mask_margin 0.075)
		)
		(pad "U10" smd circle
			(at -3.5 3.5 90)
			(size 0.5 0.5)
			(layers "F.Cu" "F.Mask" "F.Paste")
			(net 553 "+0V85")
			(pinfunction "VCCINT")
			(pintype "passive")
			(solder_mask_margin 0.075)
		)
		(pad "U11" smd circle
			(at -2.5 3.5 90)
			(size 0.5 0.5)
			(layers "F.Cu" "F.Mask" "F.Paste")
			(net 1 "GND")
			(pinfunction "GND")
			(pintype "passive")
			(solder_mask_margin 0.075)
		)
		(pad "U12" smd circle
			(at -1.5 3.5 90)
			(size 0.5 0.5)
			(layers "F.Cu" "F.Mask" "F.Paste")
			(net 553 "+0V85")
			(pinfunction "VCCINT")
			(pintype "passive")
			(solder_mask_margin 0.075)
		)
		(pad "U13" smd circle
			(at -0.5 3.5 90)
			(size 0.5 0.5)
			(layers "F.Cu" "F.Mask" "F.Paste")
			(net 1 "GND")
			(pinfunction "GND")
			(pintype "passive")
			(solder_mask_margin 0.075)
		)
		(pad "U14" smd circle
			(at 0.5 3.5 90)
			(size 0.5 0.5)
			(layers "F.Cu" "F.Mask" "F.Paste")
			(net 553 "+0V85")
			(pinfunction "VCCINT")
			(pintype "passive")
			(solder_mask_margin 0.075)
		)
		(pad "U15" smd circle
			(at 1.5 3.5 90)
			(size 0.5 0.5)
			(layers "F.Cu" "F.Mask" "F.Paste")
			(net 1 "GND")
			(pinfunction "GND")
			(pintype "passive")
			(solder_mask_margin 0.075)
		)
		(pad "U16" smd circle
			(at 2.5 3.5 90)
			(size 0.5 0.5)
			(layers "F.Cu" "F.Mask" "F.Paste")
			(net 553 "+0V85")
			(pinfunction "VCCINT")
			(pintype "passive")
			(solder_mask_margin 0.075)
		)
		(pad "U17" smd circle
			(at 3.5 3.5 90)
			(size 0.5 0.5)
			(layers "F.Cu" "F.Mask" "F.Paste")
			(net 1 "GND")
			(pinfunction "GND")
			(pintype "passive")
			(solder_mask_margin 0.075)
		)
		(pad "U18" smd circle
			(at 4.5 3.5 90)
			(size 0.5 0.5)
			(layers "F.Cu" "F.Mask" "F.Paste")
			(net 1 "GND")
			(pinfunction "GND")
			(pintype "passive")
			(solder_mask_margin 0.075)
		)
		(pad "U19" smd circle
			(at 5.5 3.5 90)
			(size 0.5 0.5)
			(layers "F.Cu" "F.Mask" "F.Paste")
			(net 120 "/DDR5 RDIMM/A.DQS4_P")
			(pinfunction "IO_L1P_T0L_N0_DBC_RS0_65")
			(pintype "bidirectional")
			(die_length 11.98)
			(solder_mask_margin 0.075)
		)
		(pad "U20" smd circle
			(at 6.5 3.5 90)
			(size 0.5 0.5)
			(layers "F.Cu" "F.Mask" "F.Paste")
			(net 173 "/DDR5 RDIMM/A.CB3")
			(pinfunction "IO_L3N_T0L_N5_AD15N_A27_65")
			(pintype "bidirectional")
			(die_length 11.601)
			(solder_mask_margin 0.075)
		)
		(pad "U21" smd circle
			(at 7.5 3.5 90)
			(size 0.5 0.5)
			(layers "F.Cu" "F.Mask" "F.Paste")
			(net 68 "/DDR5 RDIMM/A.CB1")
			(pinfunction "IO_L2P_T0L_N2_FOE_B_65")
			(pintype "bidirectional")
			(die_length 9.565)
			(solder_mask_margin 0.075)
		)
		(pad "U22" smd circle
			(at 8.5 3.5 90)
			(size 0.5 0.5)
			(layers "F.Cu" "F.Mask" "F.Paste")
			(net 67 "/DDR5 RDIMM/A.CB0")
			(pinfunction "IO_L2N_T0L_N3_FWE_FCS2_B_65")
			(pintype "bidirectional")
			(die_length 9.453)
			(solder_mask_margin 0.075)
		)
		(pad "U23" smd circle
			(at 9.5 3.5 90)
			(size 0.5 0.5)
			(layers "F.Cu" "F.Mask" "F.Paste")
			(net 687 "VDDQ")
			(pinfunction "VCCO_65")
			(pintype "passive")
			(solder_mask_margin 0.075)
		)
		(pad "U24" smd circle
			(at 10.5 3.5 90)
			(size 0.5 0.5)
			(layers "F.Cu" "F.Mask" "F.Paste")
			(net 203 "/DDR5 RDIMM/B.CS1_c")
			(pinfunction "IO_L13N_T2L_N1_GC_QBC_A07_D23_65")
			(pintype "bidirectional")
			(die_length 10.66)
			(solder_mask_margin 0.075)
		)
		(pad "U25" smd circle
			(at 11.5 3.5 90)
			(size 0.5 0.5)
			(layers "F.Cu" "F.Mask" "F.Paste")
			(net 79 "/DDR5 RDIMM/B.CA0")
			(pinfunction "IO_L14N_T2L_N3_GC_A05_D21_65")
			(pintype "bidirectional")
			(die_length 11.487)
			(solder_mask_margin 0.075)
		)
		(pad "U26" smd circle
			(at 12.5 3.5 90)
			(size 0.5 0.5)
			(layers "F.Cu" "F.Mask" "F.Paste")
			(net 84 "/DDR5 RDIMM/CTRL.DLBDQ")
			(pinfunction "IO_L16P_T2U_N6_QBC_AD3P_A00_D16_65")
			(pintype "bidirectional")
			(die_length 11.914)
			(solder_mask_margin 0.075)
		)
		(pad "V1" smd circle
			(at -12.5 4.5 90)
			(size 0.5 0.5)
			(layers "F.Cu" "F.Mask" "F.Paste")
			(net 337 "/FPGA MGT Interface/PCIE.RXD2_N")
			(pinfunction "MGTYRXN1_225")
			(pintype "input")
			(die_length 10.53)
			(solder_mask_margin 0.075)
		)
		(pad "V2" smd circle
			(at -11.5 4.5 90)
			(size 0.5 0.5)
			(layers "F.Cu" "F.Mask" "F.Paste")
			(net 336 "/FPGA MGT Interface/PCIE.RXD2_P")
			(pinfunction "MGTYRXP1_225")
			(pintype "input")
			(die_length 10.52)
			(solder_mask_margin 0.075)
		)
		(pad "V3" smd circle
			(at -10.5 4.5 90)
			(size 0.5 0.5)
			(layers "F.Cu" "F.Mask" "F.Paste")
			(net 1 "GND")
			(pinfunction "GND")
			(pintype "passive")
			(solder_mask_margin 0.075)
		)
		(pad "V4" smd circle
			(at -9.5 4.5 90)
			(size 0.5 0.5)
			(layers "F.Cu" "F.Mask" "F.Paste")
			(net 1 "GND")
			(pinfunction "GND")
			(pintype "passive")
			(solder_mask_margin 0.075)
		)
		(pad "V5" smd circle
			(at -8.5 4.5 90)
			(size 0.5 0.5)
			(layers "F.Cu" "F.Mask" "F.Paste")
			(net 172 "+1V2_MGTAVTT")
			(pinfunction "MGTAVTT_R")
			(pintype "passive")
			(solder_mask_margin 0.075)
		)
		(pad "V6" smd circle
			(at -7.5 4.5 90)
			(size 0.5 0.5)
			(layers "F.Cu" "F.Mask" "F.Paste")
			(net 564 "unconnected-(U34J-MGTREFCLK0N_225-PadV6)")
			(pinfunction "MGTREFCLK0N_225")
			(pintype "input+no_connect")
			(die_length 7.84)
			(solder_mask_margin 0.075)
		)
		(pad "V7" smd circle
			(at -6.5 4.5 90)
			(size 0.5 0.5)
			(layers "F.Cu" "F.Mask" "F.Paste")
			(net 565 "unconnected-(U34J-MGTREFCLK0P_225-PadV7)")
			(pinfunction "MGTREFCLK0P_225")
			(pintype "input+no_connect")
			(die_length 7.861)
			(solder_mask_margin 0.075)
		)
		(pad "V8" smd circle
			(at -5.5 4.5 90)
			(size 0.5 0.5)
			(layers "F.Cu" "F.Mask" "F.Paste")
			(net 1 "GND")
			(pinfunction "GND")
			(pintype "passive")
			(solder_mask_margin 0.075)
		)
		(pad "V9" smd circle
			(at -4.5 4.5 90)
			(size 0.5 0.5)
			(layers "F.Cu" "F.Mask" "F.Paste")
			(net 553 "+0V85")
			(pinfunction "VCCBRAM")
			(pintype "passive")
			(solder_mask_margin 0.075)
		)
		(pad "V10" smd circle
			(at -3.5 4.5 90)
			(size 0.5 0.5)
			(layers "F.Cu" "F.Mask" "F.Paste")
			(net 1 "GND")
			(pinfunction "GND")
			(pintype "passive")
			(solder_mask_margin 0.075)
		)
		(pad "V11" smd circle
			(at -2.5 4.5 90)
			(size 0.5 0.5)
			(layers "F.Cu" "F.Mask" "F.Paste")
			(net 553 "+0V85")
			(pinfunction "VCCINT")
			(pintype "passive")
			(solder_mask_margin 0.075)
		)
		(pad "V12" smd circle
			(at -1.5 4.5 90)
			(size 0.5 0.5)
			(layers "F.Cu" "F.Mask" "F.Paste")
			(net 1 "GND")
			(pinfunction "GND")
			(pintype "passive")
			(solder_mask_margin 0.075)
		)
		(pad "V13" smd circle
			(at -0.5 4.5 90)
			(size 0.5 0.5)
			(layers "F.Cu" "F.Mask" "F.Paste")
			(net 553 "+0V85")
			(pinfunction "VCCINT")
			(pintype "passive")
			(solder_mask_margin 0.075)
		)
		(pad "V14" smd circle
			(at 0.5 4.5 90)
			(size 0.5 0.5)
			(layers "F.Cu" "F.Mask" "F.Paste")
			(net 1 "GND")
			(pinfunction "GND")
			(pintype "passive")
			(solder_mask_margin 0.075)
		)
		(pad "V15" smd circle
			(at 1.5 4.5 90)
			(size 0.5 0.5)
			(layers "F.Cu" "F.Mask" "F.Paste")
			(net 553 "+0V85")
			(pinfunction "VCCINT")
			(pintype "passive")
			(solder_mask_margin 0.075)
		)
		(pad "V16" smd circle
			(at 2.5 4.5 90)
			(size 0.5 0.5)
			(layers "F.Cu" "F.Mask" "F.Paste")
			(net 1 "GND")
			(pinfunction "GND")
			(pintype "passive")
			(solder_mask_margin 0.075)
		)
		(pad "V17" smd circle
			(at 3.5 4.5 90)
			(size 0.5 0.5)
			(layers "F.Cu" "F.Mask" "F.Paste")
			(net 553 "+0V85")
			(pinfunction "VCCINT")
			(pintype "passive")
			(solder_mask_margin 0.075)
		)
		(pad "V18" smd circle
			(at 4.5 4.5 90)
			(size 0.5 0.5)
			(layers "F.Cu" "F.Mask" "F.Paste")
			(net 536 "/FPGA banks HP/VREF_65")
			(pinfunction "VREF_65")
			(pintype "input")
			(solder_mask_margin 0.075)
		)
		(pad "V19" smd circle
			(at 5.5 4.5 90)
			(size 0.5 0.5)
			(layers "F.Cu" "F.Mask" "F.Paste")
			(net 121 "/DDR5 RDIMM/A.DQS4_N")
			(pinfunction "IO_L1N_T0L_N1_DBC_RS1_65")
			(pintype "bidirectional")
			(die_length 12.006)
			(solder_mask_margin 0.075)
		)
		(pad "V20" smd circle
			(at 6.5 4.5 90)
			(size 0.5 0.5)
			(layers "F.Cu" "F.Mask" "F.Paste")
			(net 1 "GND")
			(pinfunction "GND")
			(pintype "passive")
			(solder_mask_margin 0.075)
		)
		(pad "V21" smd circle
			(at 7.5 4.5 90)
			(size 0.5 0.5)
			(layers "F.Cu" "F.Mask" "F.Paste")
			(net 235 "/DDR5 RDIMM/A.DQS9_P")
			(pinfunction "IO_L4P_T0U_N6_DBC_AD7P_A24_65")
			(pintype "bidirectional")
			(die_length 9.873)
			(solder_mask_margin 0.075)
		)
		(pad "V22" smd circle
			(at 8.5 4.5 90)
			(size 0.5 0.5)
			(layers "F.Cu" "F.Mask" "F.Paste")
			(net 234 "/DDR5 RDIMM/A.DQS9_N")
			(pinfunction "IO_L4N_T0U_N7_DBC_AD7N_A25_65")
			(pintype "bidirectional")
			(die_length 9.665)
			(solder_mask_margin 0.075)
		)
		(pad "V23" smd circle
			(at 9.5 4.5 90)
			(size 0.5 0.5)
			(layers "F.Cu" "F.Mask" "F.Paste")
			(net 192 "/DDR5 RDIMM/A.CA1")
			(pinfunction "IO_L11P_T1U_N8_GC_A10_D26_65")
			(pintype "bidirectional")
			(die_length 12.46)
			(solder_mask_margin 0.075)
		)
		(pad "V24" smd circle
			(at 10.5 4.5 90)
			(size 0.5 0.5)
			(layers "F.Cu" "F.Mask" "F.Paste")
			(net 77 "/DDR5 RDIMM/A.CA6")
			(pinfunction "IO_L12P_T1U_N10_GC_A08_D24_65")
			(pintype "bidirectional")
			(die_length 11.139)
			(solder_mask_margin 0.075)
		)
		(pad "V25" smd circle
			(at 11.5 4.5 90)
			(size 0.5 0.5)
			(layers "F.Cu" "F.Mask" "F.Paste")
			(net 1 "GND")
			(pinfunction "GND")
			(pintype "passive")
			(solder_mask_margin 0.075)
		)
		(pad "V26" smd circle
			(at 12.5 4.5 90)
			(size 0.5 0.5)
			(layers "F.Cu" "F.Mask" "F.Paste")
			(net 85 "/DDR5 RDIMM/CTRL.DLBDQS")
			(pinfunction "IO_L16N_T2U_N7_QBC_AD3N_A01_D17_65")
			(pintype "bidirectional")
			(die_length 11.807)
			(solder_mask_margin 0.075)
		)
		(pad "W1" smd circle
			(at -12.5 5.5 90)
			(size 0.5 0.5)
			(layers "F.Cu" "F.Mask" "F.Paste")
			(net 1 "GND")
			(pinfunction "GND")
			(pintype "passive")
			(solder_mask_margin 0.075)
		)
		(pad "W2" smd circle
			(at -11.5 5.5 90)
			(size 0.5 0.5)
			(layers "F.Cu" "F.Mask" "F.Paste")
			(net 1 "GND")
			(pinfunction "GND")
			(pintype "passive")
			(solder_mask_margin 0.075)
		)
		(pad "W3" smd circle
			(at -10.5 5.5 90)
			(size 0.5 0.5)
			(layers "F.Cu" "F.Mask" "F.Paste")
			(net 1 "GND")
			(pinfunction "GND")
			(pintype "passive")
			(solder_mask_margin 0.075)
		)
		(pad "W4" smd circle
			(at -9.5 5.5 90)
			(size 0.5 0.5)
			(layers "F.Cu" "F.Mask" "F.Paste")
			(net 26 "/FPGA MGT Interface/GTY_225_TX1_N")
			(pinfunction "MGTYTXN1_225")
			(pintype "output")
			(die_length 10.352)
			(solder_mask_margin 0.075)
		)
		(pad "W5" smd circle
			(at -8.5 5.5 90)
			(size 0.5 0.5)
			(layers "F.Cu" "F.Mask" "F.Paste")
			(net 18 "/FPGA MGT Interface/GTY_225_TX1_P")
			(pinfunction "MGTYTXP1_225")
			(pintype "output")
			(die_length 10.335)
			(solder_mask_margin 0.075)
		)
		(pad "W6" smd circle
			(at -7.5 5.5 90)
			(size 0.5 0.5)
			(layers "F.Cu" "F.Mask" "F.Paste")
			(net 1 "GND")
			(pinfunction "GND")
			(pintype "passive")
			(solder_mask_margin 0.075)
		)
		(pad "W7" smd circle
			(at -6.5 5.5 90)
			(size 0.5 0.5)
			(layers "F.Cu" "F.Mask" "F.Paste")
			(net 820 "+0V9_MGTAVCC")
			(pinfunction "MGTAVCC_R")
			(pintype "passive")
			(solder_mask_margin 0.075)
		)
		(pad "W8" smd circle
			(at -5.5 5.5 90)
			(size 0.5 0.5)
			(layers "F.Cu" "F.Mask" "F.Paste")
			(net 1 "GND")
			(pinfunction "GND")
			(pintype "passive")
			(solder_mask_margin 0.075)
		)
		(pad "W9" smd circle
			(at -4.5 5.5 90)
			(size 0.5 0.5)
			(layers "F.Cu" "F.Mask" "F.Paste")
			(net 40 "/FPGA Config/PUDC_B")
			(pinfunction "PUDC_B_0")
			(pintype "input")
			(die_length 12.177)
			(solder_mask_margin 0.075)
		)
		(pad "W10" smd circle
			(at -3.5 5.5 90)
			(size 0.5 0.5)
			(layers "F.Cu" "F.Mask" "F.Paste")
			(net 341 "/FPGA Config/INIT_B")
			(pinfunction "INIT_B_0")
			(pintype "bidirectional")
			(die_length 11.957)
			(solder_mask_margin 0.075)
		)
		(pad "W11" smd circle
			(at -2.5 5.5 90)
			(size 0.5 0.5)
			(layers "F.Cu" "F.Mask" "F.Paste")
			(net 1 "GND")
			(pinfunction "RSVDGND")
			(pintype "input")
			(die_length 12.269)
			(solder_mask_margin 0.075)
		)
		(pad "W12" smd circle
			(at -1.5 5.5 90)
			(size 0.5 0.5)
			(layers "F.Cu" "F.Mask" "F.Paste")
			(net 746 "/FPGA Config/FPGA_PWR.SDA")
			(pinfunction "IO_L12P_AD0P_84")
			(pintype "bidirectional")
			(die_length 10.067)
			(solder_mask_margin 0.075)
		)
		(pad "W13" smd circle
			(at -0.5 5.5 90)
			(size 0.5 0.5)
			(layers "F.Cu" "F.Mask" "F.Paste")
			(net 747 "/FPGA Config/FPGA_PWR.SCL")
			(pinfunction "IO_L12N_AD0N_84")
			(pintype "bidirectional")
			(die_length 10.556)
			(solder_mask_margin 0.075)
		)
		(pad "W14" smd circle
			(at 0.5 5.5 90)
			(size 0.5 0.5)
			(layers "F.Cu" "F.Mask" "F.Paste")
			(net 472 "/FPGA banks HD/FPGA_DDR.SDA")
			(pinfunction "IO_L10P_AD2P_84")
			(pintype "bidirectional")
			(die_length 9.435)
			(solder_mask_margin 0.075)
		)
		(pad "W15" smd circle
			(at 1.5 5.5 90)
			(size 0.5 0.5)
			(layers "F.Cu" "F.Mask" "F.Paste")
			(net 465 "/FPGA banks HD/FPGA_DDR.SCL")
			(pinfunction "IO_L10N_AD2N_84")
			(pintype "bidirectional")
			(die_length 9.29)
			(solder_mask_margin 0.075)
		)
		(pad "W16" smd circle
			(at 2.5 5.5 90)
			(size 0.5 0.5)
			(layers "F.Cu" "F.Mask" "F.Paste")
			(net 567 "unconnected-(U34F-IO_L9P_AD3P_84-PadW16)")
			(pinfunction "IO_L9P_AD3P_84")
			(pintype "bidirectional+no_connect")
			(die_length 10.407)
			(solder_mask_margin 0.075)
		)
		(pad "W17" smd circle
			(at 3.5 5.5 90)
			(size 0.5 0.5)
			(layers "F.Cu" "F.Mask" "F.Paste")
			(net 1 "GND")
			(pinfunction "GND")
			(pintype "passive")
			(solder_mask_margin 0.075)
		)
		(pad "W18" smd circle
			(at 4.5 5.5 90)
			(size 0.5 0.5)
			(layers "F.Cu" "F.Mask" "F.Paste")
			(net 535 "/FPGA banks HP/VREF_64")
			(pinfunction "VREF_64")
			(pintype "input")
			(solder_mask_margin 0.075)
		)
		(pad "W19" smd circle
			(at 5.5 5.5 90)
			(size 0.5 0.5)
			(layers "F.Cu" "F.Mask" "F.Paste")
			(net 187 "/DDR5 RDIMM/A.CB7")
			(pinfunction "IO_L6P_T0U_N10_AD6P_A20_65")
			(pintype "bidirectional")
			(die_length 13.539)
			(solder_mask_margin 0.075)
		)
		(pad "W20" smd circle
			(at 6.5 5.5 90)
			(size 0.5 0.5)
			(layers "F.Cu" "F.Mask" "F.Paste")
			(net 71 "/DDR5 RDIMM/A.CB5")
			(pinfunction "IO_L6N_T0U_N11_AD6N_A21_65")
			(pintype "bidirectional")
			(die_length 11.707)
			(solder_mask_margin 0.075)
		)
		(pad "W21" smd circle
			(at 7.5 5.5 90)
			(size 0.5 0.5)
			(layers "F.Cu" "F.Mask" "F.Paste")
			(net 548 "/FPGA banks HP/VRP_65")
			(pinfunction "IO_T0U_N12_VRP_A28_65")
			(pintype "bidirectional")
			(die_length 11.222)
			(solder_mask_margin 0.075)
		)
		(pad "W22" smd circle
			(at 8.5 5.5 90)
			(size 0.5 0.5)
			(layers "F.Cu" "F.Mask" "F.Paste")
			(net 1 "GND")
			(pinfunction "GND")
			(pintype "passive")
			(solder_mask_margin 0.075)
		)
		(pad "W23" smd circle
			(at 9.5 5.5 90)
			(size 0.5 0.5)
			(layers "F.Cu" "F.Mask" "F.Paste")
			(net 74 "/DDR5 RDIMM/A.CA0")
			(pinfunction "IO_L11N_T1U_N9_GC_A11_D27_65")
			(pintype "bidirectional")
			(die_length 12.408)
			(solder_mask_margin 0.075)
		)
		(pad "W24" smd circle
			(at 10.5 5.5 90)
			(size 0.5 0.5)
			(layers "F.Cu" "F.Mask" "F.Paste")
			(net 78 "/DDR5 RDIMM/A.PAR")
			(pinfunction "IO_L12N_T1U_N11_GC_A09_D25_65")
			(pintype "bidirectional")
			(die_length 11.035)
			(solder_mask_margin 0.075)
		)
		(pad "W25" smd circle
			(at 11.5 5.5 90)
			(size 0.5 0.5)
			(layers "F.Cu" "F.Mask" "F.Paste")
			(net 634 "/DDR5 RDIMM/CTRL.CK_P")
			(pinfunction "IO_L10P_T1U_N6_QBC_AD4P_A12_D28_65")
			(pintype "bidirectional")
			(die_length 12.878)
			(solder_mask_margin 0.075)
		)
		(pad "W26" smd circle
			(at 12.5 5.5 90)
			(size 0.5 0.5)
			(layers "F.Cu" "F.Mask" "F.Paste")
			(net 633 "/DDR5 RDIMM/CTRL.CK_N")
			(pinfunction "IO_L10N_T1U_N7_QBC_AD4N_A13_D29_65")
			(pintype "bidirectional")
			(die_length 12.877)
			(solder_mask_margin 0.075)
		)
		(pad "Y1" smd circle
			(at -12.5 6.5 90)
			(size 0.5 0.5)
			(layers "F.Cu" "F.Mask" "F.Paste")
			(net 339 "/FPGA MGT Interface/PCIE.RXD3_N")
			(pinfunction "MGTYRXN0_225")
			(pintype "input")
			(die_length 11.557)
			(solder_mask_margin 0.075)
		)
		(pad "Y2" smd circle
			(at -11.5 6.5 90)
			(size 0.5 0.5)
			(layers "F.Cu" "F.Mask" "F.Paste")
			(net 338 "/FPGA MGT Interface/PCIE.RXD3_P")
			(pinfunction "MGTYRXP0_225")
			(pintype "input")
			(die_length 11.548)
			(solder_mask_margin 0.075)
		)
		(pad "Y3" smd circle
			(at -10.5 6.5 90)
			(size 0.5 0.5)
			(layers "F.Cu" "F.Mask" "F.Paste")
			(net 1 "GND")
			(pinfunction "GND")
			(pintype "passive")
			(solder_mask_margin 0.075)
		)
		(pad "Y4" smd circle
			(at -9.5 6.5 90)
			(size 0.5 0.5)
			(layers "F.Cu" "F.Mask" "F.Paste")
			(net 1 "GND")
			(pinfunction "GND")
			(pintype "passive")
			(solder_mask_margin 0.075)
		)
		(pad "Y5" smd circle
			(at -8.5 6.5 90)
			(size 0.5 0.5)
			(layers "F.Cu" "F.Mask" "F.Paste")
			(net 172 "+1V2_MGTAVTT")
			(pinfunction "MGTAVTT_R")
			(pintype "passive")
			(solder_mask_margin 0.075)
		)
		(pad "Y6" smd circle
			(at -7.5 6.5 90)
			(size 0.5 0.5)
			(layers "F.Cu" "F.Mask" "F.Paste")
			(net 569 "unconnected-(U34I-MGTREFCLK1N_224-PadY6)")
			(pinfunction "MGTREFCLK1N_224")
			(pintype "input+no_connect")
			(die_length 8.854)
			(solder_mask_margin 0.075)
		)
		(pad "Y7" smd circle
			(at -6.5 6.5 90)
			(size 0.5 0.5)
			(layers "F.Cu" "F.Mask" "F.Paste")
			(net 570 "unconnected-(U34I-MGTREFCLK1P_224-PadY7)")
			(pinfunction "MGTREFCLK1P_224")
			(pintype "input+no_connect")
			(die_length 8.9)
			(solder_mask_margin 0.075)
		)
		(pad "Y8" smd circle
			(at -5.5 6.5 90)
			(size 0.5 0.5)
			(layers "F.Cu" "F.Mask" "F.Paste")
			(net 1 "GND")
			(pinfunction "GND")
			(pintype "passive")
			(solder_mask_margin 0.075)
		)
		(pad "Y9" smd circle
			(at -4.5 6.5 90)
			(size 0.5 0.5)
			(layers "F.Cu" "F.Mask" "F.Paste")
			(net 797 "+1V8")
			(pinfunction "VBATT")
			(pintype "power_in")
			(die_length 10.352)
			(solder_mask_margin 0.075)
		)
		(pad "Y10" smd circle
			(at -3.5 6.5 90)
			(size 0.5 0.5)
			(layers "F.Cu" "F.Mask" "F.Paste")
			(net 242 "/Debug FTDI + VNA/JTAG.TDO")
			(pinfunction "TDO_0")
			(pintype "output")
			(die_length 14.323)
			(solder_mask_margin 0.075)
		)
		(pad "Y11" smd circle
			(at -2.5 6.5 90)
			(size 0.5 0.5)
			(layers "F.Cu" "F.Mask" "F.Paste")
			(net 355 "/FPGA Config/FLASH.SCK")
			(pinfunction "CCLK_0")
			(pintype "bidirectional")
			(die_length 12.313)
			(solder_mask_margin 0.075)
		)
		(pad "Y12" smd circle
			(at -1.5 6.5 90)
			(size 0.5 0.5)
			(layers "F.Cu" "F.Mask" "F.Paste")
			(net 462 "/FPGA Config/POR_OVERRIDE")
			(pinfunction "POR_OVERRIDE")
			(pintype "input")
			(die_length 14.069)
			(solder_mask_margin 0.075)
		)
		(pad "Y13" smd circle
			(at -0.5 6.5 90)
			(size 0.5 0.5)
			(layers "F.Cu" "F.Mask" "F.Paste")
			(net 571 "unconnected-(U34F-IO_L11P_AD1P_84-PadY13)")
			(pinfunction "IO_L11P_AD1P_84")
			(pintype "bidirectional+no_connect")
			(die_length 13.346)
			(solder_mask_margin 0.075)
		)
		(pad "Y14" smd circle
			(at 0.5 6.5 90)
			(size 0.5 0.5)
			(layers "F.Cu" "F.Mask" "F.Paste")
			(net 151 "+3V3")
			(pinfunction "VCCO_84")
			(pintype "passive")
			(solder_mask_margin 0.075)
		)
		(pad "Y15" smd circle
			(at 1.5 6.5 90)
			(size 0.5 0.5)
			(layers "F.Cu" "F.Mask" "F.Paste")
			(net 185 "FPGA_POWER_OFF")
			(pinfunction "IO_L7P_HDGC_AD5P_84")
			(pintype "bidirectional")
			(die_length 12.09)
			(solder_mask_margin 0.075)
		)
		(pad "Y16" smd circle
			(at 2.5 6.5 90)
			(size 0.5 0.5)
			(layers "F.Cu" "F.Mask" "F.Paste")
			(net 572 "unconnected-(U34F-IO_L9N_AD3N_84-PadY16)")
			(pinfunction "IO_L9N_AD3N_84")
			(pintype "bidirectional+no_connect")
			(die_length 10.715)
			(solder_mask_margin 0.075)
		)
		(pad "Y17" smd circle
			(at 3.5 6.5 90)
			(size 0.5 0.5)
			(layers "F.Cu" "F.Mask" "F.Paste")
			(net 135 "/DDR5 RDIMM/A.DQ7")
			(pinfunction "IO_L23P_T3U_N8_64")
			(pintype "bidirectional")
			(die_length 14.175)
			(solder_mask_margin 0.075)
		)
		(pad "Y18" smd circle
			(at 4.5 6.5 90)
			(size 0.5 0.5)
			(layers "F.Cu" "F.Mask" "F.Paste")
			(net 54 "/DDR5 RDIMM/A.DQ5")
			(pinfunction "IO_L24P_T3U_N10_64")
			(pintype "bidirectional")
			(die_length 16.052)
			(solder_mask_margin 0.075)
		)
		(pad "Y19" smd circle
			(at 5.5 6.5 90)
			(size 0.5 0.5)
			(layers "F.Cu" "F.Mask" "F.Paste")
			(net 1 "GND")
			(pinfunction "GND")
			(pintype "passive")
			(solder_mask_margin 0.075)
		)
		(pad "Y20" smd circle
			(at 6.5 6.5 90)
			(size 0.5 0.5)
			(layers "F.Cu" "F.Mask" "F.Paste")
			(net 94 "/DDR5 RDIMM/A.DQS0_P")
			(pinfunction "IO_L19P_T3L_N0_DBC_AD9P_64")
			(pintype "bidirectional")
			(die_length 12.396)
			(solder_mask_margin 0.075)
		)
		(pad "Y21" smd circle
			(at 7.5 6.5 90)
			(size 0.5 0.5)
			(layers "F.Cu" "F.Mask" "F.Paste")
			(net 101 "/DDR5 RDIMM/A.DQS0_N")
			(pinfunction "IO_L19N_T3L_N1_DBC_AD9N_64")
			(pintype "bidirectional")
			(die_length 12.493)
			(solder_mask_margin 0.075)
		)
		(pad "Y22" smd circle
			(at 8.5 6.5 90)
			(size 0.5 0.5)
			(layers "F.Cu" "F.Mask" "F.Paste")
			(net 73 "/DDR5 RDIMM/A.CS0_c")
			(pinfunction "IO_L7P_T1L_N0_QBC_AD13P_A18_65")
			(pintype "bidirectional")
			(die_length 12.981)
			(solder_mask_margin 0.075)
		)
		(pad "Y23" smd circle
			(at 9.5 6.5 90)
			(size 0.5 0.5)
			(layers "F.Cu" "F.Mask" "F.Paste")
			(net 191 "/DDR5 RDIMM/A.CS1_c")
			(pinfunction "IO_L7N_T1L_N1_QBC_AD13N_A19_65")
			(pintype "bidirectional")
			(die_length 12.82)
			(solder_mask_margin 0.075)
		)
		(pad "Y24" smd circle
			(at 10.5 6.5 90)
			(size 0.5 0.5)
			(layers "F.Cu" "F.Mask" "F.Paste")
			(net 687 "VDDQ")
			(pinfunction "VCCO_65")
			(pintype "passive")
			(solder_mask_margin 0.075)
		)
		(pad "Y25" smd circle
			(at 11.5 6.5 90)
			(size 0.5 0.5)
			(layers "F.Cu" "F.Mask" "F.Paste")
			(net 76 "/DDR5 RDIMM/A.CA4")
			(pinfunction "IO_L8P_T1L_N2_AD5P_A16_65")
			(pintype "bidirectional")
			(die_length 12.979)
			(solder_mask_margin 0.075)
		)
		(pad "Y26" smd circle
			(at 12.5 6.5 90)
			(size 0.5 0.5)
			(layers "F.Cu" "F.Mask" "F.Paste")
			(net 194 "/DDR5 RDIMM/A.CA5")
			(pinfunction "IO_L8N_T1L_N3_AD5N_A17_65")
			(pintype "bidirectional")
			(die_length 13.135)
			(solder_mask_margin 0.075)
		)
	)
	(footprint "antmicro-footprints:C_0402_1005Metric"
		(layer "F.Cu")
		(at 139.624499 169.099 -90)
		(descr "Capacitor SMD 0402")
		(tags "capacitor SMD 0402")
		(property "Reference" "C121"
			(at -1.199 -2.725501 90)
			(layer "F.SilkS")
			(effects
				(font
					(size 0.7 0.7)
					(thickness 0.15)
				)
				(justify right bottom)
			)
		)
		(property "Value" "C_100n_0402"
			(at -1.022927 2.155213 90)
			(layer "F.Fab")
			(effects
				(font
					(size 0.7 0.7)
					(thickness 0.15)
				)
				(justify right bottom)
			)
		)
		(property "Datasheet" "https://www.murata.com/products/productdetail?partno=GRM155R61H104KE14%23"
			(at 0 0 270)
			(layer "F.Fab")
			(hide yes)
			(effects
				(font
					(size 1.27 1.27)
					(thickness 0.15)
				)
			)
		)
		(property "MPN" "GRM155R61H104KE14D"
			(at 0 0 270)
			(unlocked yes)
			(layer "F.Fab")
			(hide yes)
			(effects
				(font
					(size 1 1)
					(thickness 0.15)
				)
			)
		)
		(property "Manufacturer" "Murata"
			(at 0 0 270)
			(unlocked yes)
			(layer "F.Fab")
			(hide yes)
			(effects
				(font
					(size 1 1)
					(thickness 0.15)
				)
			)
		)
		(property "License" "Apache-2.0"
			(at 0 0 270)
			(unlocked yes)
			(layer "F.Fab")
			(hide yes)
			(effects
				(font
					(size 1 1)
					(thickness 0.15)
				)
			)
		)
		(property "Author" "Antmicro"
			(at 0 0 270)
			(unlocked yes)
			(layer "F.Fab")
			(hide yes)
			(effects
				(font
					(size 1 1)
					(thickness 0.15)
				)
			)
		)
		(property "Val" "100n"
			(at 0 0 270)
			(unlocked yes)
			(layer "F.Fab")
			(hide yes)
			(effects
				(font
					(size 1 1)
					(thickness 0.15)
				)
			)
		)
		(property "Voltage" "50V"
			(at 0 0 270)
			(unlocked yes)
			(layer "F.Fab")
			(hide yes)
			(effects
				(font
					(size 1 1)
					(thickness 0.15)
				)
			)
		)
		(property "Dielectric" "X5R"
			(at 0 0 270)
			(unlocked yes)
			(layer "F.Fab")
			(hide yes)
			(effects
				(font
					(size 1 1)
					(thickness 0.15)
				)
			)
		)
		(sheetname "/Debug FTDI + VNA/")
		(sheetfile "debug-ftdi.kicad_sch")
		(attr smd)
		(fp_rect
			(start -0.925 -0.47)
			(end 0.925 0.47)
			(stroke
				(width 0.05)
				(type default)
			)
			(fill no)
			(layer "F.CrtYd")
		)
		(fp_line
			(start -0.494 0.248)
			(end -0.494 -0.25)
			(stroke
				(width 0.15)
				(type solid)
			)
			(layer "F.Fab")
		)
		(fp_line
			(start 0.504 0.248)
			(end -0.494 0.248)
			(stroke
				(width 0.15)
				(type solid)
			)
			(layer "F.Fab")
		)
		(fp_line
			(start -0.494 -0.25)
			(end 0.504 -0.25)
			(stroke
				(width 0.15)
				(type solid)
			)
			(layer "F.Fab")
		)
		(fp_line
			(start 0.504 -0.25)
			(end 0.504 0.248)
			(stroke
				(width 0.15)
				(type solid)
			)
			(layer "F.Fab")
		)
		(fp_text user "Author: Antmicro"
			(at -0.939 3.399 270)
			(layer "F.Fab")
			(effects
				(font
					(size 0.7 0.7)
					(thickness 0.15)
				)
				(justify left bottom)
			)
		)
		(fp_text user "License: Apache-2.0"
			(at -0.939 5.799 270)
			(layer "F.Fab")
			(effects
				(font
					(size 0.7 0.7)
					(thickness 0.15)
				)
				(justify left bottom)
			)
		)
		(fp_text user "${REFERENCE}"
			(at -0.939 4.599 270)
			(layer "F.Fab")
			(effects
				(font
					(size 0.7 0.7)
					(thickness 0.15)
				)
				(justify left bottom)
			)
		)
		(pad "1" smd roundrect
			(at -0.48 0 270)
			(size 0.59 0.64)
			(layers "F.Cu" "F.Mask" "F.Paste")
			(roundrect_rratio 0.25)
			(net 1 "GND")
			(pintype "passive")
		)
		(pad "2" smd roundrect
			(at 0.48 0 270)
			(size 0.59 0.64)
			(layers "F.Cu" "F.Mask" "F.Paste")
			(roundrect_rratio 0.25)
			(net 6 "/Debug FTDI + VNA/FTDI_3V3")
			(pintype "passive")
		)
	)
	(footprint "antmicro-footprints:C_0402_1005Metric"
		(layer "F.Cu")
		(at 249.8 186.449 -90)
		(descr "Capacitor SMD 0402")
		(tags "capacitor SMD 0402")
		(property "Reference" "C322"
			(at -0.975 -1.45 90)
			(layer "F.SilkS")
			(effects
				(font
					(size 0.7 0.7)
					(thickness 0.15)
				)
				(justify right bottom)
			)
		)
		(property "Value" "C_100n_0402"
			(at -1.022927 2.155213 90)
			(layer "F.Fab")
			(effects
				(font
					(size 0.7 0.7)
					(thickness 0.15)
				)
				(justify right bottom)
			)
		)
		(property "Datasheet" "https://www.murata.com/products/productdetail?partno=GRM155R61H104KE14%23"
			(at 0 0 270)
			(layer "F.Fab")
			(hide yes)
			(effects
				(font
					(size 1.27 1.27)
					(thickness 0.15)
				)
			)
		)
		(property "Manufacturer" "Murata"
			(at 0 0 270)
			(unlocked yes)
			(layer "F.Fab")
			(hide yes)
			(effects
				(font
					(size 1 1)
					(thickness 0.15)
				)
			)
		)
		(property "MPN" "GRM155R61H104KE14D"
			(at 0 0 270)
			(unlocked yes)
			(layer "F.Fab")
			(hide yes)
			(effects
				(font
					(size 1 1)
					(thickness 0.15)
				)
			)
		)
		(property "Val" "100n"
			(at 0 0 270)
			(unlocked yes)
			(layer "F.Fab")
			(hide yes)
			(effects
				(font
					(size 1 1)
					(thickness 0.15)
				)
			)
		)
		(property "License" "Apache-2.0"
			(at 0 0 270)
			(unlocked yes)
			(layer "F.Fab")
			(hide yes)
			(effects
				(font
					(size 1 1)
					(thickness 0.15)
				)
			)
		)
		(property "Author" "Antmicro"
			(at 0 0 270)
			(unlocked yes)
			(layer "F.Fab")
			(hide yes)
			(effects
				(font
					(size 1 1)
					(thickness 0.15)
				)
			)
		)
		(property "Voltage" "50V"
			(at 0 0 270)
			(unlocked yes)
			(layer "F.Fab")
			(hide yes)
			(effects
				(font
					(size 1 1)
					(thickness 0.15)
				)
			)
		)
		(property "Dielectric" "X5R"
			(at 0 0 270)
			(unlocked yes)
			(layer "F.Fab")
			(hide yes)
			(effects
				(font
					(size 1 1)
					(thickness 0.15)
				)
			)
		)
		(sheetname "/I^{2}C + I3C/")
		(sheetfile "i2c.kicad_sch")
		(attr smd)
		(fp_rect
			(start -0.925 -0.47)
			(end 0.925 0.47)
			(stroke
				(width 0.05)
				(type default)
			)
			(fill no)
			(layer "F.CrtYd")
		)
		(fp_line
			(start -0.494 0.248)
			(end -0.494 -0.25)
			(stroke
				(width 0.15)
				(type solid)
			)
			(layer "F.Fab")
		)
		(fp_line
			(start 0.504 0.248)
			(end -0.494 0.248)
			(stroke
				(width 0.15)
				(type solid)
			)
			(layer "F.Fab")
		)
		(fp_line
			(start -0.494 -0.25)
			(end 0.504 -0.25)
			(stroke
				(width 0.15)
				(type solid)
			)
			(layer "F.Fab")
		)
		(fp_line
			(start 0.504 -0.25)
			(end 0.504 0.248)
			(stroke
				(width 0.15)
				(type solid)
			)
			(layer "F.Fab")
		)
		(fp_text user "${REFERENCE}"
			(at -0.939 4.599 270)
			(layer "F.Fab")
			(effects
				(font
					(size 0.7 0.7)
					(thickness 0.15)
				)
				(justify left bottom)
			)
		)
		(fp_text user "Author: Antmicro"
			(at -0.939 3.399 270)
			(layer "F.Fab")
			(effects
				(font
					(size 0.7 0.7)
					(thickness 0.15)
				)
				(justify left bottom)
			)
		)
		(fp_text user "License: Apache-2.0"
			(at -0.939 5.799 270)
			(layer "F.Fab")
			(effects
				(font
					(size 0.7 0.7)
					(thickness 0.15)
				)
				(justify left bottom)
			)
		)
		(pad "1" smd roundrect
			(at -0.48 0 270)
			(size 0.59 0.64)
			(layers "F.Cu" "F.Mask" "F.Paste")
			(roundrect_rratio 0.25)
			(net 775 "Net-(Q24-S)")
			(pintype "passive")
		)
		(pad "2" smd roundrect
			(at 0.48 0 270)
			(size 0.59 0.64)
			(layers "F.Cu" "F.Mask" "F.Paste")
			(roundrect_rratio 0.25)
			(net 1 "GND")
			(pintype "passive")
		)
	)
	(footprint "antmicro-footprints:R_0402_1005Metric"
		(layer "F.Cu")
		(at 260.5055 151.921 90)
		(descr "Resistor SMD 0402")
		(tags "resistor SMD 0402")
		(property "Reference" "R166"
			(at -1.379 1.8445 90)
			(layer "F.SilkS")
			(effects
				(font
					(size 0.7 0.7)
					(thickness 0.15)
				)
				(justify left bottom)
			)
		)
		(property "Value" "R_0R_0402"
			(at -1.011843 1.772047 90)
			(layer "F.Fab")
			(effects
				(font
					(size 0.7 0.7)
					(thickness 0.15)
				)
				(justify left bottom)
			)
		)
		(property "Datasheet" "https://industrial.panasonic.com/cdbs/www-data/pdf/RDA0000/AOA0000C301.pdf"
			(at 0 0 90)
			(layer "F.Fab")
			(hide yes)
			(effects
				(font
					(size 1.27 1.27)
					(thickness 0.15)
				)
			)
		)
		(property "Manufacturer" "Panasonic"
			(at 0 0 90)
			(unlocked yes)
			(layer "F.Fab")
			(hide yes)
			(effects
				(font
					(size 1 1)
					(thickness 0.15)
				)
			)
		)
		(property "MPN" "ERJ2GE0R00X"
			(at 0 0 90)
			(unlocked yes)
			(layer "F.Fab")
			(hide yes)
			(effects
				(font
					(size 1 1)
					(thickness 0.15)
				)
			)
		)
		(property "Val" "0R"
			(at 0 0 90)
			(unlocked yes)
			(layer "F.Fab")
			(hide yes)
			(effects
				(font
					(size 1 1)
					(thickness 0.15)
				)
			)
		)
		(property "License" "Apache-2.0"
			(at 0 0 90)
			(unlocked yes)
			(layer "F.Fab")
			(hide yes)
			(effects
				(font
					(size 1 1)
					(thickness 0.15)
				)
			)
		)
		(property "Author" "Antmicro"
			(at 0 0 90)
			(unlocked yes)
			(layer "F.Fab")
			(hide yes)
			(effects
				(font
					(size 1 1)
					(thickness 0.15)
				)
			)
		)
		(property "Tolerance" "~"
			(at 0 0 90)
			(unlocked yes)
			(layer "F.Fab")
			(hide yes)
			(effects
				(font
					(size 1 1)
					(thickness 0.15)
				)
			)
		)
		(property "Current" "1A"
			(at 0 0 90)
			(unlocked yes)
			(layer "F.Fab")
			(hide yes)
			(effects
				(font
					(size 1 1)
					(thickness 0.15)
				)
			)
		)
		(sheetname "/Supply/DC-DC IO/")
		(sheetfile "dc-dc-io.kicad_sch")
		(attr smd)
		(fp_rect
			(start -0.925 -0.47)
			(end 0.925 0.47)
			(stroke
				(width 0.05)
				(type default)
			)
			(fill no)
			(layer "F.CrtYd")
		)
		(fp_rect
			(start -0.5 -0.25)
			(end 0.5 0.25)
			(stroke
				(width 0.15)
				(type solid)
			)
			(fill no)
			(layer "F.Fab")
		)
		(fp_text user "${REFERENCE}"
			(at -0.95 3.168 90)
			(layer "F.Fab")
			(effects
				(font
					(size 0.7 0.7)
					(thickness 0.15)
				)
				(justify left bottom)
			)
		)
		(fp_text user "License: Apache-2.0"
			(at -0.95 5.169 90)
			(layer "F.Fab")
			(effects
				(font
					(size 0.7 0.7)
					(thickness 0.15)
				)
				(justify left bottom)
			)
		)
		(fp_text user "Author: Antmicro"
			(at -0.95 4.169 90)
			(layer "F.Fab")
			(effects
				(font
					(size 0.7 0.7)
					(thickness 0.15)
				)
				(justify left bottom)
			)
		)
		(pad "1" smd roundrect
			(at -0.48 0 90)
			(size 0.59 0.64)
			(layers "F.Cu" "F.Mask" "F.Paste")
			(roundrect_rratio 0.25)
			(net 718 "/Supply/DC-DC IO/FB7")
			(pintype "passive")
		)
		(pad "2" smd roundrect
			(at 0.48 0 90)
			(size 0.59 0.64)
			(layers "F.Cu" "F.Mask" "F.Paste")
			(roundrect_rratio 0.25)
			(net 158 "/Supply/DC-DC IO/VDDQ_local")
			(pintype "passive")
		)
	)
	(footprint "antmicro-footprints:SOT-23-3"
		(layer "F.Cu")
		(at 207.29 151 -90)
		(property "Reference" "U30"
			(at -1.85 0.79 180)
			(layer "F.SilkS")
			(effects
				(font
					(size 0.7 0.7)
					(thickness 0.15)
				)
				(justify right bottom)
			)
		)
		(property "Value" "REF3012AIDBZT"
			(at -1.9 2.7 90)
			(layer "F.Fab")
			(effects
				(font
					(size 0.7 0.7)
					(thickness 0.15)
				)
				(justify right bottom)
			)
		)
		(property "Datasheet" "https://www.ti.com/lit/gpn/REF3012"
			(at 0 0 270)
			(layer "F.Fab")
			(hide yes)
			(effects
				(font
					(size 1.27 1.27)
					(thickness 0.15)
				)
			)
		)
		(property "MPN" "REF3012AIDBZT"
			(at 0 0 270)
			(unlocked yes)
			(layer "F.Fab")
			(hide yes)
			(effects
				(font
					(size 1 1)
					(thickness 0.15)
				)
			)
		)
		(property "Manufacturer" "Texas Instruments"
			(at 0 0 270)
			(unlocked yes)
			(layer "F.Fab")
			(hide yes)
			(effects
				(font
					(size 1 1)
					(thickness 0.15)
				)
			)
		)
		(property "Author" "Antmicro"
			(at 0 0 270)
			(unlocked yes)
			(layer "F.Fab")
			(hide yes)
			(effects
				(font
					(size 1 1)
					(thickness 0.15)
				)
			)
		)
		(property "License" "Apache-2.0"
			(at 0 0 270)
			(unlocked yes)
			(layer "F.Fab")
			(hide yes)
			(effects
				(font
					(size 1 1)
					(thickness 0.15)
				)
			)
		)
		(sheetname "/FPGA Config/")
		(sheetfile "fpga-config.kicad_sch")
		(attr smd)
		(fp_line
			(start -0.7 1.5)
			(end -0.7 1.35)
			(stroke
				(width 0.15)
				(type solid)
			)
			(layer "F.SilkS")
		)
		(fp_line
			(start 0.7 1.5)
			(end -0.7 1.5)
			(stroke
				(width 0.15)
				(type solid)
			)
			(layer "F.SilkS")
		)
		(fp_line
			(start 0.7 0.4)
			(end 0.7 1.5)
			(stroke
				(width 0.15)
				(type solid)
			)
			(layer "F.SilkS")
		)
		(fp_line
			(start 0.7 -0.4)
			(end 0.7 -1.5)
			(stroke
				(width 0.15)
				(type solid)
			)
			(layer "F.SilkS")
		)
		(fp_line
			(start -1.45 -1.35)
			(end -0.85 -1.35)
			(stroke
				(width 0.15)
				(type solid)
			)
			(layer "F.SilkS")
		)
		(fp_line
			(start -0.85 -1.35)
			(end -0.7 -1.5)
			(stroke
				(width 0.15)
				(type solid)
			)
			(layer "F.SilkS")
		)
		(fp_line
			(start 0.7 -1.5)
			(end -0.7 -1.5)
			(stroke
				(width 0.15)
				(type solid)
			)
			(layer "F.SilkS")
		)
		(fp_line
			(start -0.85 1.65)
			(end -0.85 1.4)
			(stroke
				(width 0.05)
				(type solid)
			)
			(layer "F.CrtYd")
		)
		(fp_line
			(start 0.85 1.65)
			(end -0.85 1.65)
			(stroke
				(width 0.05)
				(type solid)
			)
			(layer "F.CrtYd")
		)
		(fp_line
			(start -1.75 1.4)
			(end -1.75 0.5)
			(stroke
				(width 0.05)
				(type solid)
			)
			(layer "F.CrtYd")
		)
		(fp_line
			(start -0.85 1.4)
			(end -1.75 1.4)
			(stroke
				(width 0.05)
				(type solid)
			)
			(layer "F.CrtYd")
		)
		(fp_line
			(start -1.75 0.5)
			(end -0.85 0.5)
			(stroke
				(width 0.05)
				(type solid)
			)
			(layer "F.CrtYd")
		)
		(fp_line
			(start -0.85 0.5)
			(end -0.85 -0.5)
			(stroke
				(width 0.05)
				(type solid)
			)
			(layer "F.CrtYd")
		)
		(fp_line
			(start 0.85 0.45)
			(end 0.85 1.65)
			(stroke
				(width 0.05)
				(type solid)
			)
			(layer "F.CrtYd")
		)
		(fp_line
			(start 1.75 0.45)
			(end 0.85 0.45)
			(stroke
				(width 0.05)
				(type solid)
			)
			(layer "F.CrtYd")
		)
		(fp_line
			(start 0.825 -0.45)
			(end 1.75 -0.45)
			(stroke
				(width 0.05)
				(type solid)
			)
			(layer "F.CrtYd")
		)
		(fp_line
			(start 1.75 -0.45)
			(end 1.75 0.45)
			(stroke
				(width 0.05)
				(type solid)
			)
			(layer "F.CrtYd")
		)
		(fp_line
			(start -1.75 -0.5)
			(end -1.75 -1.4)
			(stroke
				(width 0.05)
				(type solid)
			)
			(layer "F.CrtYd")
		)
		(fp_line
			(start -0.85 -0.5)
			(end -1.75 -0.5)
			(stroke
				(width 0.05)
				(type solid)
			)
			(layer "F.CrtYd")
		)
		(fp_line
			(start -0.9 -1.4)
			(end -1.75 -1.4)
			(stroke
				(width 0.05)
				(type solid)
			)
			(layer "F.CrtYd")
		)
		(fp_line
			(start -0.9 -1.6)
			(end -0.9 -1.4)
			(stroke
				(width 0.05)
				(type solid)
			)
			(layer "F.CrtYd")
		)
		(fp_line
			(start -0.9 -1.6)
			(end 0.825 -1.6)
			(stroke
				(width 0.05)
				(type solid)
			)
			(layer "F.CrtYd")
		)
		(fp_line
			(start 0.825 -1.6)
			(end 0.825 -0.45)
			(stroke
				(width 0.05)
				(type solid)
			)
			(layer "F.CrtYd")
		)
		(fp_line
			(start -0.712 1.519)
			(end 0.688 1.519)
			(stroke
				(width 0.15)
				(type solid)
			)
			(layer "F.Fab")
		)
		(fp_line
			(start 0.688 1.519)
			(end 0.688 -1.52)
			(stroke
				(width 0.15)
				(type solid)
			)
			(layer "F.Fab")
		)
		(fp_line
			(start -0.712 -1.325)
			(end -0.712 1.523)
			(stroke
				(width 0.15)
				(type solid)
			)
			(layer "F.Fab")
		)
		(fp_line
			(start -0.437 -1.526)
			(end -0.712 -1.325)
			(stroke
				(width 0.15)
				(type solid)
			)
			(layer "F.Fab")
		)
		(fp_line
			(start -0.437 -1.526)
			(end 0.688 -1.526)
			(stroke
				(width 0.15)
				(type solid)
			)
			(layer "F.Fab")
		)
		(fp_text user "License: Apache-2.0"
			(at -1.8 6.8 270)
			(layer "F.Fab")
			(effects
				(font
					(size 0.7 0.7)
					(thickness 0.15)
				)
				(justify left bottom)
			)
		)
		(fp_text user "Author: Antmicro"
			(at -1.837 5.3 270)
			(layer "F.Fab")
			(effects
				(font
					(size 0.7 0.7)
					(thickness 0.15)
				)
				(justify left bottom)
			)
		)
		(fp_text user "${REFERENCE}"
			(at -1.837 4 270)
			(layer "F.Fab")
			(effects
				(font
					(size 0.7 0.7)
					(thickness 0.15)
				)
				(justify left bottom)
			)
		)
		(pad "1" smd roundrect
			(at -1.1 -0.951 270)
			(size 1 0.6)
			(layers "F.Cu" "F.Mask" "F.Paste")
			(roundrect_rratio 0.15)
			(net 797 "+1V8")
			(pinfunction "IN")
			(pintype "power_in")
		)
		(pad "2" smd roundrect
			(at -1.1 0.949 270)
			(size 1 0.6)
			(layers "F.Cu" "F.Mask" "F.Paste")
			(roundrect_rratio 0.15)
			(net 160 "Net-(U30-OUT)")
			(pinfunction "OUT")
			(pintype "output")
		)
		(pad "3" smd roundrect
			(at 1.1 -0.0005 270)
			(size 1 0.6)
			(layers "F.Cu" "F.Mask" "F.Paste")
			(roundrect_rratio 0.15)
			(net 1 "GND")
			(pinfunction "GND")
			(pintype "passive")
		)
	)
	(footprint "antmicro-footprints:C_Pol_EIA-B"
		(layer "F.Cu")
		(at 207.290002 158.5 90)
		(property "Reference" "C25"
			(at 0 -2.3 90)
			(layer "F.SilkS")
			(effects
				(font
					(size 0.7 0.7)
					(thickness 0.15)
				)
				(justify left bottom)
			)
		)
		(property "Value" "C_Pol_330u_6.3V_KEMET-T520-B"
			(at 0 2.85 90)
			(layer "F.Fab")
			(effects
				(font
					(size 0.7 0.7)
					(thickness 0.15)
				)
				(justify left bottom)
			)
		)
		(property "Datasheet" "https://www.kemet.com/en/us/capacitors/product/T520B337M006ATE040.html"
			(at 0 0 90)
			(layer "F.Fab")
			(hide yes)
			(effects
				(font
					(size 1.27 1.27)
					(thickness 0.15)
				)
			)
		)
		(property "Val" "330u"
			(at 0 0 90)
			(unlocked yes)
			(layer "F.Fab")
			(hide yes)
			(effects
				(font
					(size 1 1)
					(thickness 0.15)
				)
			)
		)
		(property "MPN" "T520B337M006ATE040"
			(at 0 0 90)
			(unlocked yes)
			(layer "F.Fab")
			(hide yes)
			(effects
				(font
					(size 1 1)
					(thickness 0.15)
				)
			)
		)
		(property "Manufacturer" "KEMET"
			(at 0 0 90)
			(unlocked yes)
			(layer "F.Fab")
			(hide yes)
			(effects
				(font
					(size 1 1)
					(thickness 0.15)
				)
			)
		)
		(property "License" "Apache-2.0"
			(at 0 0 90)
			(unlocked yes)
			(layer "F.Fab")
			(hide yes)
			(effects
				(font
					(size 1 1)
					(thickness 0.15)
				)
			)
		)
		(property "Author" "Antmicro"
			(at 0 0 90)
			(unlocked yes)
			(layer "F.Fab")
			(hide yes)
			(effects
				(font
					(size 1 1)
					(thickness 0.15)
				)
			)
		)
		(property "Voltage" "6.3V"
			(at 0 0 90)
			(unlocked yes)
			(layer "F.Fab")
			(hide yes)
			(effects
				(font
					(size 1 1)
					(thickness 0.15)
				)
			)
		)
		(property "Dielectric" "template_dielectric"
			(at 0 0 90)
			(unlocked yes)
			(layer "F.Fab")
			(hide yes)
			(effects
				(font
					(size 1 1)
					(thickness 0.15)
				)
			)
		)
		(sheetname "/FPGA power/")
		(sheetfile "fpga-power.kicad_sch")
		(attr smd)
		(fp_line
			(start -2.521 -1.676)
			(end -2.123 -1.676)
			(stroke
				(width 0.15)
				(type solid)
			)
			(layer "F.SilkS")
		)
		(fp_line
			(start -1.8 -1.6)
			(end 1.8 -1.6)
			(stroke
				(width 0.15)
				(type solid)
			)
			(layer "F.SilkS")
		)
		(fp_line
			(start -2.325 -1.475)
			(end -2.325 -1.878)
			(stroke
				(width 0.15)
				(type solid)
			)
			(layer "F.SilkS")
		)
		(fp_line
			(start 1.8 -1.3)
			(end 1.8 -1.6)
			(stroke
				(width 0.15)
				(type solid)
			)
			(layer "F.SilkS")
		)
		(fp_line
			(start -1.8 -1.3)
			(end -1.8 -1.6)
			(stroke
				(width 0.15)
				(type solid)
			)
			(layer "F.SilkS")
		)
		(fp_line
			(start 1.8 1.3)
			(end 1.8 1.6)
			(stroke
				(width 0.15)
				(type solid)
			)
			(layer "F.SilkS")
		)
		(fp_line
			(start -1.8 1.3)
			(end -1.8 1.6)
			(stroke
				(width 0.15)
				(type solid)
			)
			(layer "F.SilkS")
		)
		(fp_line
			(start 1.8 1.6)
			(end -1.8 1.6)
			(stroke
				(width 0.15)
				(type solid)
			)
			(layer "F.SilkS")
		)
		(fp_line
			(start 1.959 -1.75)
			(end -1.97 -1.75)
			(stroke
				(width 0.05)
				(type solid)
			)
			(layer "F.CrtYd")
		)
		(fp_line
			(start 1.959 -1.75)
			(end 1.959 -1.35)
			(stroke
				(width 0.05)
				(type solid)
			)
			(layer "F.CrtYd")
		)
		(fp_line
			(start -1.97 -1.75)
			(end -1.97 -1.35)
			(stroke
				(width 0.05)
				(type solid)
			)
			(layer "F.CrtYd")
		)
		(fp_line
			(start 2.399 -1.35)
			(end 1.959 -1.35)
			(stroke
				(width 0.05)
				(type solid)
			)
			(layer "F.CrtYd")
		)
		(fp_line
			(start 2.399 -1.35)
			(end 2.4 1.35)
			(stroke
				(width 0.05)
				(type solid)
			)
			(layer "F.CrtYd")
		)
		(fp_line
			(start -1.97 -1.35)
			(end -2.41 -1.35)
			(stroke
				(width 0.05)
				(type solid)
			)
			(layer "F.CrtYd")
		)
		(fp_line
			(start -2.411 -1.35)
			(end -2.41 1.35)
			(stroke
				(width 0.05)
				(type solid)
			)
			(layer "F.CrtYd")
		)
		(fp_line
			(start 2.4 1.35)
			(end 1.96 1.35)
			(stroke
				(width 0.05)
				(type solid)
			)
			(layer "F.CrtYd")
		)
		(fp_line
			(start 1.96 1.35)
			(end 1.96 1.75)
			(stroke
				(width 0.05)
				(type solid)
			)
			(layer "F.CrtYd")
		)
		(fp_line
			(start -1.97 1.35)
			(end -2.41 1.35)
			(stroke
				(width 0.05)
				(type solid)
			)
			(layer "F.CrtYd")
		)
		(fp_line
			(start -1.97 1.35)
			(end -1.97 1.75)
			(stroke
				(width 0.05)
				(type solid)
			)
			(layer "F.CrtYd")
		)
		(fp_line
			(start 1.96 1.75)
			(end -1.97 1.75)
			(stroke
				(width 0.05)
				(type solid)
			)
			(layer "F.CrtYd")
		)
		(fp_line
			(start -1.7 1.324)
			(end -1.551 1.475)
			(stroke
				(width 0.15)
				(type solid)
			)
			(layer "F.Fab")
		)
		(fp_rect
			(start -1.72 -1.5)
			(end 1.719 1.499)
			(stroke
				(width 0.15)
				(type solid)
			)
			(fill no)
			(layer "F.Fab")
		)
		(fp_text user "Author: Antmicro"
			(at -2.665 6.85 90)
			(layer "F.Fab")
			(effects
				(font
					(size 0.7 0.7)
					(thickness 0.15)
				)
				(justify left bottom)
			)
		)
		(fp_text user "License: Apache-2.0"
			(at -2.665 5.65 90)
			(layer "F.Fab")
			(effects
				(font
					(size 0.7 0.7)
					(thickness 0.15)
				)
				(justify left bottom)
			)
		)
		(fp_text user "${REFERENCE}"
			(at -2.665 4.45 90)
			(layer "F.Fab")
			(effects
				(font
					(size 0.7 0.7)
					(thickness 0.15)
				)
				(justify left bottom)
			)
		)
		(pad "1" smd roundrect
			(at -1.551 0 90)
			(size 1.2 2.2)
			(layers "F.Cu" "F.Mask" "F.Paste")
			(roundrect_rratio 0.1)
			(net 553 "+0V85")
			(pintype "passive")
		)
		(pad "2" smd roundrect
			(at 1.55 0 90)
			(size 1.2 2.2)
			(layers "F.Cu" "F.Mask" "F.Paste")
			(roundrect_rratio 0.1)
			(net 1 "GND")
			(pintype "passive")
		)
	)
	(footprint "antmicro-footprints:SC70-3"
		(layer "F.Cu")
		(at 250.274499 137.899)
		(property "Reference" "Q17"
			(at 0.545501 1.111 90)
			(layer "F.SilkS")
			(effects
				(font
					(size 0.7 0.7)
					(thickness 0.15)
				)
				(justify left bottom)
			)
		)
		(property "Value" "BSS138PW"
			(at 0 2.3 0)
			(layer "F.Fab")
			(effects
				(font
					(size 0.7 0.7)
					(thickness 0.15)
				)
				(justify left bottom)
			)
		)
		(property "Datasheet" "https://assets.nexperia.com/documents/data-sheet/BSS138PW.pdf"
			(at 0 0 0)
			(layer "F.Fab")
			(hide yes)
			(effects
				(font
					(size 1.27 1.27)
					(thickness 0.15)
				)
			)
		)
		(property "MPN" "BSS138PW"
			(at 0 0 0)
			(unlocked yes)
			(layer "F.Fab")
			(hide yes)
			(effects
				(font
					(size 1 1)
					(thickness 0.15)
				)
			)
		)
		(property "Manufacturer" "Nexperia"
			(at 0 0 0)
			(unlocked yes)
			(layer "F.Fab")
			(hide yes)
			(effects
				(font
					(size 1 1)
					(thickness 0.15)
				)
			)
		)
		(property "Author" "Antmicro"
			(at 0 0 0)
			(unlocked yes)
			(layer "F.Fab")
			(hide yes)
			(effects
				(font
					(size 1 1)
					(thickness 0.15)
				)
			)
		)
		(property "License" "Apache-2.0"
			(at 0 0 0)
			(unlocked yes)
			(layer "F.Fab")
			(hide yes)
			(effects
				(font
					(size 1 1)
					(thickness 0.15)
				)
			)
		)
		(sheetname "/Supply/")
		(sheetfile "supply.kicad_sch")
		(attr smd)
		(fp_line
			(start -0.3 -1)
			(end 0.627 -0.999)
			(stroke
				(width 0.15)
				(type solid)
			)
			(layer "F.SilkS")
		)
		(fp_line
			(start -0.3 1)
			(end 0.627 1.001)
			(stroke
				(width 0.15)
				(type solid)
			)
			(layer "F.SilkS")
		)
		(fp_line
			(start 0.627 -0.6)
			(end 0.627 -0.999)
			(stroke
				(width 0.15)
				(type solid)
			)
			(layer "F.SilkS")
		)
		(fp_line
			(start 0.627 0.6)
			(end 0.627 1.001)
			(stroke
				(width 0.15)
				(type solid)
			)
			(layer "F.SilkS")
		)
		(fp_line
			(start -1.4 1)
			(end -1.4 -1)
			(stroke
				(width 0.05)
				(type solid)
			)
			(layer "F.CrtYd")
		)
		(fp_line
			(start -0.9 -1.3)
			(end -0.9 -1)
			(stroke
				(width 0.05)
				(type solid)
			)
			(layer "F.CrtYd")
		)
		(fp_line
			(start -0.9 -1.3)
			(end 0.9 -1.3)
			(stroke
				(width 0.05)
				(type solid)
			)
			(layer "F.CrtYd")
		)
		(fp_line
			(start -0.9 -1)
			(end -1.4 -1)
			(stroke
				(width 0.05)
				(type solid)
			)
			(layer "F.CrtYd")
		)
		(fp_line
			(start -0.9 1)
			(end -1.4 1)
			(stroke
				(width 0.05)
				(type solid)
			)
			(layer "F.CrtYd")
		)
		(fp_line
			(start -0.9 1.3)
			(end -0.9 1)
			(stroke
				(width 0.05)
				(type solid)
			)
			(layer "F.CrtYd")
		)
		(fp_line
			(start 0.9 -1.3)
			(end 0.9 -0.4)
			(stroke
				(width 0.05)
				(type solid)
			)
			(layer "F.CrtYd")
		)
		(fp_line
			(start 0.9 -0.4)
			(end 1.4 -0.4)
			(stroke
				(width 0.05)
				(type solid)
			)
			(layer "F.CrtYd")
		)
		(fp_line
			(start 0.9 0.4)
			(end 0.9 1.3)
			(stroke
				(width 0.05)
				(type solid)
			)
			(layer "F.CrtYd")
		)
		(fp_line
			(start 0.9 1.3)
			(end -0.9 1.3)
			(stroke
				(width 0.05)
				(type solid)
			)
			(layer "F.CrtYd")
		)
		(fp_line
			(start 1.4 -0.4)
			(end 1.4 0.4)
			(stroke
				(width 0.05)
				(type solid)
			)
			(layer "F.CrtYd")
		)
		(fp_line
			(start 1.4 0.4)
			(end 0.9 0.4)
			(stroke
				(width 0.05)
				(type solid)
			)
			(layer "F.CrtYd")
		)
		(fp_rect
			(start -0.623 -0.999)
			(end 0.627 1.001)
			(stroke
				(width 0.15)
				(type solid)
			)
			(fill no)
			(layer "F.Fab")
		)
		(fp_text user "Author: Antmicro"
			(at -1.45 5.782 0)
			(layer "F.Fab")
			(effects
				(font
					(size 0.7 0.7)
					(thickness 0.15)
				)
				(justify left bottom)
			)
		)
		(fp_text user "License: Apache-2.0"
			(at -1.45 6.782 0)
			(layer "F.Fab")
			(effects
				(font
					(size 0.7 0.7)
					(thickness 0.15)
				)
				(justify left bottom)
			)
		)
		(fp_text user "${REFERENCE}"
			(at -1.45 4.783 0)
			(layer "F.Fab")
			(effects
				(font
					(size 0.7 0.7)
					(thickness 0.15)
				)
				(justify left bottom)
			)
		)
		(pad "1" smd rect
			(at -1.051 -0.65 90)
			(size 0.6 0.6)
			(layers "F.Cu" "F.Mask" "F.Paste")
			(net 287 "Net-(Q17-G)")
			(pinfunction "G")
			(pintype "passive")
		)
		(pad "2" smd rect
			(at -1.051 0.65 90)
			(size 0.6 0.6)
			(layers "F.Cu" "F.Mask" "F.Paste")
			(net 1 "GND")
			(pinfunction "S")
			(pintype "passive")
		)
		(pad "3" smd rect
			(at 1.05 0 90)
			(size 0.6 0.6)
			(layers "F.Cu" "F.Mask" "F.Paste")
			(net 625 "Net-(Q17-D)")
			(pinfunction "D")
			(pintype "passive")
		)
	)
	(footprint "antmicro-footprints:C_0603_1608Metric"
		(layer "F.Cu")
		(at 257 177.9)
		(descr "Capacitor SMD 0603")
		(tags "capacitor 0603")
		(property "Reference" "C260"
			(at 1.25 0.2 0)
			(layer "F.SilkS")
			(effects
				(font
					(size 0.7 0.7)
					(thickness 0.15)
				)
				(justify left bottom)
			)
		)
		(property "Value" "C_22u_0603"
			(at -1.42757 1.770288 0)
			(layer "F.Fab")
			(effects
				(font
					(size 0.7 0.7)
					(thickness 0.15)
				)
				(justify left bottom)
			)
		)
		(property "Datasheet" "https://www.murata.com/products/productdetail?partno=GRM188R60J226MEA0%23"
			(at 0 0 0)
			(layer "F.Fab")
			(hide yes)
			(effects
				(font
					(size 1.27 1.27)
					(thickness 0.15)
				)
			)
		)
		(property "Manufacturer" "Murata"
			(at 0 0 0)
			(unlocked yes)
			(layer "F.Fab")
			(hide yes)
			(effects
				(font
					(size 1 1)
					(thickness 0.15)
				)
			)
		)
		(property "MPN" "GRM188R60J226MEA0D"
			(at 0 0 0)
			(unlocked yes)
			(layer "F.Fab")
			(hide yes)
			(effects
				(font
					(size 1 1)
					(thickness 0.15)
				)
			)
		)
		(property "Val" "22u"
			(at 0 0 0)
			(unlocked yes)
			(layer "F.Fab")
			(hide yes)
			(effects
				(font
					(size 1 1)
					(thickness 0.15)
				)
			)
		)
		(property "License" "Apache-2.0"
			(at 0 0 0)
			(unlocked yes)
			(layer "F.Fab")
			(hide yes)
			(effects
				(font
					(size 1 1)
					(thickness 0.15)
				)
			)
		)
		(property "Author" "Antmicro"
			(at 0 0 0)
			(unlocked yes)
			(layer "F.Fab")
			(hide yes)
			(effects
				(font
					(size 1 1)
					(thickness 0.15)
				)
			)
		)
		(property "Voltage" ""
			(at 0 0 0)
			(unlocked yes)
			(layer "F.Fab")
			(hide yes)
			(effects
				(font
					(size 1 1)
					(thickness 0.15)
				)
			)
		)
		(property "Dielectric" ""
			(at 0 0 0)
			(unlocked yes)
			(layer "F.Fab")
			(hide yes)
			(effects
				(font
					(size 1 1)
					(thickness 0.15)
				)
			)
		)
		(sheetname "/Supply/DC-DC AUX, MGT/")
		(sheetfile "dc-dc-aux-mgt.kicad_sch")
		(attr smd)
		(fp_line
			(start -0.15 -0.4)
			(end 0.15 -0.4)
			(stroke
				(width 0.15)
				(type solid)
			)
			(layer "F.SilkS")
		)
		(fp_line
			(start -0.15 0.4)
			(end 0.15 0.4)
			(stroke
				(width 0.15)
				(type solid)
			)
			(layer "F.SilkS")
		)
		(fp_rect
			(start -1.25 -0.65)
			(end 1.25 0.65)
			(stroke
				(width 0.05)
				(type solid)
			)
			(fill no)
			(layer "F.CrtYd")
		)
		(fp_rect
			(start -0.8 -0.4)
			(end 0.8 0.4)
			(stroke
				(width 0.15)
				(type solid)
			)
			(fill no)
			(layer "F.Fab")
		)
		(fp_text user "Author: Antmicro"
			(at -1.682 4.894 0)
			(layer "F.Fab")
			(effects
				(font
					(size 0.7 0.7)
					(thickness 0.15)
				)
				(justify left bottom)
			)
		)
		(fp_text user "License: Apache-2.0"
			(at -1.682 5.895 0)
			(layer "F.Fab")
			(effects
				(font
					(size 0.7 0.7)
					(thickness 0.15)
				)
				(justify left bottom)
			)
		)
		(fp_text user "${REFERENCE}"
			(at -1.682 3.895 0)
			(layer "F.Fab")
			(effects
				(font
					(size 0.7 0.7)
					(thickness 0.15)
				)
				(justify left bottom)
			)
		)
		(pad "1" smd roundrect
			(at -0.7 0)
			(size 0.8 1)
			(layers "F.Cu" "F.Mask" "F.Paste")
			(roundrect_rratio 0.2)
			(net 1 "GND")
			(pintype "passive")
		)
		(pad "2" smd roundrect
			(at 0.7 0)
			(size 0.8 1)
			(layers "F.Cu" "F.Mask" "F.Paste")
			(roundrect_rratio 0.2)
			(net 225 "/Supply/DC-DC AUX, MGT/MGTAVCCAUX_local")
			(pintype "passive")
		)
	)
	(footprint "antmicro-footprints:VSSOP-8_2.3x2mm_P0.5mm"
		(layer "F.Cu")
		(at 239.274499 186.499)
		(property "Reference" "U23"
			(at -1.15 2.1 0)
			(layer "F.SilkS")
			(effects
				(font
					(size 0.7 0.7)
					(thickness 0.15)
				)
				(justify left bottom)
			)
		)
		(property "Value" "TS5A3359_VSSOP"
			(at 0 2.258 0)
			(layer "F.Fab")
			(effects
				(font
					(size 0.7 0.7)
					(thickness 0.15)
				)
				(justify left bottom)
			)
		)
		(property "Datasheet" "https://www.ti.com/general/docs/suppproductinfo.tsp?distId=26&gotoUrl=http%3A%2F%2Fwww.ti.com%2Flit%2Fgpn%2Fts5a3359"
			(at 0 0 0)
			(layer "F.Fab")
			(hide yes)
			(effects
				(font
					(size 1.27 1.27)
					(thickness 0.15)
				)
			)
		)
		(property "MPN" "TS5A3359DCUR"
			(at 0 0 0)
			(unlocked yes)
			(layer "F.Fab")
			(hide yes)
			(effects
				(font
					(size 1 1)
					(thickness 0.15)
				)
			)
		)
		(property "Manufacturer" "Texas Instruments"
			(at 0 0 0)
			(unlocked yes)
			(layer "F.Fab")
			(hide yes)
			(effects
				(font
					(size 1 1)
					(thickness 0.15)
				)
			)
		)
		(property "Author" "Antmicro"
			(at 0 0 0)
			(unlocked yes)
			(layer "F.Fab")
			(hide yes)
			(effects
				(font
					(size 1 1)
					(thickness 0.15)
				)
			)
		)
		(property "License" "Apache-2.0"
			(at 0 0 0)
			(unlocked yes)
			(layer "F.Fab")
			(hide yes)
			(effects
				(font
					(size 1 1)
					(thickness 0.15)
				)
			)
		)
		(sheetname "/I^{2}C + I3C/")
		(sheetfile "i2c.kicad_sch")
		(attr smd)
		(fp_line
			(start -0.82 -0.992)
			(end 0.825 -0.992)
			(stroke
				(width 0.15)
				(type solid)
			)
			(layer "F.SilkS")
		)
		(fp_line
			(start 0.825 1.007)
			(end -0.82 1.007)
			(stroke
				(width 0.15)
				(type solid)
			)
			(layer "F.SilkS")
		)
		(fp_circle
			(center -1.402 -1.192)
			(end -1.352 -1.192)
			(stroke
				(width 0.15)
				(type solid)
			)
			(fill yes)
			(layer "F.SilkS")
		)
		(fp_rect
			(start 1.8 1.35)
			(end -1.8 -1.35)
			(stroke
				(width 0.05)
				(type solid)
			)
			(fill no)
			(layer "F.CrtYd")
		)
		(fp_line
			(start -0.7 -0.99)
			(end -1.14 -0.55)
			(stroke
				(width 0.15)
				(type solid)
			)
			(layer "F.Fab")
		)
		(fp_rect
			(start -1.147 -0.992)
			(end 1.151 1.007)
			(stroke
				(width 0.15)
				(type solid)
			)
			(fill no)
			(layer "F.Fab")
		)
		(fp_text user "License: Apache-2.0"
			(at -1.8 6.408 0)
			(layer "F.Fab")
			(effects
				(font
					(size 0.7 0.7)
					(thickness 0.15)
				)
				(justify left bottom)
			)
		)
		(fp_text user "Author: Antmicro"
			(at -1.8 5.208 0)
			(layer "F.Fab")
			(effects
				(font
					(size 0.7 0.7)
					(thickness 0.15)
				)
				(justify left bottom)
			)
		)
		(fp_text user "${REFERENCE}"
			(at -1.8 4.006 0)
			(layer "F.Fab")
			(effects
				(font
					(size 0.7 0.7)
					(thickness 0.15)
				)
				(justify left bottom)
			)
		)
		(pad "1" smd rect
			(at -1.372 -0.742)
			(size 0.75 0.4)
			(layers "F.Cu" "F.Mask" "F.Paste")
			(net 472 "/FPGA banks HD/FPGA_DDR.SDA")
			(pinfunction "NO1")
			(pintype "passive")
		)
		(pad "2" smd rect
			(at -1.372 -0.244)
			(size 0.75 0.3)
			(layers "F.Cu" "F.Mask" "F.Paste")
			(net 746 "/FPGA Config/FPGA_PWR.SDA")
			(pinfunction "NO2")
			(pintype "passive")
		)
		(pad "3" smd rect
			(at -1.372 0.256)
			(size 0.75 0.3)
			(layers "F.Cu" "F.Mask" "F.Paste")
			(net 527 "/Debug FTDI + VNA/FTDI.SDA")
			(pinfunction "NO3")
			(pintype "passive")
		)
		(pad "4" smd rect
			(at -1.372 0.757)
			(size 0.75 0.4)
			(layers "F.Cu" "F.Mask" "F.Paste")
			(net 1 "GND")
			(pinfunction "GND")
			(pintype "passive")
		)
		(pad "5" smd rect
			(at 1.377 0.757)
			(size 0.75 0.4)
			(layers "F.Cu" "F.Mask" "F.Paste")
			(net 405 "IN2")
			(pinfunction "IN2")
			(pintype "passive")
		)
		(pad "6" smd rect
			(at 1.377 0.256)
			(size 0.75 0.3)
			(layers "F.Cu" "F.Mask" "F.Paste")
			(net 404 "IN1")
			(pinfunction "IN1")
			(pintype "passive")
		)
		(pad "7" smd rect
			(at 1.377 -0.244)
			(size 0.75 0.3)
			(layers "F.Cu" "F.Mask" "F.Paste")
			(net 533 "/I^{2}C + I3C/PWR.SDA")
			(pinfunction "COM")
			(pintype "passive")
		)
		(pad "8" smd rect
			(at 1.377 -0.742)
			(size 0.75 0.4)
			(layers "F.Cu" "F.Mask" "F.Paste")
			(net 38 "+3V3_AON")
			(pinfunction "VCC")
			(pintype "passive")
		)
	)
	(footprint "antmicro-footprints:R_0402_1005Metric"
		(layer "F.Cu")
		(at 119.15 149.61 180)
		(descr "Resistor SMD 0402")
		(tags "resistor SMD 0402")
		(property "Reference" "R24"
			(at -5.11 -0.415 0)
			(layer "F.SilkS")
			(effects
				(font
					(size 0.7 0.7)
					(thickness 0.15)
				)
				(justify right bottom)
			)
		)
		(property "Value" "R_49k9_0402"
			(at -1.011843 1.772047 0)
			(layer "F.Fab")
			(effects
				(font
					(size 0.7 0.7)
					(thickness 0.15)
				)
				(justify right bottom)
			)
		)
		(property "Datasheet" "https://www.bourns.com/docs/product-datasheets/cr.pdf"
			(at 0 0 180)
			(layer "F.Fab")
			(hide yes)
			(effects
				(font
					(size 1.27 1.27)
					(thickness 0.15)
				)
			)
		)
		(property "MPN" "CR0402-FX-4992GLF"
			(at 0 0 180)
			(unlocked yes)
			(layer "F.Fab")
			(hide yes)
			(effects
				(font
					(size 1 1)
					(thickness 0.15)
				)
			)
		)
		(property "Manufacturer" "Bourns"
			(at 0 0 180)
			(unlocked yes)
			(layer "F.Fab")
			(hide yes)
			(effects
				(font
					(size 1 1)
					(thickness 0.15)
				)
			)
		)
		(property "License" "Apache-2.0"
			(at 0 0 180)
			(unlocked yes)
			(layer "F.Fab")
			(hide yes)
			(effects
				(font
					(size 1 1)
					(thickness 0.15)
				)
			)
		)
		(property "Author" "Antmicro"
			(at 0 0 180)
			(unlocked yes)
			(layer "F.Fab")
			(hide yes)
			(effects
				(font
					(size 1 1)
					(thickness 0.15)
				)
			)
		)
		(property "Val" "49k9"
			(at 0 0 180)
			(unlocked yes)
			(layer "F.Fab")
			(hide yes)
			(effects
				(font
					(size 1 1)
					(thickness 0.15)
				)
			)
		)
		(property "Tolerance" "1%"
			(at 0 0 180)
			(unlocked yes)
			(layer "F.Fab")
			(hide yes)
			(effects
				(font
					(size 1 1)
					(thickness 0.15)
				)
			)
		)
		(sheetname "/HDMI + SD Card/")
		(sheetfile "hdmi-sd-card.kicad_sch")
		(attr smd)
		(fp_rect
			(start -0.925 -0.47)
			(end 0.925 0.47)
			(stroke
				(width 0.05)
				(type default)
			)
			(fill no)
			(layer "F.CrtYd")
		)
		(fp_rect
			(start -0.5 -0.25)
			(end 0.5 0.25)
			(stroke
				(width 0.15)
				(type solid)
			)
			(fill no)
			(layer "F.Fab")
		)
		(fp_text user "${REFERENCE}"
			(at -0.95 3.168 180)
			(layer "F.Fab")
			(effects
				(font
					(size 0.7 0.7)
					(thickness 0.15)
				)
				(justify left bottom)
			)
		)
		(fp_text user "License: Apache-2.0"
			(at -0.95 5.169 180)
			(layer "F.Fab")
			(effects
				(font
					(size 0.7 0.7)
					(thickness 0.15)
				)
				(justify left bottom)
			)
		)
		(fp_text user "Author: Antmicro"
			(at -0.95 4.169 180)
			(layer "F.Fab")
			(effects
				(font
					(size 0.7 0.7)
					(thickness 0.15)
				)
				(justify left bottom)
			)
		)
		(pad "1" smd roundrect
			(at -0.48 0 180)
			(size 0.59 0.64)
			(layers "F.Cu" "F.Mask" "F.Paste")
			(roundrect_rratio 0.25)
			(net 673 "Net-(L3-Pad2)")
			(pintype "passive")
		)
		(pad "2" smd roundrect
			(at 0.48 0 180)
			(size 0.59 0.64)
			(layers "F.Cu" "F.Mask" "F.Paste")
			(roundrect_rratio 0.25)
			(net 322 "Net-(C300-Pad2)")
			(pintype "passive")
		)
	)
	(footprint "antmicro-footprints:L_0402_1005Metric"
		(layer "F.Cu")
		(at 121.025 152.61 180)
		(descr "Inductor SMD 0402")
		(tags "Inductor SMD 0402")
		(property "Reference" "L9"
			(at -5.425 -0.415 0)
			(layer "F.SilkS")
			(effects
				(font
					(size 0.7 0.7)
					(thickness 0.15)
				)
				(justify right bottom)
			)
		)
		(property "Value" "L_20n_0.35A_0402"
			(at 0 1.4 0)
			(layer "F.Fab")
			(effects
				(font
					(size 0.7 0.7)
					(thickness 0.15)
				)
				(justify right bottom)
			)
		)
		(property "Datasheet" "https://product.tdk.com/system/files/dam/doc/product/inductor/inductor/smd/catalog/inductor_automotive_high-frequency_mlg1005s_en.pdf?ref_disty=mouser"
			(at 0 0 180)
			(layer "F.Fab")
			(hide yes)
			(effects
				(font
					(size 1.27 1.27)
					(thickness 0.15)
				)
			)
		)
		(property "Val" "20n/0.35A"
			(at 0 0 180)
			(unlocked yes)
			(layer "F.Fab")
			(hide yes)
			(effects
				(font
					(size 1 1)
					(thickness 0.15)
				)
			)
		)
		(property "Manufacturer" "TDK"
			(at 0 0 180)
			(unlocked yes)
			(layer "F.Fab")
			(hide yes)
			(effects
				(font
					(size 1 1)
					(thickness 0.15)
				)
			)
		)
		(property "MPN" "MLG1005S20NJTD25"
			(at 0 0 180)
			(unlocked yes)
			(layer "F.Fab")
			(hide yes)
			(effects
				(font
					(size 1 1)
					(thickness 0.15)
				)
			)
		)
		(property "ISat" ""
			(at 0 0 180)
			(unlocked yes)
			(layer "F.Fab")
			(hide yes)
			(effects
				(font
					(size 1 1)
					(thickness 0.15)
				)
			)
		)
		(property "IMax" "0.35 A"
			(at 0 0 180)
			(unlocked yes)
			(layer "F.Fab")
			(hide yes)
			(effects
				(font
					(size 1 1)
					(thickness 0.15)
				)
			)
		)
		(property "Size" "1.0x0.5"
			(at 0 0 180)
			(unlocked yes)
			(layer "F.Fab")
			(hide yes)
			(effects
				(font
					(size 1 1)
					(thickness 0.15)
				)
			)
		)
		(property "Author" "Antmicro"
			(at 0 0 180)
			(unlocked yes)
			(layer "F.Fab")
			(hide yes)
			(effects
				(font
					(size 1 1)
					(thickness 0.15)
				)
			)
		)
		(property "License" "Apache-2.0"
			(at 0 0 180)
			(unlocked yes)
			(layer "F.Fab")
			(hide yes)
			(effects
				(font
					(size 1 1)
					(thickness 0.15)
				)
			)
		)
		(sheetname "/HDMI + SD Card/")
		(sheetfile "hdmi-sd-card.kicad_sch")
		(attr smd)
		(fp_rect
			(start -0.925 -0.47)
			(end 0.925 0.47)
			(stroke
				(width 0.05)
				(type default)
			)
			(fill no)
			(layer "F.CrtYd")
		)
		(fp_rect
			(start -0.499 -0.249)
			(end 0.499 0.249)
			(stroke
				(width 0.15)
				(type solid)
			)
			(fill no)
			(layer "F.Fab")
		)
		(fp_text user "License: Apache-2.0"
			(at -0.932 5.17 180)
			(layer "F.Fab")
			(effects
				(font
					(size 0.7 0.7)
					(thickness 0.15)
				)
				(justify left bottom)
			)
		)
		(fp_text user "${REFERENCE}"
			(at -0.932 3.168 180)
			(layer "F.Fab")
			(effects
				(font
					(size 0.7 0.7)
					(thickness 0.15)
				)
				(justify left bottom)
			)
		)
		(fp_text user "Author: Antmicro"
			(at -0.932 4.17 180)
			(layer "F.Fab")
			(effects
				(font
					(size 0.7 0.7)
					(thickness 0.15)
				)
				(justify left bottom)
			)
		)
		(pad "1" smd roundrect
			(at -0.48 0 180)
			(size 0.59 0.64)
			(layers "F.Cu" "F.Mask" "F.Paste")
			(roundrect_rratio 0.25)
			(net 349 "/FPGA MGT Interface/HDMI_IN.D0_N")
			(pintype "passive")
		)
		(pad "2" smd roundrect
			(at 0.48 0 180)
			(size 0.59 0.64)
			(layers "F.Cu" "F.Mask" "F.Paste")
			(roundrect_rratio 0.25)
			(net 679 "Net-(L9-Pad2)")
			(pintype "passive")
		)
	)
	(footprint "antmicro-footprints:Mech_Lightpipe_Mentor_1296.2013"
		(layer "F.Cu")
		(at 107.185 114.725 90)
		(property "Reference" "H2"
			(at 0 -0.5 180)
			(unlocked yes)
			(layer "F.SilkS")
			(hide yes)
			(effects
				(font
					(size 0.7 0.7)
					(thickness 0.15)
				)
				(justify left bottom)
			)
		)
		(property "Value" "Lightpipe_Mentor_1296.2013"
			(at -1.75 6.25 90)
			(unlocked yes)
			(layer "F.Fab")
			(effects
				(font
					(size 0.7 0.7)
					(thickness 0.15)
				)
				(justify left bottom)
			)
		)
		(property "Datasheet" "https://docs.rs-online.com/e47b/0900766b813f6efb.pdf"
			(at 0 0 90)
			(layer "F.Fab")
			(hide yes)
			(effects
				(font
					(size 1.27 1.27)
					(thickness 0.15)
				)
			)
		)
		(property "Manufacturer" "Mentor Worldwide"
			(at 0 0 90)
			(unlocked yes)
			(layer "F.Fab")
			(hide yes)
			(effects
				(font
					(size 1 1)
					(thickness 0.15)
				)
			)
		)
		(property "MPN" "1296.2013"
			(at 0 0 90)
			(unlocked yes)
			(layer "F.Fab")
			(hide yes)
			(effects
				(font
					(size 1 1)
					(thickness 0.15)
				)
			)
		)
		(property "Author" "Antmicro"
			(at 0 0 90)
			(unlocked yes)
			(layer "F.Fab")
			(hide yes)
			(effects
				(font
					(size 1 1)
					(thickness 0.15)
				)
			)
		)
		(property "License" "Apache-2.0"
			(at 0 0 90)
			(unlocked yes)
			(layer "F.Fab")
			(hide yes)
			(effects
				(font
					(size 1 1)
					(thickness 0.15)
				)
			)
		)
		(sheetname "/")
		(sheetfile "data-center-rdimm-ddr5-tester.kicad_sch")
		(attr exclude_from_pos_files)
		(fp_rect
			(start -1.508 -6.335)
			(end 1.507 5.289)
			(stroke
				(width 0.15)
				(type solid)
			)
			(fill no)
			(layer "F.SilkS")
		)
		(fp_text user "License: Apache-2.0"
			(at -1.75 10.25 90)
			(layer "F.Fab")
			(effects
				(font
					(size 0.7 0.7)
					(thickness 0.15)
				)
				(justify left bottom)
			)
		)
		(fp_text user "${REFERENCE}"
			(at -1.75 7.5 90)
			(layer "F.Fab")
			(effects
				(font
					(size 0.7 0.7)
					(thickness 0.15)
				)
				(justify left bottom)
			)
		)
		(fp_text user "Author: Antmicro"
			(at -1.75 8.75 90)
			(layer "F.Fab")
			(effects
				(font
					(size 0.7 0.7)
					(thickness 0.15)
				)
				(justify left bottom)
			)
		)
		(pad "" np_thru_hole circle
			(at 0 -4.96 90)
			(size 1.2 1.2)
			(drill 1.2)
			(layers "*.Cu" "*.Mask")
		)
		(pad "" np_thru_hole circle
			(at 0 4.24 90)
			(size 1.2 1.2)
			(drill 1.2)
			(layers "*.Cu" "*.Mask")
		)
	)
	(footprint "antmicro-footprints:SOT-323"
		(layer "F.Cu")
		(at 119.43 139.53 -90)
		(property "Reference" "Q20"
			(at 0 -2.5 90)
			(layer "F.SilkS")
			(effects
				(font
					(size 0.7 0.7)
					(thickness 0.15)
				)
				(justify right bottom)
			)
		)
		(property "Value" "BSS84AKW"
			(at 0 2.749 90)
			(layer "F.Fab")
			(effects
				(font
					(size 0.7 0.7)
					(thickness 0.15)
				)
				(justify right bottom)
			)
		)
		(property "Datasheet" "https://assets.nexperia.com/documents/data-sheet/BSS84AKW.pdf"
			(at 0 0 270)
			(layer "F.Fab")
			(hide yes)
			(effects
				(font
					(size 1.27 1.27)
					(thickness 0.15)
				)
			)
		)
		(property "MPN" "BSS84AKW,115"
			(at 0 0 270)
			(unlocked yes)
			(layer "F.Fab")
			(hide yes)
			(effects
				(font
					(size 1 1)
					(thickness 0.15)
				)
			)
		)
		(property "Manufacturer" "Nexperia"
			(at 0 0 270)
			(unlocked yes)
			(layer "F.Fab")
			(hide yes)
			(effects
				(font
					(size 1 1)
					(thickness 0.15)
				)
			)
		)
		(property "Author" "Antmicro"
			(at 0 0 270)
			(unlocked yes)
			(layer "F.Fab")
			(hide yes)
			(effects
				(font
					(size 1 1)
					(thickness 0.15)
				)
			)
		)
		(property "License" "Apache-2.0"
			(at 0 0 270)
			(unlocked yes)
			(layer "F.Fab")
			(hide yes)
			(effects
				(font
					(size 1 1)
					(thickness 0.15)
				)
			)
		)
		(sheetname "/Debug FTDI + VNA/")
		(sheetfile "debug-ftdi.kicad_sch")
		(attr smd)
		(fp_line
			(start -0.802 1.199)
			(end -0.5 1.199)
			(stroke
				(width 0.15)
				(type solid)
			)
			(layer "F.SilkS")
		)
		(fp_line
			(start 0.498 1.199)
			(end 0.8 1.199)
			(stroke
				(width 0.15)
				(type solid)
			)
			(layer "F.SilkS")
		)
		(fp_line
			(start 0.8 1.199)
			(end 0.8 0.9)
			(stroke
				(width 0.15)
				(type solid)
			)
			(layer "F.SilkS")
		)
		(fp_line
			(start -0.802 1.05)
			(end -0.802 1.199)
			(stroke
				(width 0.15)
				(type solid)
			)
			(layer "F.SilkS")
		)
		(fp_line
			(start -0.802 -1.2)
			(end -0.802 -1.05)
			(stroke
				(width 0.15)
				(type solid)
			)
			(layer "F.SilkS")
		)
		(fp_line
			(start -0.402 -1.2)
			(end -0.802 -1.2)
			(stroke
				(width 0.15)
				(type solid)
			)
			(layer "F.SilkS")
		)
		(fp_line
			(start 0.498 -1.2)
			(end 0.8 -1.2)
			(stroke
				(width 0.15)
				(type solid)
			)
			(layer "F.SilkS")
		)
		(fp_line
			(start 0.8 -1.2)
			(end 0.8 -0.902)
			(stroke
				(width 0.15)
				(type solid)
			)
			(layer "F.SilkS")
		)
		(fp_circle
			(center -1.05 -1.156824)
			(end -1 -1.129824)
			(stroke
				(width 0.15)
				(type solid)
			)
			(fill no)
			(layer "F.SilkS")
		)
		(fp_rect
			(start -1.35 -1.35)
			(end 1.35 1.35)
			(stroke
				(width 0.05)
				(type solid)
			)
			(fill no)
			(layer "F.CrtYd")
		)
		(fp_line
			(start -0.677 1.1)
			(end 0.675 1.1)
			(stroke
				(width 0.15)
				(type solid)
			)
			(layer "F.Fab")
		)
		(fp_line
			(start -0.677 -1.101)
			(end -0.677 1.1)
			(stroke
				(width 0.15)
				(type solid)
			)
			(layer "F.Fab")
		)
		(fp_line
			(start -0.677 -1.101)
			(end 0.675 -1.101)
			(stroke
				(width 0.15)
				(type solid)
			)
			(layer "F.Fab")
		)
		(fp_line
			(start 0.675 -1.101)
			(end 0.675 1.1)
			(stroke
				(width 0.15)
				(type solid)
			)
			(layer "F.Fab")
		)
		(fp_text user "${REFERENCE}"
			(at -1.35 4.749 270)
			(layer "F.Fab")
			(effects
				(font
					(size 0.7 0.7)
					(thickness 0.15)
				)
				(justify left bottom)
			)
		)
		(fp_text user "License: Apache-2.0"
			(at -1.35 5.949 270)
			(layer "F.Fab")
			(effects
				(font
					(size 0.7 0.7)
					(thickness 0.15)
				)
				(justify left bottom)
			)
		)
		(fp_text user "Author: Antmicro"
			(at -1.35 7.149 270)
			(layer "F.Fab")
			(effects
				(font
					(size 0.7 0.7)
					(thickness 0.15)
				)
				(justify left bottom)
			)
		)
		(pad "1" smd rect
			(at -0.927 -0.652 270)
			(size 0.55 0.6)
			(layers "F.Cu" "F.Mask" "F.Paste")
			(net 372 "/Debug FTDI + VNA/FTDI_PWREN")
			(pinfunction "G")
			(pintype "bidirectional")
		)
		(pad "2" smd rect
			(at -0.927 0.65 270)
			(size 0.55 0.6)
			(layers "F.Cu" "F.Mask" "F.Paste")
			(net 6 "/Debug FTDI + VNA/FTDI_3V3")
			(pinfunction "S")
			(pintype "bidirectional")
		)
		(pad "3" smd rect
			(at 0.925 0 270)
			(size 0.55 0.6)
			(layers "F.Cu" "F.Mask" "F.Paste")
			(net 818 "Net-(D17-A)")
			(pinfunction "D")
			(pintype "bidirectional")
		)
	)
	(footprint "antmicro-footprints:R_0402_1005Metric"
		(layer "F.Cu")
		(at 108.824499 145.796)
		(descr "Resistor SMD 0402")
		(tags "resistor SMD 0402")
		(property "Reference" "R69"
			(at 1.125501 0.504 0)
			(layer "F.SilkS")
			(effects
				(font
					(size 0.7 0.7)
					(thickness 0.15)
				)
				(justify left bottom)
			)
		)
		(property "Value" "R_5k11_0402"
			(at -1.011843 1.772047 0)
			(layer "F.Fab")
			(effects
				(font
					(size 0.7 0.7)
					(thickness 0.15)
				)
				(justify left bottom)
			)
		)
		(property "Datasheet" "https://www.bourns.com/docs/product-datasheets/cr.pdf"
			(at 0 0 0)
			(layer "F.Fab")
			(hide yes)
			(effects
				(font
					(size 1.27 1.27)
					(thickness 0.15)
				)
			)
		)
		(property "Manufacturer" "Bourns"
			(at 0 0 0)
			(unlocked yes)
			(layer "F.Fab")
			(hide yes)
			(effects
				(font
					(size 1 1)
					(thickness 0.15)
				)
			)
		)
		(property "MPN" "CR0402-FX-5111GLF"
			(at 0 0 0)
			(unlocked yes)
			(layer "F.Fab")
			(hide yes)
			(effects
				(font
					(size 1 1)
					(thickness 0.15)
				)
			)
		)
		(property "Val" "5k11"
			(at 0 0 0)
			(unlocked yes)
			(layer "F.Fab")
			(hide yes)
			(effects
				(font
					(size 1 1)
					(thickness 0.15)
				)
			)
		)
		(property "License" "Apache-2.0"
			(at 0 0 0)
			(unlocked yes)
			(layer "F.Fab")
			(hide yes)
			(effects
				(font
					(size 1 1)
					(thickness 0.15)
				)
			)
		)
		(property "Author" "Antmicro"
			(at 0 0 0)
			(unlocked yes)
			(layer "F.Fab")
			(hide yes)
			(effects
				(font
					(size 1 1)
					(thickness 0.15)
				)
			)
		)
		(property "Tolerance" "1%"
			(at 0 0 0)
			(unlocked yes)
			(layer "F.Fab")
			(hide yes)
			(effects
				(font
					(size 1 1)
					(thickness 0.15)
				)
			)
		)
		(sheetname "/Debug FTDI + VNA/")
		(sheetfile "debug-ftdi.kicad_sch")
		(attr smd)
		(fp_rect
			(start -0.925 -0.47)
			(end 0.925 0.47)
			(stroke
				(width 0.05)
				(type default)
			)
			(fill no)
			(layer "F.CrtYd")
		)
		(fp_rect
			(start -0.5 -0.25)
			(end 0.5 0.25)
			(stroke
				(width 0.15)
				(type solid)
			)
			(fill no)
			(layer "F.Fab")
		)
		(fp_text user "License: Apache-2.0"
			(at -0.95 5.169 0)
			(layer "F.Fab")
			(effects
				(font
					(size 0.7 0.7)
					(thickness 0.15)
				)
				(justify left bottom)
			)
		)
		(fp_text user "Author: Antmicro"
			(at -0.95 4.169 0)
			(layer "F.Fab")
			(effects
				(font
					(size 0.7 0.7)
					(thickness 0.15)
				)
				(justify left bottom)
			)
		)
		(fp_text user "${REFERENCE}"
			(at -0.95 3.168 0)
			(layer "F.Fab")
			(effects
				(font
					(size 0.7 0.7)
					(thickness 0.15)
				)
				(justify left bottom)
			)
		)
		(pad "1" smd roundrect
			(at -0.48 0)
			(size 0.59 0.64)
			(layers "F.Cu" "F.Mask" "F.Paste")
			(roundrect_rratio 0.25)
			(net 366 "/Debug FTDI + VNA/CC2")
			(pintype "passive")
		)
		(pad "2" smd roundrect
			(at 0.48 0)
			(size 0.59 0.64)
			(layers "F.Cu" "F.Mask" "F.Paste")
			(roundrect_rratio 0.25)
			(net 1 "GND")
			(pintype "passive")
		)
	)
	(footprint "antmicro-footprints:C_0402_1005Metric"
		(layer "F.Cu")
		(at 223.15 178.85 90)
		(descr "Capacitor SMD 0402")
		(tags "capacitor SMD 0402")
		(property "Reference" "C215"
			(at -5.67 0.99 90)
			(layer "F.SilkS")
			(effects
				(font
					(size 0.7 0.7)
					(thickness 0.15)
				)
				(justify left bottom)
			)
		)
		(property "Value" "C_220n_16V_0402"
			(at -1.022927 2.155213 90)
			(layer "F.Fab")
			(effects
				(font
					(size 0.7 0.7)
					(thickness 0.15)
				)
				(justify left bottom)
			)
		)
		(property "Datasheet" "https://www.murata.com/products/productdetail?partno=GRM155R71C224KA12%23"
			(at 0 0 90)
			(layer "F.Fab")
			(hide yes)
			(effects
				(font
					(size 1.27 1.27)
					(thickness 0.15)
				)
			)
		)
		(property "MPN" "GRM155R71C224KA12D"
			(at 0 0 90)
			(unlocked yes)
			(layer "F.Fab")
			(hide yes)
			(effects
				(font
					(size 1 1)
					(thickness 0.15)
				)
			)
		)
		(property "Manufacturer" "Murata"
			(at 0 0 90)
			(unlocked yes)
			(layer "F.Fab")
			(hide yes)
			(effects
				(font
					(size 1 1)
					(thickness 0.15)
				)
			)
		)
		(property "License" "Apache-2.0"
			(at 0 0 90)
			(unlocked yes)
			(layer "F.Fab")
			(hide yes)
			(effects
				(font
					(size 1 1)
					(thickness 0.15)
				)
			)
		)
		(property "Author" "Antmicro"
			(at 0 0 90)
			(unlocked yes)
			(layer "F.Fab")
			(hide yes)
			(effects
				(font
					(size 1 1)
					(thickness 0.15)
				)
			)
		)
		(property "Val" "220n"
			(at 0 0 90)
			(unlocked yes)
			(layer "F.Fab")
			(hide yes)
			(effects
				(font
					(size 1 1)
					(thickness 0.15)
				)
			)
		)
		(property "Voltage" "16V"
			(at 0 0 90)
			(unlocked yes)
			(layer "F.Fab")
			(hide yes)
			(effects
				(font
					(size 1 1)
					(thickness 0.15)
				)
			)
		)
		(property "Dielectric" "X7R"
			(at 0 0 90)
			(unlocked yes)
			(layer "F.Fab")
			(hide yes)
			(effects
				(font
					(size 1 1)
					(thickness 0.15)
				)
			)
		)
		(sheetname "/Supply/DC-DC VCCINT/")
		(sheetfile "dc-dc-vccint.kicad_sch")
		(attr smd)
		(fp_rect
			(start -0.925 -0.47)
			(end 0.925 0.47)
			(stroke
				(width 0.05)
				(type default)
			)
			(fill no)
			(layer "F.CrtYd")
		)
		(fp_line
			(start 0.504 -0.25)
			(end 0.504 0.248)
			(stroke
				(width 0.15)
				(type solid)
			)
			(layer "F.Fab")
		)
		(fp_line
			(start -0.494 -0.25)
			(end 0.504 -0.25)
			(stroke
				(width 0.15)
				(type solid)
			)
			(layer "F.Fab")
		)
		(fp_line
			(start 0.504 0.248)
			(end -0.494 0.248)
			(stroke
				(width 0.15)
				(type solid)
			)
			(layer "F.Fab")
		)
		(fp_line
			(start -0.494 0.248)
			(end -0.494 -0.25)
			(stroke
				(width 0.15)
				(type solid)
			)
			(layer "F.Fab")
		)
		(fp_text user "${REFERENCE}"
			(at -0.939 4.599 90)
			(layer "F.Fab")
			(effects
				(font
					(size 0.7 0.7)
					(thickness 0.15)
				)
				(justify left bottom)
			)
		)
		(fp_text user "Author: Antmicro"
			(at -0.939 3.399 90)
			(layer "F.Fab")
			(effects
				(font
					(size 0.7 0.7)
					(thickness 0.15)
				)
				(justify left bottom)
			)
		)
		(fp_text user "License: Apache-2.0"
			(at -0.939 5.799 90)
			(layer "F.Fab")
			(effects
				(font
					(size 0.7 0.7)
					(thickness 0.15)
				)
				(justify left bottom)
			)
		)
		(pad "1" smd roundrect
			(at -0.48 0 90)
			(size 0.59 0.64)
			(layers "F.Cu" "F.Mask" "F.Paste")
			(roundrect_rratio 0.25)
			(net 164 "Net-(U4-BST)")
			(pintype "passive")
		)
		(pad "2" smd roundrect
			(at 0.48 0 90)
			(size 0.59 0.64)
			(layers "F.Cu" "F.Mask" "F.Paste")
			(roundrect_rratio 0.25)
			(net 165 "Net-(C215-Pad2)")
			(pintype "passive")
		)
	)
	(footprint "antmicro-footprints:R_1206_3216Metric"
		(layer "F.Cu")
		(at 256.676 148.148 180)
		(property "Reference" "R147"
			(at 2.176 -0.852 0)
			(layer "F.SilkS")
			(effects
				(font
					(size 0.7 0.7)
					(thickness 0.15)
				)
				(justify right bottom)
			)
		)
		(property "Value" "R_0R01_1206"
			(at 13.377643 2.255091 0)
			(layer "F.Fab")
			(effects
				(font
					(size 0.7 0.7)
					(thickness 0.15)
				)
				(justify right bottom)
			)
		)
		(property "Datasheet" "https://www.yageo.com/upload/media/product/productsearch/datasheet/rchip/PYu-RL_Group_521_RoHS_L_2.pdf"
			(at 0 0 180)
			(layer "F.Fab")
			(hide yes)
			(effects
				(font
					(size 1.27 1.27)
					(thickness 0.15)
				)
			)
		)
		(property "Manufacturer" "YAGEO"
			(at 0 0 180)
			(unlocked yes)
			(layer "F.Fab")
			(hide yes)
			(effects
				(font
					(size 1 1)
					(thickness 0.15)
				)
			)
		)
		(property "MPN" "RL1206FR-7W0R01L"
			(at 0 0 180)
			(unlocked yes)
			(layer "F.Fab")
			(hide yes)
			(effects
				(font
					(size 1 1)
					(thickness 0.15)
				)
			)
		)
		(property "Val" "0R01"
			(at 0 0 180)
			(unlocked yes)
			(layer "F.Fab")
			(hide yes)
			(effects
				(font
					(size 1 1)
					(thickness 0.15)
				)
			)
		)
		(property "License" "Apache-2.0"
			(at 0 0 180)
			(unlocked yes)
			(layer "F.Fab")
			(hide yes)
			(effects
				(font
					(size 1 1)
					(thickness 0.15)
				)
			)
		)
		(property "Author" "Antmicro"
			(at 0 0 180)
			(unlocked yes)
			(layer "F.Fab")
			(hide yes)
			(effects
				(font
					(size 1 1)
					(thickness 0.15)
				)
			)
		)
		(property "Tolerance" "1%"
			(at 0 0 180)
			(unlocked yes)
			(layer "F.Fab")
			(hide yes)
			(effects
				(font
					(size 1 1)
					(thickness 0.15)
				)
			)
		)
		(sheetname "/Supply/DC-DC IO/")
		(sheetfile "dc-dc-io.kicad_sch")
		(attr smd)
		(fp_line
			(start 0.8 0.901)
			(end -0.8 0.901)
			(stroke
				(width 0.15)
				(type solid)
			)
			(layer "F.SilkS")
		)
		(fp_line
			(start 0.8 -0.899)
			(end -0.8 -0.899)
			(stroke
				(width 0.15)
				(type solid)
			)
			(layer "F.SilkS")
		)
		(fp_rect
			(start -2.325 -1.15)
			(end 2.325 1.15)
			(stroke
				(width 0.05)
				(type default)
			)
			(fill no)
			(layer "F.CrtYd")
		)
		(fp_line
			(start 1.6 -0.802)
			(end 1.6 0.8)
			(stroke
				(width 0.15)
				(type solid)
			)
			(layer "F.Fab")
		)
		(fp_line
			(start -1.601 0.8)
			(end 1.6 0.8)
			(stroke
				(width 0.15)
				(type solid)
			)
			(layer "F.Fab")
		)
		(fp_line
			(start -1.601 -0.802)
			(end 1.6 -0.802)
			(stroke
				(width 0.15)
				(type solid)
			)
			(layer "F.Fab")
		)
		(fp_line
			(start -1.601 -0.802)
			(end -1.601 0.8)
			(stroke
				(width 0.15)
				(type solid)
			)
			(layer "F.Fab")
		)
		(fp_text user "${REFERENCE}"
			(at -2.401 3.5 180)
			(layer "F.Fab")
			(effects
				(font
					(size 0.7 0.7)
					(thickness 0.15)
				)
				(justify left bottom)
			)
		)
		(fp_text user "License: Apache-2.0"
			(at -2.401 6.3 180)
			(layer "F.Fab")
			(effects
				(font
					(size 0.7 0.7)
					(thickness 0.15)
				)
				(justify left bottom)
			)
		)
		(fp_text user "Author: Antmicro"
			(at -2.401 4.899 180)
			(layer "F.Fab")
			(effects
				(font
					(size 0.7 0.7)
					(thickness 0.15)
				)
				(justify left bottom)
			)
		)
		(pad "1" smd roundrect
			(at -1.5 0.001 180)
			(size 1.15 1.8)
			(layers "F.Cu" "F.Mask" "F.Paste")
			(roundrect_rratio 0.25)
			(net 158 "/Supply/DC-DC IO/VDDQ_local")
			(pintype "passive")
		)
		(pad "2" smd roundrect
			(at 1.5 0.001 180)
			(size 1.15 1.8)
			(layers "F.Cu" "F.Mask" "F.Paste")
			(roundrect_rratio 0.25)
			(net 687 "VDDQ")
			(pintype "passive")
		)
	)
	(footprint "antmicro-footprints:C_0603_1608Metric"
		(layer "F.Cu")
		(at 215.965 168.76)
		(descr "Capacitor SMD 0603")
		(tags "capacitor 0603")
		(property "Reference" "C266"
			(at -4.144999 0.540001 0)
			(layer "F.SilkS")
			(effects
				(font
					(size 0.7 0.7)
					(thickness 0.15)
				)
				(justify left bottom)
			)
		)
		(property "Value" "C_22u_0603"
			(at -1.42757 1.770288 0)
			(layer "F.Fab")
			(effects
				(font
					(size 0.7 0.7)
					(thickness 0.15)
				)
				(justify left bottom)
			)
		)
		(property "Datasheet" "https://www.murata.com/products/productdetail?partno=GRM188R60J226MEA0%23"
			(at 0 0 0)
			(layer "F.Fab")
			(hide yes)
			(effects
				(font
					(size 1.27 1.27)
					(thickness 0.15)
				)
			)
		)
		(property "Manufacturer" "Murata"
			(at 0 0 0)
			(unlocked yes)
			(layer "F.Fab")
			(hide yes)
			(effects
				(font
					(size 1 1)
					(thickness 0.15)
				)
			)
		)
		(property "MPN" "GRM188R60J226MEA0D"
			(at 0 0 0)
			(unlocked yes)
			(layer "F.Fab")
			(hide yes)
			(effects
				(font
					(size 1 1)
					(thickness 0.15)
				)
			)
		)
		(property "Val" "22u"
			(at 0 0 0)
			(unlocked yes)
			(layer "F.Fab")
			(hide yes)
			(effects
				(font
					(size 1 1)
					(thickness 0.15)
				)
			)
		)
		(property "License" "Apache-2.0"
			(at 0 0 0)
			(unlocked yes)
			(layer "F.Fab")
			(hide yes)
			(effects
				(font
					(size 1 1)
					(thickness 0.15)
				)
			)
		)
		(property "Author" "Antmicro"
			(at 0 0 0)
			(unlocked yes)
			(layer "F.Fab")
			(hide yes)
			(effects
				(font
					(size 1 1)
					(thickness 0.15)
				)
			)
		)
		(property "Voltage" ""
			(at 0 0 0)
			(unlocked yes)
			(layer "F.Fab")
			(hide yes)
			(effects
				(font
					(size 1 1)
					(thickness 0.15)
				)
			)
		)
		(property "Dielectric" ""
			(at 0 0 0)
			(unlocked yes)
			(layer "F.Fab")
			(hide yes)
			(effects
				(font
					(size 1 1)
					(thickness 0.15)
				)
			)
		)
		(sheetname "/Supply/DC-DC VCCINT/")
		(sheetfile "dc-dc-vccint.kicad_sch")
		(attr smd)
		(fp_line
			(start -0.15 -0.4)
			(end 0.15 -0.4)
			(stroke
				(width 0.15)
				(type solid)
			)
			(layer "F.SilkS")
		)
		(fp_line
			(start -0.15 0.4)
			(end 0.15 0.4)
			(stroke
				(width 0.15)
				(type solid)
			)
			(layer "F.SilkS")
		)
		(fp_rect
			(start -1.25 -0.65)
			(end 1.25 0.65)
			(stroke
				(width 0.05)
				(type solid)
			)
			(fill no)
			(layer "F.CrtYd")
		)
		(fp_rect
			(start -0.8 -0.4)
			(end 0.8 0.4)
			(stroke
				(width 0.15)
				(type solid)
			)
			(fill no)
			(layer "F.Fab")
		)
		(fp_text user "Author: Antmicro"
			(at -1.682 4.894 0)
			(layer "F.Fab")
			(effects
				(font
					(size 0.7 0.7)
					(thickness 0.15)
				)
				(justify left bottom)
			)
		)
		(fp_text user "License: Apache-2.0"
			(at -1.682 5.895 0)
			(layer "F.Fab")
			(effects
				(font
					(size 0.7 0.7)
					(thickness 0.15)
				)
				(justify left bottom)
			)
		)
		(fp_text user "${REFERENCE}"
			(at -1.682 3.895 0)
			(layer "F.Fab")
			(effects
				(font
					(size 0.7 0.7)
					(thickness 0.15)
				)
				(justify left bottom)
			)
		)
		(pad "1" smd roundrect
			(at -0.7 0)
			(size 0.8 1)
			(layers "F.Cu" "F.Mask" "F.Paste")
			(roundrect_rratio 0.2)
			(net 1 "GND")
			(pintype "passive")
		)
		(pad "2" smd roundrect
			(at 0.7 0)
			(size 0.8 1)
			(layers "F.Cu" "F.Mask" "F.Paste")
			(roundrect_rratio 0.2)
			(net 223 "/Supply/DC-DC VCCINT/0V85_REG0")
			(pintype "passive")
		)
	)
	(footprint "antmicro-footprints:C_0603_1608Metric"
		(layer "F.Cu")
		(at 250.293 153.921 90)
		(descr "Capacitor SMD 0603")
		(tags "capacitor 0603")
		(property "Reference" "C185"
			(at 1.221 0.507 90)
			(layer "F.SilkS")
			(effects
				(font
					(size 0.7 0.7)
					(thickness 0.15)
				)
				(justify left bottom)
			)
		)
		(property "Value" "C_22u_0603"
			(at -1.42757 1.770288 90)
			(layer "F.Fab")
			(effects
				(font
					(size 0.7 0.7)
					(thickness 0.15)
				)
				(justify left bottom)
			)
		)
		(property "Datasheet" "https://www.murata.com/products/productdetail?partno=GRM188R60J226MEA0%23"
			(at 0 0 90)
			(layer "F.Fab")
			(hide yes)
			(effects
				(font
					(size 1.27 1.27)
					(thickness 0.15)
				)
			)
		)
		(property "Manufacturer" "Murata"
			(at 0 0 90)
			(unlocked yes)
			(layer "F.Fab")
			(hide yes)
			(effects
				(font
					(size 1 1)
					(thickness 0.15)
				)
			)
		)
		(property "MPN" "GRM188R60J226MEA0D"
			(at 0 0 90)
			(unlocked yes)
			(layer "F.Fab")
			(hide yes)
			(effects
				(font
					(size 1 1)
					(thickness 0.15)
				)
			)
		)
		(property "Val" "22u"
			(at 0 0 90)
			(unlocked yes)
			(layer "F.Fab")
			(hide yes)
			(effects
				(font
					(size 1 1)
					(thickness 0.15)
				)
			)
		)
		(property "License" "Apache-2.0"
			(at 0 0 90)
			(unlocked yes)
			(layer "F.Fab")
			(hide yes)
			(effects
				(font
					(size 1 1)
					(thickness 0.15)
				)
			)
		)
		(property "Author" "Antmicro"
			(at 0 0 90)
			(unlocked yes)
			(layer "F.Fab")
			(hide yes)
			(effects
				(font
					(size 1 1)
					(thickness 0.15)
				)
			)
		)
		(property "Voltage" ""
			(at 0 0 90)
			(unlocked yes)
			(layer "F.Fab")
			(hide yes)
			(effects
				(font
					(size 1 1)
					(thickness 0.15)
				)
			)
		)
		(property "Dielectric" ""
			(at 0 0 90)
			(unlocked yes)
			(layer "F.Fab")
			(hide yes)
			(effects
				(font
					(size 1 1)
					(thickness 0.15)
				)
			)
		)
		(sheetname "/Supply/DC-DC IO/")
		(sheetfile "dc-dc-io.kicad_sch")
		(attr smd)
		(fp_line
			(start -0.15 -0.4)
			(end 0.15 -0.4)
			(stroke
				(width 0.15)
				(type solid)
			)
			(layer "F.SilkS")
		)
		(fp_line
			(start -0.15 0.4)
			(end 0.15 0.4)
			(stroke
				(width 0.15)
				(type solid)
			)
			(layer "F.SilkS")
		)
		(fp_rect
			(start -1.25 -0.65)
			(end 1.25 0.65)
			(stroke
				(width 0.05)
				(type solid)
			)
			(fill no)
			(layer "F.CrtYd")
		)
		(fp_rect
			(start -0.8 -0.4)
			(end 0.8 0.4)
			(stroke
				(width 0.15)
				(type solid)
			)
			(fill no)
			(layer "F.Fab")
		)
		(fp_text user "${REFERENCE}"
			(at -1.682 3.895 90)
			(layer "F.Fab")
			(effects
				(font
					(size 0.7 0.7)
					(thickness 0.15)
				)
				(justify left bottom)
			)
		)
		(fp_text user "Author: Antmicro"
			(at -1.682 4.894 90)
			(layer "F.Fab")
			(effects
				(font
					(size 0.7 0.7)
					(thickness 0.15)
				)
				(justify left bottom)
			)
		)
		(fp_text user "License: Apache-2.0"
			(at -1.682 5.895 90)
			(layer "F.Fab")
			(effects
				(font
					(size 0.7 0.7)
					(thickness 0.15)
				)
				(justify left bottom)
			)
		)
		(pad "1" smd roundrect
			(at -0.7 0 90)
			(size 0.8 1)
			(layers "F.Cu" "F.Mask" "F.Paste")
			(roundrect_rratio 0.2)
			(net 1 "GND")
			(pintype "passive")
		)
		(pad "2" smd roundrect
			(at 0.7 0 90)
			(size 0.8 1)
			(layers "F.Cu" "F.Mask" "F.Paste")
			(roundrect_rratio 0.2)
			(net 46 "/Supply/DC-DC IO/5V_local")
			(pintype "passive")
		)
	)
	(footprint "antmicro-footprints:R_0402_1005Metric"
		(layer "F.Cu")
		(at 123.681 168.3125 90)
		(descr "Resistor SMD 0402")
		(tags "resistor SMD 0402")
		(property "Reference" "R220"
			(at -3.825 0.619 90)
			(layer "F.SilkS")
			(effects
				(font
					(size 0.7 0.7)
					(thickness 0.15)
				)
				(justify left bottom)
			)
		)
		(property "Value" "R_64k9_0402"
			(at -1.011843 1.772047 90)
			(layer "F.Fab")
			(effects
				(font
					(size 0.7 0.7)
					(thickness 0.15)
				)
				(justify left bottom)
			)
		)
		(property "Datasheet" "https://www.bourns.com/docs/product-datasheets/cr.pdf"
			(at 0 0 90)
			(layer "F.Fab")
			(hide yes)
			(effects
				(font
					(size 1.27 1.27)
					(thickness 0.15)
				)
			)
		)
		(property "MPN" "CR0402-FX-6492GLF"
			(at 0 0 90)
			(unlocked yes)
			(layer "F.Fab")
			(hide yes)
			(effects
				(font
					(size 1 1)
					(thickness 0.15)
				)
			)
		)
		(property "Manufacturer" "Bourns"
			(at 0 0 90)
			(unlocked yes)
			(layer "F.Fab")
			(hide yes)
			(effects
				(font
					(size 1 1)
					(thickness 0.15)
				)
			)
		)
		(property "License" "Apache-2.0"
			(at 0 0 90)
			(unlocked yes)
			(layer "F.Fab")
			(hide yes)
			(effects
				(font
					(size 1 1)
					(thickness 0.15)
				)
			)
		)
		(property "Author" "Antmicro"
			(at 0 0 90)
			(unlocked yes)
			(layer "F.Fab")
			(hide yes)
			(effects
				(font
					(size 1 1)
					(thickness 0.15)
				)
			)
		)
		(property "Val" "64k9"
			(at 0 0 90)
			(unlocked yes)
			(layer "F.Fab")
			(hide yes)
			(effects
				(font
					(size 1 1)
					(thickness 0.15)
				)
			)
		)
		(property "Tolerance" "1%"
			(at 0 0 90)
			(unlocked yes)
			(layer "F.Fab")
			(hide yes)
			(effects
				(font
					(size 1 1)
					(thickness 0.15)
				)
			)
		)
		(sheetname "/HDMI + SD Card/")
		(sheetfile "hdmi-sd-card.kicad_sch")
		(attr smd exclude_from_bom dnp)
		(fp_rect
			(start -0.925 -0.47)
			(end 0.925 0.47)
			(stroke
				(width 0.05)
				(type default)
			)
			(fill no)
			(layer "F.CrtYd")
		)
		(fp_rect
			(start -0.5 -0.25)
			(end 0.5 0.25)
			(stroke
				(width 0.15)
				(type solid)
			)
			(fill no)
			(layer "F.Fab")
		)
		(fp_text user "Author: Antmicro"
			(at -0.95 4.169 90)
			(layer "F.Fab")
			(effects
				(font
					(size 0.7 0.7)
					(thickness 0.15)
				)
				(justify left bottom)
			)
		)
		(fp_text user "License: Apache-2.0"
			(at -0.95 5.169 90)
			(layer "F.Fab")
			(effects
				(font
					(size 0.7 0.7)
					(thickness 0.15)
				)
				(justify left bottom)
			)
		)
		(fp_text user "${REFERENCE}"
			(at -0.95 3.168 90)
			(layer "F.Fab")
			(effects
				(font
					(size 0.7 0.7)
					(thickness 0.15)
				)
				(justify left bottom)
			)
		)
		(pad "1" smd roundrect
			(at -0.48 0 90)
			(size 0.59 0.64)
			(layers "F.Cu" "F.Mask" "F.Paste")
			(roundrect_rratio 0.25)
			(net 1 "GND")
			(pintype "passive")
		)
		(pad "2" smd roundrect
			(at 0.48 0 90)
			(size 0.59 0.64)
			(layers "F.Cu" "F.Mask" "F.Paste")
			(roundrect_rratio 0.25)
			(net 739 "/HDMI + SD Card/TX_TERM_CTL")
			(pintype "passive")
		)
	)
	(footprint "antmicro-footprints:R_0402_1005Metric"
		(layer "F.Cu")
		(at 257.79 143.185 -90)
		(descr "Resistor SMD 0402")
		(tags "resistor SMD 0402")
		(property "Reference" "R78"
			(at -1.085 0.54 90)
			(layer "F.SilkS")
			(effects
				(font
					(size 0.7 0.7)
					(thickness 0.15)
				)
				(justify right bottom)
			)
		)
		(property "Value" "R_4k7_0402"
			(at -1.011843 1.772047 90)
			(layer "F.Fab")
			(effects
				(font
					(size 0.7 0.7)
					(thickness 0.15)
				)
				(justify right bottom)
			)
		)
		(property "Datasheet" "https://www.bourns.com/docs/product-datasheets/cr.pdf"
			(at 0 0 270)
			(layer "F.Fab")
			(hide yes)
			(effects
				(font
					(size 1.27 1.27)
					(thickness 0.15)
				)
			)
		)
		(property "Manufacturer" "Bourns"
			(at 0 0 270)
			(unlocked yes)
			(layer "F.Fab")
			(hide yes)
			(effects
				(font
					(size 1 1)
					(thickness 0.15)
				)
			)
		)
		(property "MPN" "CR0402-FX-4701GLF"
			(at 0 0 270)
			(unlocked yes)
			(layer "F.Fab")
			(hide yes)
			(effects
				(font
					(size 1 1)
					(thickness 0.15)
				)
			)
		)
		(property "Val" "4k7"
			(at 0 0 270)
			(unlocked yes)
			(layer "F.Fab")
			(hide yes)
			(effects
				(font
					(size 1 1)
					(thickness 0.15)
				)
			)
		)
		(property "License" "Apache-2.0"
			(at 0 0 270)
			(unlocked yes)
			(layer "F.Fab")
			(hide yes)
			(effects
				(font
					(size 1 1)
					(thickness 0.15)
				)
			)
		)
		(property "Author" "Antmicro"
			(at 0 0 270)
			(unlocked yes)
			(layer "F.Fab")
			(hide yes)
			(effects
				(font
					(size 1 1)
					(thickness 0.15)
				)
			)
		)
		(property "Tolerance" "1%"
			(at 0 0 270)
			(unlocked yes)
			(layer "F.Fab")
			(hide yes)
			(effects
				(font
					(size 1 1)
					(thickness 0.15)
				)
			)
		)
		(sheetname "/DDR5 RDIMM/")
		(sheetfile "ddr5-rdimm.kicad_sch")
		(attr smd)
		(fp_rect
			(start -0.925 -0.47)
			(end 0.925 0.47)
			(stroke
				(width 0.05)
				(type default)
			)
			(fill no)
			(layer "F.CrtYd")
		)
		(fp_rect
			(start -0.5 -0.25)
			(end 0.5 0.25)
			(stroke
				(width 0.15)
				(type solid)
			)
			(fill no)
			(layer "F.Fab")
		)
		(fp_text user "Author: Antmicro"
			(at -0.95 4.169 270)
			(layer "F.Fab")
			(effects
				(font
					(size 0.7 0.7)
					(thickness 0.15)
				)
				(justify left bottom)
			)
		)
		(fp_text user "${REFERENCE}"
			(at -0.95 3.168 270)
			(layer "F.Fab")
			(effects
				(font
					(size 0.7 0.7)
					(thickness 0.15)
				)
				(justify left bottom)
			)
		)
		(fp_text user "License: Apache-2.0"
			(at -0.95 5.169 270)
			(layer "F.Fab")
			(effects
				(font
					(size 0.7 0.7)
					(thickness 0.15)
				)
				(justify left bottom)
			)
		)
		(pad "1" smd roundrect
			(at -0.48 0 270)
			(size 0.59 0.64)
			(layers "F.Cu" "F.Mask" "F.Paste")
			(roundrect_rratio 0.25)
			(net 151 "+3V3")
			(pintype "passive")
		)
		(pad "2" smd roundrect
			(at 0.48 0 270)
			(size 0.59 0.64)
			(layers "F.Cu" "F.Mask" "F.Paste")
			(roundrect_rratio 0.25)
			(net 69 "HOT_SWAP_BUTTON")
			(pintype "passive")
		)
	)
	(footprint "antmicro-footprints:Conn_JST_SH_1x2_BM02B-SRSS-TB-LF-SN"
		(layer "F.Cu")
		(at 239.55 119.92 180)
		(property "Reference" "J17"
			(at 0.31 -3.915 0)
			(layer "F.SilkS")
			(effects
				(font
					(size 0.7 0.7)
					(thickness 0.15)
				)
				(justify right bottom)
			)
		)
		(property "Value" "JST_SH_1x2_BM02B-SRSS-TB-LF-SN"
			(at -2.3 4 0)
			(layer "F.Fab")
			(effects
				(font
					(size 0.7 0.7)
					(thickness 0.15)
				)
				(justify right bottom)
			)
		)
		(property "Datasheet" "https://www.jst-mfg.com/product/pdf/eng/eSH.pdf"
			(at 0 0 180)
			(layer "F.Fab")
			(hide yes)
			(effects
				(font
					(size 1.27 1.27)
					(thickness 0.15)
				)
			)
		)
		(property "MPN" "BM02B-SRSS-TB(LF)(SN)"
			(at 0 0 180)
			(unlocked yes)
			(layer "F.Fab")
			(hide yes)
			(effects
				(font
					(size 1 1)
					(thickness 0.15)
				)
			)
		)
		(property "Manufacturer" "JST Automotive Connectors"
			(at 0 0 180)
			(unlocked yes)
			(layer "F.Fab")
			(hide yes)
			(effects
				(font
					(size 1 1)
					(thickness 0.15)
				)
			)
		)
		(property "Author" "Antmicro"
			(at 0 0 180)
			(unlocked yes)
			(layer "F.Fab")
			(hide yes)
			(effects
				(font
					(size 1 1)
					(thickness 0.15)
				)
			)
		)
		(property "License" "Apache-2.0"
			(at 0 0 180)
			(unlocked yes)
			(layer "F.Fab")
			(hide yes)
			(effects
				(font
					(size 1 1)
					(thickness 0.15)
				)
			)
		)
		(sheetname "/Supply/")
		(sheetfile "supply.kicad_sch")
		(attr smd)
		(fp_line
			(start 1.9 -0.88)
			(end 1.9 0.88)
			(stroke
				(width 0.15)
				(type solid)
			)
			(layer "F.SilkS")
		)
		(fp_line
			(start -1.1 2.1)
			(end 0 2.1)
			(stroke
				(width 0.15)
				(type solid)
			)
			(layer "F.SilkS")
		)
		(fp_line
			(start -1.1 2.1)
			(end -1.1 1.22)
			(stroke
				(width 0.15)
				(type solid)
			)
			(layer "F.SilkS")
		)
		(fp_line
			(start -1.1 -1.22)
			(end -1.1 -2.1)
			(stroke
				(width 0.15)
				(type solid)
			)
			(layer "F.SilkS")
		)
		(fp_line
			(start -1.1 -2.1)
			(end 0 -2.1)
			(stroke
				(width 0.15)
				(type solid)
			)
			(layer "F.SilkS")
		)
		(fp_circle
			(center -1.6 -1.2)
			(end -1.55 -1.2)
			(stroke
				(width 0.15)
				(type solid)
			)
			(fill yes)
			(layer "F.SilkS")
		)
		(fp_rect
			(start -2.05 -2.95)
			(end 2.05 2.95)
			(stroke
				(width 0.05)
				(type solid)
			)
			(fill no)
			(layer "F.CrtYd")
		)
		(fp_rect
			(start -1.8 -2)
			(end 1.8 2)
			(stroke
				(width 0.15)
				(type solid)
			)
			(fill no)
			(layer "F.Fab")
		)
		(fp_text user "${REFERENCE}"
			(at -2.3 7.2 180)
			(layer "F.Fab")
			(effects
				(font
					(size 0.7 0.7)
					(thickness 0.15)
				)
				(justify left bottom)
			)
		)
		(fp_text user "License: Apache-2.0"
			(at -2.3 8.4 180)
			(layer "F.Fab")
			(effects
				(font
					(size 0.7 0.7)
					(thickness 0.15)
				)
				(justify left bottom)
			)
		)
		(fp_text user "Author: Antmicro"
			(at -2.3 6 180)
			(layer "F.Fab")
			(effects
				(font
					(size 0.7 0.7)
					(thickness 0.15)
				)
				(justify left bottom)
			)
		)
		(pad "1" smd roundrect
			(at -1.325 -0.5 90)
			(size 0.6 1.55)
			(layers "F.Cu" "F.Mask" "F.Paste")
			(roundrect_rratio 0.25)
			(net 811 "/Supply/heater")
			(pintype "passive")
		)
		(pad "2" smd roundrect
			(at -1.325 0.5 270)
			(size 0.6 1.55)
			(layers "F.Cu" "F.Mask" "F.Paste")
			(roundrect_rratio 0.25)
			(net 1 "GND")
			(pintype "passive")
		)
		(pad "MP" smd roundrect
			(at 1.2 -1.8 270)
			(size 1.2 1.8)
			(layers "F.Cu" "F.Mask" "F.Paste")
			(roundrect_rratio 0.25)
			(net 1 "GND")
			(pintype "passive")
		)
		(pad "MP" smd roundrect
			(at 1.2 1.8 270)
			(size 1.2 1.8)
			(layers "F.Cu" "F.Mask" "F.Paste")
			(roundrect_rratio 0.25)
			(net 1 "GND")
			(pintype "passive")
		)
	)
	(footprint "antmicro-footprints:SC70-3"
		(layer "F.Cu")
		(at 115.1 115.1 90)
		(property "Reference" "Q2"
			(at -0.45 -0.775 0)
			(layer "F.SilkS")
			(effects
				(font
					(size 0.7 0.7)
					(thickness 0.15)
				)
				(justify left bottom)
			)
		)
		(property "Value" "BSS138PW"
			(at 0 2.3 90)
			(layer "F.Fab")
			(effects
				(font
					(size 0.7 0.7)
					(thickness 0.15)
				)
				(justify left bottom)
			)
		)
		(property "Datasheet" "https://assets.nexperia.com/documents/data-sheet/BSS138PW.pdf"
			(at 0 0 90)
			(layer "F.Fab")
			(hide yes)
			(effects
				(font
					(size 1.27 1.27)
					(thickness 0.15)
				)
			)
		)
		(property "MPN" "BSS138PW"
			(at 0 0 90)
			(unlocked yes)
			(layer "F.Fab")
			(hide yes)
			(effects
				(font
					(size 1 1)
					(thickness 0.15)
				)
			)
		)
		(property "Manufacturer" "Nexperia"
			(at 0 0 90)
			(unlocked yes)
			(layer "F.Fab")
			(hide yes)
			(effects
				(font
					(size 1 1)
					(thickness 0.15)
				)
			)
		)
		(property "Author" "Antmicro"
			(at 0 0 90)
			(unlocked yes)
			(layer "F.Fab")
			(hide yes)
			(effects
				(font
					(size 1 1)
					(thickness 0.15)
				)
			)
		)
		(property "License" "Apache-2.0"
			(at 0 0 90)
			(unlocked yes)
			(layer "F.Fab")
			(hide yes)
			(effects
				(font
					(size 1 1)
					(thickness 0.15)
				)
			)
		)
		(sheetname "/FPGA Config/")
		(sheetfile "fpga-config.kicad_sch")
		(attr smd)
		(fp_line
			(start -0.3 -1)
			(end 0.627 -0.999)
			(stroke
				(width 0.15)
				(type solid)
			)
			(layer "F.SilkS")
		)
		(fp_line
			(start 0.627 -0.6)
			(end 0.627 -0.999)
			(stroke
				(width 0.15)
				(type solid)
			)
			(layer "F.SilkS")
		)
		(fp_line
			(start 0.627 0.6)
			(end 0.627 1.001)
			(stroke
				(width 0.15)
				(type solid)
			)
			(layer "F.SilkS")
		)
		(fp_line
			(start -0.3 1)
			(end 0.627 1.001)
			(stroke
				(width 0.15)
				(type solid)
			)
			(layer "F.SilkS")
		)
		(fp_line
			(start 0.9 -1.3)
			(end 0.9 -0.4)
			(stroke
				(width 0.05)
				(type solid)
			)
			(layer "F.CrtYd")
		)
		(fp_line
			(start -0.9 -1.3)
			(end 0.9 -1.3)
			(stroke
				(width 0.05)
				(type solid)
			)
			(layer "F.CrtYd")
		)
		(fp_line
			(start -0.9 -1.3)
			(end -0.9 -1)
			(stroke
				(width 0.05)
				(type solid)
			)
			(layer "F.CrtYd")
		)
		(fp_line
			(start -0.9 -1)
			(end -1.4 -1)
			(stroke
				(width 0.05)
				(type solid)
			)
			(layer "F.CrtYd")
		)
		(fp_line
			(start 1.4 -0.4)
			(end 1.4 0.4)
			(stroke
				(width 0.05)
				(type solid)
			)
			(layer "F.CrtYd")
		)
		(fp_line
			(start 0.9 -0.4)
			(end 1.4 -0.4)
			(stroke
				(width 0.05)
				(type solid)
			)
			(layer "F.CrtYd")
		)
		(fp_line
			(start 1.4 0.4)
			(end 0.9 0.4)
			(stroke
				(width 0.05)
				(type solid)
			)
			(layer "F.CrtYd")
		)
		(fp_line
			(start 0.9 0.4)
			(end 0.9 1.3)
			(stroke
				(width 0.05)
				(type solid)
			)
			(layer "F.CrtYd")
		)
		(fp_line
			(start -0.9 1)
			(end -1.4 1)
			(stroke
				(width 0.05)
				(type solid)
			)
			(layer "F.CrtYd")
		)
		(fp_line
			(start -1.4 1)
			(end -1.4 -1)
			(stroke
				(width 0.05)
				(type solid)
			)
			(layer "F.CrtYd")
		)
		(fp_line
			(start 0.9 1.3)
			(end -0.9 1.3)
			(stroke
				(width 0.05)
				(type solid)
			)
			(layer "F.CrtYd")
		)
		(fp_line
			(start -0.9 1.3)
			(end -0.9 1)
			(stroke
				(width 0.05)
				(type solid)
			)
			(layer "F.CrtYd")
		)
		(fp_rect
			(start -0.623 -0.999)
			(end 0.627 1.001)
			(stroke
				(width 0.15)
				(type solid)
			)
			(fill no)
			(layer "F.Fab")
		)
		(fp_text user "${REFERENCE}"
			(at -1.45 4.783 90)
			(layer "F.Fab")
			(effects
				(font
					(size 0.7 0.7)
					(thickness 0.15)
				)
				(justify left bottom)
			)
		)
		(fp_text user "Author: Antmicro"
			(at -1.45 5.782 90)
			(layer "F.Fab")
			(effects
				(font
					(size 0.7 0.7)
					(thickness 0.15)
				)
				(justify left bottom)
			)
		)
		(fp_text user "License: Apache-2.0"
			(at -1.45 6.782 90)
			(layer "F.Fab")
			(effects
				(font
					(size 0.7 0.7)
					(thickness 0.15)
				)
				(justify left bottom)
			)
		)
		(pad "1" smd rect
			(at -1.051 -0.65 180)
			(size 0.6 0.6)
			(layers "F.Cu" "F.Mask" "F.Paste")
			(net 341 "/FPGA Config/INIT_B")
			(pinfunction "G")
			(pintype "passive")
		)
		(pad "2" smd rect
			(at -1.051 0.65 180)
			(size 0.6 0.6)
			(layers "F.Cu" "F.Mask" "F.Paste")
			(net 1 "GND")
			(pinfunction "S")
			(pintype "passive")
		)
		(pad "3" smd rect
			(at 1.05 0 180)
			(size 0.6 0.6)
			(layers "F.Cu" "F.Mask" "F.Paste")
			(net 270 "Net-(Q2-D)")
			(pinfunction "D")
			(pintype "passive")
		)
	)
	(footprint "antmicro-footprints:C_0402_1005Metric"
		(layer "F.Cu")
		(at 155.67 159.154999 90)
		(descr "Capacitor SMD 0402")
		(tags "capacitor SMD 0402")
		(property "Reference" "C286"
			(at -1.025 -0.88 90)
			(layer "F.SilkS")
			(effects
				(font
					(size 0.7 0.7)
					(thickness 0.15)
				)
				(justify left bottom)
			)
		)
		(property "Value" "C_100n_0402"
			(at -1.022927 2.155213 90)
			(layer "F.Fab")
			(effects
				(font
					(size 0.7 0.7)
					(thickness 0.15)
				)
				(justify left bottom)
			)
		)
		(property "Datasheet" "https://www.murata.com/products/productdetail?partno=GRM155R61H104KE14%23"
			(at 0 0 90)
			(layer "F.Fab")
			(hide yes)
			(effects
				(font
					(size 1.27 1.27)
					(thickness 0.15)
				)
			)
		)
		(property "MPN" "GRM155R61H104KE14D"
			(at 0 0 90)
			(unlocked yes)
			(layer "F.Fab")
			(hide yes)
			(effects
				(font
					(size 1 1)
					(thickness 0.15)
				)
			)
		)
		(property "Manufacturer" "Murata"
			(at 0 0 90)
			(unlocked yes)
			(layer "F.Fab")
			(hide yes)
			(effects
				(font
					(size 1 1)
					(thickness 0.15)
				)
			)
		)
		(property "License" "Apache-2.0"
			(at 0 0 90)
			(unlocked yes)
			(layer "F.Fab")
			(hide yes)
			(effects
				(font
					(size 1 1)
					(thickness 0.15)
				)
			)
		)
		(property "Author" "Antmicro"
			(at 0 0 90)
			(unlocked yes)
			(layer "F.Fab")
			(hide yes)
			(effects
				(font
					(size 1 1)
					(thickness 0.15)
				)
			)
		)
		(property "Val" "100n"
			(at 0 0 90)
			(unlocked yes)
			(layer "F.Fab")
			(hide yes)
			(effects
				(font
					(size 1 1)
					(thickness 0.15)
				)
			)
		)
		(property "Voltage" "50V"
			(at 0 0 90)
			(unlocked yes)
			(layer "F.Fab")
			(hide yes)
			(effects
				(font
					(size 1 1)
					(thickness 0.15)
				)
			)
		)
		(property "Dielectric" "X5R"
			(at 0 0 90)
			(unlocked yes)
			(layer "F.Fab")
			(hide yes)
			(effects
				(font
					(size 1 1)
					(thickness 0.15)
				)
			)
		)
		(property "Public" ""
			(at 0 0 90)
			(unlocked yes)
			(layer "F.Fab")
			(hide yes)
			(effects
				(font
					(size 1 1)
					(thickness 0.15)
				)
			)
		)
		(sheetname "/FPGA MGT Interface/")
		(sheetfile "fpga-mgt.kicad_sch")
		(attr smd)
		(fp_rect
			(start -0.925 -0.47)
			(end 0.925 0.47)
			(stroke
				(width 0.05)
				(type default)
			)
			(fill no)
			(layer "F.CrtYd")
		)
		(fp_line
			(start 0.504 -0.25)
			(end 0.504 0.248)
			(stroke
				(width 0.15)
				(type solid)
			)
			(layer "F.Fab")
		)
		(fp_line
			(start -0.494 -0.25)
			(end 0.504 -0.25)
			(stroke
				(width 0.15)
				(type solid)
			)
			(layer "F.Fab")
		)
		(fp_line
			(start 0.504 0.248)
			(end -0.494 0.248)
			(stroke
				(width 0.15)
				(type solid)
			)
			(layer "F.Fab")
		)
		(fp_line
			(start -0.494 0.248)
			(end -0.494 -0.25)
			(stroke
				(width 0.15)
				(type solid)
			)
			(layer "F.Fab")
		)
		(fp_text user "${REFERENCE}"
			(at -0.939 4.599 90)
			(layer "F.Fab")
			(effects
				(font
					(size 0.7 0.7)
					(thickness 0.15)
				)
				(justify left bottom)
			)
		)
		(fp_text user "License: Apache-2.0"
			(at -0.939 5.799 90)
			(layer "F.Fab")
			(effects
				(font
					(size 0.7 0.7)
					(thickness 0.15)
				)
				(justify left bottom)
			)
		)
		(fp_text user "Author: Antmicro"
			(at -0.939 3.399 90)
			(layer "F.Fab")
			(effects
				(font
					(size 0.7 0.7)
					(thickness 0.15)
				)
				(justify left bottom)
			)
		)
		(pad "1" smd roundrect
			(at -0.48 0 90)
			(size 0.59 0.64)
			(layers "F.Cu" "F.Mask" "F.Paste")
			(roundrect_rratio 0.25)
			(net 151 "+3V3")
			(pintype "passive")
		)
		(pad "2" smd roundrect
			(at 0.48 0 90)
			(size 0.59 0.64)
			(layers "F.Cu" "F.Mask" "F.Paste")
			(roundrect_rratio 0.25)
			(net 1 "GND")
			(pintype "passive")
		)
	)
	(footprint "antmicro-footprints:SOT-23-5"
		(layer "F.Cu")
		(at 112.124499 139.549)
		(property "Reference" "U5"
			(at 0.4 2.7 0)
			(layer "F.SilkS")
			(effects
				(font
					(size 0.7 0.7)
					(thickness 0.15)
				)
				(justify left bottom)
			)
		)
		(property "Value" "NCP718BSN330T1G"
			(at 0.002 2.799 0)
			(layer "F.Fab")
			(effects
				(font
					(size 0.7 0.7)
					(thickness 0.15)
				)
				(justify left bottom)
			)
		)
		(property "Datasheet" "https://www.mouser.com/datasheet/2/308/NCP718_D-1224359.pdf"
			(at 0 0 0)
			(layer "F.Fab")
			(hide yes)
			(effects
				(font
					(size 1.27 1.27)
					(thickness 0.15)
				)
			)
		)
		(property "MPN" "NCP718BSN330T1G"
			(at 0 0 0)
			(unlocked yes)
			(layer "F.Fab")
			(hide yes)
			(effects
				(font
					(size 1 1)
					(thickness 0.15)
				)
			)
		)
		(property "Manufacturer" "ON Semiconductor"
			(at 0 0 0)
			(unlocked yes)
			(layer "F.Fab")
			(hide yes)
			(effects
				(font
					(size 1 1)
					(thickness 0.15)
				)
			)
		)
		(property "Author" "Antmicro"
			(at 0 0 0)
			(unlocked yes)
			(layer "F.Fab")
			(hide yes)
			(effects
				(font
					(size 1 1)
					(thickness 0.15)
				)
			)
		)
		(property "License" "Apache-2.0"
			(at 0 0 0)
			(unlocked yes)
			(layer "F.Fab")
			(hide yes)
			(effects
				(font
					(size 1 1)
					(thickness 0.15)
				)
			)
		)
		(sheetname "/Debug FTDI + VNA/")
		(sheetfile "debug-ftdi.kicad_sch")
		(attr smd)
		(fp_line
			(start -0.85 1.6)
			(end -0.85 1.301)
			(stroke
				(width 0.15)
				(type solid)
			)
			(layer "F.SilkS")
		)
		(fp_line
			(start -0.8 -1.6)
			(end -0.8 -1.3)
			(stroke
				(width 0.15)
				(type solid)
			)
			(layer "F.SilkS")
		)
		(fp_line
			(start -0.8 -1.6)
			(end -0.5 -1.6)
			(stroke
				(width 0.15)
				(type solid)
			)
			(layer "F.SilkS")
		)
		(fp_line
			(start -0.55 1.6)
			(end -0.85 1.6)
			(stroke
				(width 0.15)
				(type solid)
			)
			(layer "F.SilkS")
		)
		(fp_line
			(start 0.8 -1.6)
			(end 0.5 -1.6)
			(stroke
				(width 0.15)
				(type solid)
			)
			(layer "F.SilkS")
		)
		(fp_line
			(start 0.8 -1.3)
			(end 0.8 -1.6)
			(stroke
				(width 0.15)
				(type solid)
			)
			(layer "F.SilkS")
		)
		(fp_line
			(start 0.8 0.55)
			(end 0.8 -0.55)
			(stroke
				(width 0.15)
				(type solid)
			)
			(layer "F.SilkS")
		)
		(fp_line
			(start 0.8 1.3)
			(end 0.8 1.599)
			(stroke
				(width 0.15)
				(type solid)
			)
			(layer "F.SilkS")
		)
		(fp_line
			(start 0.8 1.599)
			(end 0.549 1.599)
			(stroke
				(width 0.15)
				(type solid)
			)
			(layer "F.SilkS")
		)
		(fp_circle
			(center -1.25 -1.5)
			(end -1.2 -1.5)
			(stroke
				(width 0.15)
				(type solid)
			)
			(fill yes)
			(layer "F.SilkS")
		)
		(fp_rect
			(start 1.9 -1.76)
			(end -1.9 1.75)
			(stroke
				(width 0.05)
				(type solid)
			)
			(fill no)
			(layer "F.CrtYd")
		)
		(fp_line
			(start -0.398 -1.526)
			(end -0.874 -1.05)
			(stroke
				(width 0.15)
				(type solid)
			)
			(layer "F.Fab")
		)
		(fp_rect
			(start 0.874 1.523)
			(end -0.873 -1.525)
			(stroke
				(width 0.15)
				(type solid)
			)
			(fill no)
			(layer "F.Fab")
		)
		(fp_text user "${REFERENCE}"
			(at -1.898 4.299 0)
			(layer "F.Fab")
			(effects
				(font
					(size 0.7 0.7)
					(thickness 0.15)
				)
				(justify left bottom)
			)
		)
		(fp_text user "Author: Antmicro"
			(at -1.898 5.499 0)
			(layer "F.Fab")
			(effects
				(font
					(size 0.7 0.7)
					(thickness 0.15)
				)
				(justify left bottom)
			)
		)
		(fp_text user "License: Apache-2.0"
			(at -1.898 6.7 0)
			(layer "F.Fab")
			(effects
				(font
					(size 0.7 0.7)
					(thickness 0.15)
				)
				(justify left bottom)
			)
		)
		(pad "1" smd rect
			(at -1.351 -0.951 270)
			(size 0.55 1)
			(layers "F.Cu" "F.Mask" "F.Paste")
			(net 2 "/Debug FTDI + VNA/VBUS")
			(pinfunction "VIN")
			(pintype "passive")
		)
		(pad "2" smd rect
			(at -1.351 0 270)
			(size 0.55 1)
			(layers "F.Cu" "F.Mask" "F.Paste")
			(net 1 "GND")
			(pinfunction "GND")
			(pintype "passive")
		)
		(pad "3" smd rect
			(at -1.351 0.949 270)
			(size 0.55 1)
			(layers "F.Cu" "F.Mask" "F.Paste")
			(net 2 "/Debug FTDI + VNA/VBUS")
			(pinfunction "EN")
			(pintype "passive")
		)
		(pad "4" smd rect
			(at 1.35 0.949 270)
			(size 0.55 1)
			(layers "F.Cu" "F.Mask" "F.Paste")
			(net 311 "unconnected-(U5-NC-Pad4)")
			(pinfunction "NC")
			(pintype "no_connect")
		)
		(pad "5" smd rect
			(at 1.35 -0.951 270)
			(size 0.55 1)
			(layers "F.Cu" "F.Mask" "F.Paste")
			(net 6 "/Debug FTDI + VNA/FTDI_3V3")
			(pinfunction "VOUT")
			(pintype "passive")
		)
	)
	(footprint "antmicro-footprints:Resonator_SMD_Abracon_ABM8G_3.2x2.5mm"
		(layer "F.Cu")
		(at 158.030003 155.609999 -135)
		(property "Reference" "Y4"
			(at 0.85 1.7 45)
			(layer "F.SilkS")
			(effects
				(font
					(size 0.7 0.7)
					(thickness 0.15)
				)
				(justify right bottom)
			)
		)
		(property "Value" "Resonator_114.285MHZ_ABM8"
			(at -1.75 2.548 45)
			(layer "F.Fab")
			(effects
				(font
					(size 0.7 0.7)
					(thickness 0.15)
				)
				(justify right bottom)
			)
		)
		(property "Datasheet" "https://abracon.com/Resonators/ABM8-166.pdf"
			(at 0 0 225)
			(layer "F.Fab")
			(hide yes)
			(effects
				(font
					(size 1.27 1.27)
					(thickness 0.15)
				)
			)
		)
		(property "MPN" "ABM8-166-114.285MHZ-T2"
			(at 0 0 225)
			(unlocked yes)
			(layer "F.Fab")
			(hide yes)
			(effects
				(font
					(size 1 1)
					(thickness 0.15)
				)
			)
		)
		(property "Manufacturer" "Abracon"
			(at 0 0 225)
			(unlocked yes)
			(layer "F.Fab")
			(hide yes)
			(effects
				(font
					(size 1 1)
					(thickness 0.15)
				)
			)
		)
		(property "Author" "Antmicro"
			(at 0 0 225)
			(unlocked yes)
			(layer "F.Fab")
			(hide yes)
			(effects
				(font
					(size 1 1)
					(thickness 0.15)
				)
			)
		)
		(property "License" "Apache-2.0"
			(at 0 0 225)
			(unlocked yes)
			(layer "F.Fab")
			(hide yes)
			(effects
				(font
					(size 1 1)
					(thickness 0.15)
				)
			)
		)
		(property "Val" "114.285 MHz"
			(at 0 0 225)
			(unlocked yes)
			(layer "F.Fab")
			(hide yes)
			(effects
				(font
					(size 1 1)
					(thickness 0.15)
				)
			)
		)
		(sheetname "/FPGA MGT Interface/")
		(sheetfile "fpga-mgt.kicad_sch")
		(attr smd)
		(fp_line
			(start 1.6 0.3)
			(end 1.6 -0.2)
			(stroke
				(width 0.15)
				(type solid)
			)
			(layer "F.SilkS")
		)
		(fp_line
			(start -0.35 1.25)
			(end 0.450001 1.25)
			(stroke
				(width 0.15)
				(type solid)
			)
			(layer "F.SilkS")
		)
		(fp_line
			(start -1.6 0.3)
			(end -1.6 -0.2)
			(stroke
				(width 0.15)
				(type solid)
			)
			(layer "F.SilkS")
		)
		(fp_line
			(start -0.35 -1.25)
			(end 0.450001 -1.25)
			(stroke
				(width 0.15)
				(type solid)
			)
			(layer "F.SilkS")
		)
		(fp_circle
			(center -1.75 1.5)
			(end -1.7 1.5)
			(stroke
				(width 0.15)
				(type solid)
			)
			(fill no)
			(layer "F.SilkS")
		)
		(fp_poly
			(pts
				(xy -1.907 -1.55) (xy 2.006 -1.55) (xy 2.006 1.649) (xy -1.907001 1.649)
			)
			(stroke
				(width 0.05)
				(type solid)
			)
			(fill no)
			(layer "F.CrtYd")
		)
		(fp_text user "Author: Antmicro"
			(at -1.75 5 225)
			(layer "F.Fab")
			(effects
				(font
					(size 0.7 0.7)
					(thickness 0.15)
				)
				(justify left bottom)
			)
		)
		(fp_text user "License: Apache-2.0"
			(at -1.75 6.5 225)
			(layer "F.Fab")
			(effects
				(font
					(size 0.7 0.7)
					(thickness 0.15)
				)
				(justify left bottom)
			)
		)
		(fp_text user "${REFERENCE}"
			(at -1.749999 3.75 225)
			(layer "F.Fab")
			(effects
				(font
					(size 0.7 0.7)
					(thickness 0.15)
				)
				(justify left bottom)
			)
		)
		(pad "1" smd roundrect
			(at -1.101 0.949 225)
			(size 1.3 1.1)
			(layers "F.Cu" "F.Mask" "F.Paste")
			(roundrect_rratio 0)
			(chamfer_ratio 0.2)
			(chamfer bottom_left)
			(net 764 "/FPGA MGT Interface/XA")
			(pintype "passive")
		)
		(pad "2" smd rect
			(at 1.199 0.949 225)
			(size 1.3 1.1)
			(layers "F.Cu" "F.Mask" "F.Paste")
			(net 1 "GND")
			(pinfunction "SH")
			(pintype "passive")
		)
		(pad "3" smd rect
			(at 1.199 -0.85 225)
			(size 1.3 1.1)
			(layers "F.Cu" "F.Mask" "F.Paste")
			(net 765 "/FPGA MGT Interface/XB")
			(pintype "passive")
		)
		(pad "4" smd rect
			(at -1.101 -0.85 225)
			(size 1.3 1.1)
			(layers "F.Cu" "F.Mask" "F.Paste")
			(net 1 "GND")
			(pinfunction "SH")
			(pintype "passive")
		)
	)
	(footprint "antmicro-footprints:LED_0603_1608Metric_G"
		(layer "F.Cu")
		(at 108.005 102.225 90)
		(descr "LED SMD 0603 Green")
		(tags "LED SMD 0603 Green")
		(property "Reference" "D6"
			(at -2.575 -0.305 90)
			(layer "F.SilkS")
			(hide yes)
			(effects
				(font
					(size 0.7 0.7)
					(thickness 0.15)
				)
				(justify left bottom)
			)
		)
		(property "Value" "LED_G_0603_KP-1608CGCK"
			(at -0.001 1.599 90)
			(layer "F.Fab")
			(effects
				(font
					(size 0.7 0.7)
					(thickness 0.15)
				)
				(justify left bottom)
			)
		)
		(property "Datasheet" "http://www.kingbright.com/attachments/file/psearch//000/00/00/KP-1608CGCK(Ver.23B).pdf"
			(at 0 0 90)
			(layer "F.Fab")
			(hide yes)
			(effects
				(font
					(size 1.27 1.27)
					(thickness 0.15)
				)
			)
		)
		(property "MPN" "KP-1608CGCK"
			(at 0 0 90)
			(unlocked yes)
			(layer "F.Fab")
			(hide yes)
			(effects
				(font
					(size 1 1)
					(thickness 0.15)
				)
			)
		)
		(property "Manufacturer" "Kingbright"
			(at 0 0 90)
			(unlocked yes)
			(layer "F.Fab")
			(hide yes)
			(effects
				(font
					(size 1 1)
					(thickness 0.15)
				)
			)
		)
		(property "Author" "Antmicro"
			(at 0 0 90)
			(unlocked yes)
			(layer "F.Fab")
			(hide yes)
			(effects
				(font
					(size 1 1)
					(thickness 0.15)
				)
			)
		)
		(property "License" "Apache-2.0"
			(at 0 0 90)
			(unlocked yes)
			(layer "F.Fab")
			(hide yes)
			(effects
				(font
					(size 1 1)
					(thickness 0.15)
				)
			)
		)
		(property "Color" "Green"
			(at 0 0 90)
			(unlocked yes)
			(layer "F.Fab")
			(hide yes)
			(effects
				(font
					(size 1 1)
					(thickness 0.15)
				)
			)
		)
		(sheetname "/FPGA banks HD/")
		(sheetfile "fpga-hd-banks.kicad_sch")
		(attr smd)
		(fp_line
			(start 0.22 -0.35)
			(end -0.22 -0.35)
			(stroke
				(width 0.15)
				(type solid)
			)
			(layer "F.SilkS")
		)
		(fp_line
			(start -1.18 -0.319)
			(end -1.18 0.321)
			(stroke
				(width 0.15)
				(type solid)
			)
			(layer "F.SilkS")
		)
		(fp_line
			(start 0.105328 0.001008)
			(end 0.24 0.001)
			(stroke
				(width 0.1)
				(type solid)
			)
			(layer "F.SilkS")
		)
		(fp_line
			(start -0.094672 0.001008)
			(end 0.105328 -0.198992)
			(stroke
				(width 0.1)
				(type solid)
			)
			(layer "F.SilkS")
		)
		(fp_line
			(start -0.094672 0.001008)
			(end -0.24 0.001008)
			(stroke
				(width 0.1)
				(type solid)
			)
			(layer "F.SilkS")
		)
		(fp_line
			(start 0.105328 0.201008)
			(end 0.105328 -0.198992)
			(stroke
				(width 0.1)
				(type solid)
			)
			(layer "F.SilkS")
		)
		(fp_line
			(start 0.105328 0.201008)
			(end -0.094672 0.001008)
			(stroke
				(width 0.1)
				(type solid)
			)
			(layer "F.SilkS")
		)
		(fp_line
			(start -0.094672 0.201008)
			(end -0.094672 -0.198992)
			(stroke
				(width 0.1)
				(type solid)
			)
			(layer "F.SilkS")
		)
		(fp_line
			(start 0.22 0.35)
			(end -0.22 0.35)
			(stroke
				(width 0.15)
				(type solid)
			)
			(layer "F.SilkS")
		)
		(fp_rect
			(start 1.25 0.65)
			(end -1.25 -0.65)
			(stroke
				(width 0.05)
				(type solid)
			)
			(fill no)
			(layer "F.CrtYd")
		)
		(fp_line
			(start 0.201 -0.202)
			(end -0.101 0)
			(stroke
				(width 0.15)
				(type solid)
			)
			(layer "F.Fab")
		)
		(fp_line
			(start -0.199 -0.202)
			(end -0.199 0.1)
			(stroke
				(width 0.15)
				(type solid)
			)
			(layer "F.Fab")
		)
		(fp_line
			(start 0.599 0)
			(end 0.201 0)
			(stroke
				(width 0.15)
				(type solid)
			)
			(layer "F.Fab")
		)
		(fp_line
			(start 0.201 0)
			(end 0.201 -0.202)
			(stroke
				(width 0.15)
				(type solid)
			)
			(layer "F.Fab")
		)
		(fp_line
			(start -0.101 0)
			(end 0.201 0.2)
			(stroke
				(width 0.15)
				(type solid)
			)
			(layer "F.Fab")
		)
		(fp_line
			(start -0.199 0)
			(end -0.597 0)
			(stroke
				(width 0.15)
				(type solid)
			)
			(layer "F.Fab")
		)
		(fp_line
			(start 0.201 0.2)
			(end 0.201 0)
			(stroke
				(width 0.15)
				(type solid)
			)
			(layer "F.Fab")
		)
		(fp_line
			(start -0.199 0.2)
			(end -0.199 0.1)
			(stroke
				(width 0.15)
				(type solid)
			)
			(layer "F.Fab")
		)
		(fp_rect
			(start 0.848 0.4)
			(end -0.85 -0.402)
			(stroke
				(width 0.15)
				(type solid)
			)
			(fill no)
			(layer "F.Fab")
		)
		(fp_text user "${REFERENCE}"
			(at -1.4224 5.999 90)
			(layer "F.Fab")
			(effects
				(font
					(size 0.7 0.7)
					(thickness 0.15)
				)
				(justify left bottom)
			)
		)
		(fp_text user "License: Apache-2.0"
			(at -1.4224 3.599 90)
			(layer "F.Fab")
			(effects
				(font
					(size 0.7 0.7)
					(thickness 0.15)
				)
				(justify left bottom)
			)
		)
		(fp_text user "Author: Antmicro"
			(at -1.4224 4.799 90)
			(layer "F.Fab")
			(effects
				(font
					(size 0.7 0.7)
					(thickness 0.15)
				)
				(justify left bottom)
			)
		)
		(pad "1" smd roundrect
			(at -0.7 0 270)
			(size 0.8 1)
			(layers "F.Cu" "F.Mask" "F.Paste")
			(roundrect_rratio 0.2)
			(net 151 "+3V3")
			(pinfunction "C")
			(pintype "passive")
		)
		(pad "2" smd roundrect
			(at 0.7 0 270)
			(size 0.8 1)
			(layers "F.Cu" "F.Mask" "F.Paste")
			(roundrect_rratio 0.2)
			(net 231 "Net-(D6-A)")
			(pinfunction "A")
			(pintype "passive")
		)
	)
	(footprint "antmicro-footprints:DFN-8-1EP_3x2mm_P0.5mm_EP1.36x1.46mm"
		(layer "F.Cu")
		(at 130.758 172.363)
		(property "Reference" "U42"
			(at -1.808 2.212 0)
			(layer "F.SilkS")
			(effects
				(font
					(size 0.7 0.7)
					(thickness 0.15)
				)
				(justify left bottom)
			)
		)
		(property "Value" "M24C64-F_DFN8"
			(at 0 2.2 0)
			(layer "F.Fab")
			(effects
				(font
					(size 0.7 0.7)
					(thickness 0.15)
				)
				(justify left bottom)
			)
		)
		(property "Datasheet" "https://eu.mouser.com/datasheet/2/389/cd00259166-1797197.pdf"
			(at 0 0 0)
			(layer "F.Fab")
			(hide yes)
			(effects
				(font
					(size 1.27 1.27)
					(thickness 0.15)
				)
			)
		)
		(property "Manufacturer" "STMicroelectronics"
			(at 0 0 0)
			(unlocked yes)
			(layer "F.Fab")
			(hide yes)
			(effects
				(font
					(size 1 1)
					(thickness 0.15)
				)
			)
		)
		(property "MPN" "M24C64-FMC6TG"
			(at 0 0 0)
			(unlocked yes)
			(layer "F.Fab")
			(hide yes)
			(effects
				(font
					(size 1 1)
					(thickness 0.15)
				)
			)
		)
		(property "Author" "Antmicro"
			(at 0 0 0)
			(unlocked yes)
			(layer "F.Fab")
			(hide yes)
			(effects
				(font
					(size 1 1)
					(thickness 0.15)
				)
			)
		)
		(property "License" "Apache-2.0"
			(at 0 0 0)
			(unlocked yes)
			(layer "F.Fab")
			(hide yes)
			(effects
				(font
					(size 1 1)
					(thickness 0.15)
				)
			)
		)
		(property ki_fp_filters "UFDFPN8DFN8_2X3_STM UFDFPN8DFN8_2X3_STM-M UFDFPN8DFN8_2X3_STM-L")
		(sheetname "/HDMI + SD Card/")
		(sheetfile "hdmi-sd-card.kicad_sch")
		(attr smd)
		(fp_line
			(start -1.501 1.111)
			(end 1.518 1.111)
			(stroke
				(width 0.15)
				(type solid)
			)
			(layer "F.SilkS")
		)
		(fp_line
			(start 1.498 -1.12)
			(end -1.511 -1.12)
			(stroke
				(width 0.15)
				(type solid)
			)
			(layer "F.SilkS")
		)
		(fp_circle
			(center -1.751 -1.05)
			(end -1.7 -1.05)
			(stroke
				(width 0.15)
				(type solid)
			)
			(fill yes)
			(layer "F.SilkS")
		)
		(fp_line
			(start -1.901 -1.262)
			(end 1.889 -1.262)
			(stroke
				(width 0.05)
				(type solid)
			)
			(layer "F.CrtYd")
		)
		(fp_line
			(start -1.901 1.228)
			(end -1.901 -1.262)
			(stroke
				(width 0.05)
				(type solid)
			)
			(layer "F.CrtYd")
		)
		(fp_line
			(start 1.889 -1.262)
			(end 1.889 1.228)
			(stroke
				(width 0.05)
				(type solid)
			)
			(layer "F.CrtYd")
		)
		(fp_line
			(start 1.889 1.228)
			(end -1.901 1.228)
			(stroke
				(width 0.05)
				(type solid)
			)
			(layer "F.CrtYd")
		)
		(fp_line
			(start -1.501 0.99)
			(end -1.501 -0.989)
			(stroke
				(width 0.15)
				(type solid)
			)
			(layer "F.Fab")
		)
		(fp_line
			(start 1.498 -0.999)
			(end -1.491 -0.999)
			(stroke
				(width 0.15)
				(type solid)
			)
			(layer "F.Fab")
		)
		(fp_line
			(start 1.498 -0.999)
			(end 1.498 0.99)
			(stroke
				(width 0.15)
				(type solid)
			)
			(layer "F.Fab")
		)
		(fp_line
			(start 1.498 0.999)
			(end -1.501 0.999)
			(stroke
				(width 0.15)
				(type solid)
			)
			(layer "F.Fab")
		)
		(fp_text user "Author: Antmicro"
			(at -2.27 5.253 0)
			(layer "F.Fab")
			(effects
				(font
					(size 0.7 0.7)
					(thickness 0.15)
				)
				(justify left bottom)
			)
		)
		(fp_text user "License: Apache-2.0"
			(at -2.27 6.453 0)
			(layer "F.Fab")
			(effects
				(font
					(size 0.7 0.7)
					(thickness 0.15)
				)
				(justify left bottom)
			)
		)
		(fp_text user "${REFERENCE}"
			(at -2.27 4.052 0)
			(layer "F.Fab")
			(effects
				(font
					(size 0.7 0.7)
					(thickness 0.15)
				)
				(justify left bottom)
			)
		)
		(pad "1" smd rect
			(at -1.451 -0.749 270)
			(size 0.3 0.7)
			(layers "F.Cu" "F.Mask" "F.Paste")
			(net 1 "GND")
			(pinfunction "E0")
			(pintype "input")
		)
		(pad "2" smd rect
			(at -1.451 -0.25 270)
			(size 0.3 0.7)
			(layers "F.Cu" "F.Mask" "F.Paste")
			(net 1 "GND")
			(pinfunction "E1")
			(pintype "input")
		)
		(pad "3" smd rect
			(at -1.451 0.249 270)
			(size 0.3 0.7)
			(layers "F.Cu" "F.Mask" "F.Paste")
			(net 1 "GND")
			(pinfunction "E2")
			(pintype "input")
		)
		(pad "4" smd rect
			(at -1.451 0.75 270)
			(size 0.3 0.7)
			(layers "F.Cu" "F.Mask" "F.Paste")
			(net 1 "GND")
			(pinfunction "VSS")
			(pintype "power_in")
		)
		(pad "5" smd rect
			(at 1.448 0.75 270)
			(size 0.3 0.7)
			(layers "F.Cu" "F.Mask" "F.Paste")
			(net 769 "/FPGA MGT Interface/HDMI_CTL.SDA")
			(pinfunction "SDA")
			(pintype "bidirectional")
		)
		(pad "6" smd rect
			(at 1.448 0.249 270)
			(size 0.3 0.7)
			(layers "F.Cu" "F.Mask" "F.Paste")
			(net 768 "/FPGA MGT Interface/HDMI_CTL.SCL")
			(pinfunction "SCL")
			(pintype "input")
		)
		(pad "7" smd rect
			(at 1.448 -0.25 270)
			(size 0.3 0.7)
			(layers "F.Cu" "F.Mask" "F.Paste")
			(net 1 "GND")
			(pinfunction "~{WC}")
			(pintype "input")
		)
		(pad "8" smd rect
			(at 1.448 -0.749 270)
			(size 0.3 0.7)
			(layers "F.Cu" "F.Mask" "F.Paste")
			(net 151 "+3V3")
			(pinfunction "VCC")
			(pintype "power_in")
		)
		(pad "9" smd rect
			(at 0 0 270)
			(size 1.5 1.7)
			(layers "F.Cu" "F.Mask" "F.Paste")
			(net 1 "GND")
			(pinfunction "VSS")
			(pintype "passive")
			(solder_paste_margin_ratio -0.1)
		)
	)
	(footprint "antmicro-footprints:C_0402_1005Metric"
		(layer "F.Cu")
		(at 163.95 161.154999 90)
		(descr "Capacitor SMD 0402")
		(tags "capacitor SMD 0402")
		(property "Reference" "C285"
			(at 1.255 0.48 90)
			(layer "F.SilkS")
			(effects
				(font
					(size 0.7 0.7)
					(thickness 0.15)
				)
				(justify left bottom)
			)
		)
		(property "Value" "C_100n_0402"
			(at -1.022927 2.155213 90)
			(layer "F.Fab")
			(effects
				(font
					(size 0.7 0.7)
					(thickness 0.15)
				)
				(justify left bottom)
			)
		)
		(property "Datasheet" "https://www.murata.com/products/productdetail?partno=GRM155R61H104KE14%23"
			(at 0 0 90)
			(layer "F.Fab")
			(hide yes)
			(effects
				(font
					(size 1.27 1.27)
					(thickness 0.15)
				)
			)
		)
		(property "MPN" "GRM155R61H104KE14D"
			(at 0 0 90)
			(unlocked yes)
			(layer "F.Fab")
			(hide yes)
			(effects
				(font
					(size 1 1)
					(thickness 0.15)
				)
			)
		)
		(property "Manufacturer" "Murata"
			(at 0 0 90)
			(unlocked yes)
			(layer "F.Fab")
			(hide yes)
			(effects
				(font
					(size 1 1)
					(thickness 0.15)
				)
			)
		)
		(property "License" "Apache-2.0"
			(at 0 0 90)
			(unlocked yes)
			(layer "F.Fab")
			(hide yes)
			(effects
				(font
					(size 1 1)
					(thickness 0.15)
				)
			)
		)
		(property "Author" "Antmicro"
			(at 0 0 90)
			(unlocked yes)
			(layer "F.Fab")
			(hide yes)
			(effects
				(font
					(size 1 1)
					(thickness 0.15)
				)
			)
		)
		(property "Val" "100n"
			(at 0 0 90)
			(unlocked yes)
			(layer "F.Fab")
			(hide yes)
			(effects
				(font
					(size 1 1)
					(thickness 0.15)
				)
			)
		)
		(property "Voltage" "50V"
			(at 0 0 90)
			(unlocked yes)
			(layer "F.Fab")
			(hide yes)
			(effects
				(font
					(size 1 1)
					(thickness 0.15)
				)
			)
		)
		(property "Dielectric" "X5R"
			(at 0 0 90)
			(unlocked yes)
			(layer "F.Fab")
			(hide yes)
			(effects
				(font
					(size 1 1)
					(thickness 0.15)
				)
			)
		)
		(property "Public" ""
			(at 0 0 90)
			(unlocked yes)
			(layer "F.Fab")
			(hide yes)
			(effects
				(font
					(size 1 1)
					(thickness 0.15)
				)
			)
		)
		(sheetname "/FPGA MGT Interface/")
		(sheetfile "fpga-mgt.kicad_sch")
		(attr smd)
		(fp_rect
			(start -0.925 -0.47)
			(end 0.925 0.47)
			(stroke
				(width 0.05)
				(type default)
			)
			(fill no)
			(layer "F.CrtYd")
		)
		(fp_line
			(start 0.504 -0.25)
			(end 0.504 0.248)
			(stroke
				(width 0.15)
				(type solid)
			)
			(layer "F.Fab")
		)
		(fp_line
			(start -0.494 -0.25)
			(end 0.504 -0.25)
			(stroke
				(width 0.15)
				(type solid)
			)
			(layer "F.Fab")
		)
		(fp_line
			(start 0.504 0.248)
			(end -0.494 0.248)
			(stroke
				(width 0.15)
				(type solid)
			)
			(layer "F.Fab")
		)
		(fp_line
			(start -0.494 0.248)
			(end -0.494 -0.25)
			(stroke
				(width 0.15)
				(type solid)
			)
			(layer "F.Fab")
		)
		(fp_text user "Author: Antmicro"
			(at -0.939 3.399 90)
			(layer "F.Fab")
			(effects
				(font
					(size 0.7 0.7)
					(thickness 0.15)
				)
				(justify left bottom)
			)
		)
		(fp_text user "License: Apache-2.0"
			(at -0.939 5.799 90)
			(layer "F.Fab")
			(effects
				(font
					(size 0.7 0.7)
					(thickness 0.15)
				)
				(justify left bottom)
			)
		)
		(fp_text user "${REFERENCE}"
			(at -0.939 4.599 90)
			(layer "F.Fab")
			(effects
				(font
					(size 0.7 0.7)
					(thickness 0.15)
				)
				(justify left bottom)
			)
		)
		(pad "1" smd roundrect
			(at -0.48 0 90)
			(size 0.59 0.64)
			(layers "F.Cu" "F.Mask" "F.Paste")
			(roundrect_rratio 0.25)
			(net 151 "+3V3")
			(pintype "passive")
		)
		(pad "2" smd roundrect
			(at 0.48 0 90)
			(size 0.59 0.64)
			(layers "F.Cu" "F.Mask" "F.Paste")
			(roundrect_rratio 0.25)
			(net 1 "GND")
			(pintype "passive")
		)
	)
	(footprint "antmicro-footprints:R_0402_1005Metric"
		(layer "F.Cu")
		(at 126.681 166.1125 90)
		(descr "Resistor SMD 0402")
		(tags "resistor SMD 0402")
		(property "Reference" "R224"
			(at 0.9125 3.969 90)
			(layer "F.SilkS")
			(effects
				(font
					(size 0.7 0.7)
					(thickness 0.15)
				)
				(justify left bottom)
			)
		)
		(property "Value" "R_64k9_0402"
			(at -1.011843 1.772047 90)
			(layer "F.Fab")
			(effects
				(font
					(size 0.7 0.7)
					(thickness 0.15)
				)
				(justify left bottom)
			)
		)
		(property "Datasheet" "https://www.bourns.com/docs/product-datasheets/cr.pdf"
			(at 0 0 90)
			(layer "F.Fab")
			(hide yes)
			(effects
				(font
					(size 1.27 1.27)
					(thickness 0.15)
				)
			)
		)
		(property "MPN" "CR0402-FX-6492GLF"
			(at 0 0 90)
			(unlocked yes)
			(layer "F.Fab")
			(hide yes)
			(effects
				(font
					(size 1 1)
					(thickness 0.15)
				)
			)
		)
		(property "Manufacturer" "Bourns"
			(at 0 0 90)
			(unlocked yes)
			(layer "F.Fab")
			(hide yes)
			(effects
				(font
					(size 1 1)
					(thickness 0.15)
				)
			)
		)
		(property "License" "Apache-2.0"
			(at 0 0 90)
			(unlocked yes)
			(layer "F.Fab")
			(hide yes)
			(effects
				(font
					(size 1 1)
					(thickness 0.15)
				)
			)
		)
		(property "Author" "Antmicro"
			(at 0 0 90)
			(unlocked yes)
			(layer "F.Fab")
			(hide yes)
			(effects
				(font
					(size 1 1)
					(thickness 0.15)
				)
			)
		)
		(property "Val" "64k9"
			(at 0 0 90)
			(unlocked yes)
			(layer "F.Fab")
			(hide yes)
			(effects
				(font
					(size 1 1)
					(thickness 0.15)
				)
			)
		)
		(property "Tolerance" "1%"
			(at 0 0 90)
			(unlocked yes)
			(layer "F.Fab")
			(hide yes)
			(effects
				(font
					(size 1 1)
					(thickness 0.15)
				)
			)
		)
		(sheetname "/HDMI + SD Card/")
		(sheetfile "hdmi-sd-card.kicad_sch")
		(attr smd exclude_from_bom dnp)
		(fp_rect
			(start -0.925 -0.47)
			(end 0.925 0.47)
			(stroke
				(width 0.05)
				(type default)
			)
			(fill no)
			(layer "F.CrtYd")
		)
		(fp_rect
			(start -0.5 -0.25)
			(end 0.5 0.25)
			(stroke
				(width 0.15)
				(type solid)
			)
			(fill no)
			(layer "F.Fab")
		)
		(fp_text user "Author: Antmicro"
			(at -0.95 4.169 90)
			(layer "F.Fab")
			(effects
				(font
					(size 0.7 0.7)
					(thickness 0.15)
				)
				(justify left bottom)
			)
		)
		(fp_text user "${REFERENCE}"
			(at -0.95 3.168 90)
			(layer "F.Fab")
			(effects
				(font
					(size 0.7 0.7)
					(thickness 0.15)
				)
				(justify left bottom)
			)
		)
		(fp_text user "License: Apache-2.0"
			(at -0.95 5.169 90)
			(layer "F.Fab")
			(effects
				(font
					(size 0.7 0.7)
					(thickness 0.15)
				)
				(justify left bottom)
			)
		)
		(pad "1" smd roundrect
			(at -0.48 0 90)
			(size 0.59 0.64)
			(layers "F.Cu" "F.Mask" "F.Paste")
			(roundrect_rratio 0.25)
			(net 707 "/HDMI + SD Card/SWAP{slash}POL")
			(pintype "passive")
		)
		(pad "2" smd roundrect
			(at 0.48 0 90)
			(size 0.59 0.64)
			(layers "F.Cu" "F.Mask" "F.Paste")
			(roundrect_rratio 0.25)
			(net 151 "+3V3")
			(pintype "passive")
		)
	)
	(footprint "antmicro-footprints:FB_0603_1608Metric"
		(layer "F.Cu")
		(at 116.981 172.1625 -90)
		(property "Reference" "FB3"
			(at -1.9125 -1.635 90)
			(layer "F.SilkS")
			(effects
				(font
					(size 0.7 0.7)
					(thickness 0.15)
				)
				(justify right bottom)
			)
		)
		(property "Value" "FB_120Z_2A_Murata-BLM18PG_0603"
			(at 0 1.5 90)
			(layer "F.Fab")
			(effects
				(font
					(size 0.7 0.7)
					(thickness 0.15)
				)
				(justify right bottom)
			)
		)
		(property "Datasheet" "https://www.murata.com/en-us/products/productdata/8796738650142/ENFA0003.pdf"
			(at 0 0 270)
			(layer "F.Fab")
			(hide yes)
			(effects
				(font
					(size 1.27 1.27)
					(thickness 0.15)
				)
			)
		)
		(property "Val" "120Z/2A"
			(at 0 0 270)
			(unlocked yes)
			(layer "F.Fab")
			(hide yes)
			(effects
				(font
					(size 1 1)
					(thickness 0.15)
				)
			)
		)
		(property "MPN" "BLM18PG121SN1D"
			(at 0 0 270)
			(unlocked yes)
			(layer "F.Fab")
			(hide yes)
			(effects
				(font
					(size 1 1)
					(thickness 0.15)
				)
			)
		)
		(property "Manufacturer" "Murata"
			(at 0 0 270)
			(unlocked yes)
			(layer "F.Fab")
			(hide yes)
			(effects
				(font
					(size 1 1)
					(thickness 0.15)
				)
			)
		)
		(property "Author" "Antmicro"
			(at 0 0 270)
			(unlocked yes)
			(layer "F.Fab")
			(hide yes)
			(effects
				(font
					(size 1 1)
					(thickness 0.15)
				)
			)
		)
		(property "License" "Apache-2.0"
			(at 0 0 270)
			(unlocked yes)
			(layer "F.Fab")
			(hide yes)
			(effects
				(font
					(size 1 1)
					(thickness 0.15)
				)
			)
		)
		(sheetname "/HDMI + SD Card/")
		(sheetfile "hdmi-sd-card.kicad_sch")
		(attr smd)
		(fp_line
			(start -0.15 0.4)
			(end 0.15 0.4)
			(stroke
				(width 0.15)
				(type solid)
			)
			(layer "F.SilkS")
		)
		(fp_line
			(start -0.15 -0.4)
			(end 0.15 -0.4)
			(stroke
				(width 0.15)
				(type solid)
			)
			(layer "F.SilkS")
		)
		(fp_rect
			(start -1.25 -0.65)
			(end 1.25 0.65)
			(stroke
				(width 0.05)
				(type solid)
			)
			(fill no)
			(layer "F.CrtYd")
		)
		(fp_line
			(start -0.803 0.406)
			(end -0.803 -0.408)
			(stroke
				(width 0.15)
				(type solid)
			)
			(layer "F.Fab")
		)
		(fp_line
			(start 0.8 0.406)
			(end -0.803 0.406)
			(stroke
				(width 0.15)
				(type solid)
			)
			(layer "F.Fab")
		)
		(fp_line
			(start 0.8 -0.408)
			(end 0.8 0.406)
			(stroke
				(width 0.15)
				(type solid)
			)
			(layer "F.Fab")
		)
		(fp_line
			(start 0.8 -0.408)
			(end -0.803 -0.408)
			(stroke
				(width 0.15)
				(type solid)
			)
			(layer "F.Fab")
		)
		(fp_text user "${REFERENCE}"
			(at -1.653 4.6 270)
			(layer "F.Fab")
			(effects
				(font
					(size 0.7 0.7)
					(thickness 0.15)
				)
				(justify left bottom)
			)
		)
		(fp_text user "Author: Antmicro"
			(at -1.653 3.162 270)
			(layer "F.Fab")
			(effects
				(font
					(size 0.7 0.7)
					(thickness 0.15)
				)
				(justify left bottom)
			)
		)
		(fp_text user "License: Apache-2.0"
			(at -1.653 5.9 270)
			(layer "F.Fab")
			(effects
				(font
					(size 0.7 0.7)
					(thickness 0.15)
				)
				(justify left bottom)
			)
		)
		(pad "1" smd roundrect
			(at -0.7 0 270)
			(size 0.8 1)
			(layers "F.Cu" "F.Mask" "F.Paste")
			(roundrect_rratio 0.2)
			(net 152 "+5V")
			(pintype "passive")
		)
		(pad "2" smd roundrect
			(at 0.7 0 270)
			(size 0.8 1)
			(layers "F.Cu" "F.Mask" "F.Paste")
			(roundrect_rratio 0.2)
			(net 33 "/HDMI + SD Card/HDMI_5V")
			(pintype "passive")
		)
	)
	(footprint "antmicro-footprints:L_WE-HCM-7050"
		(layer "F.Cu")
		(at 229.15 174.725 90)
		(property "Reference" "L2"
			(at -2.9 -3.9 90)
			(layer "F.SilkS")
			(effects
				(font
					(size 0.7 0.7)
					(thickness 0.15)
				)
				(justify left bottom)
			)
		)
		(property "Value" "L_150n_30A_WE-HCM-7050"
			(at -2.9 5.2 90)
			(layer "F.Fab")
			(effects
				(font
					(size 0.7 0.7)
					(thickness 0.15)
				)
				(justify left bottom)
			)
		)
		(property "Datasheet" "https://www.we-online.com/components/products/datasheet/744302015.pdf"
			(at 0 0 90)
			(layer "F.Fab")
			(hide yes)
			(effects
				(font
					(size 1.27 1.27)
					(thickness 0.15)
				)
			)
		)
		(property "Val" "150n/30A"
			(at 0 0 90)
			(unlocked yes)
			(layer "F.Fab")
			(hide yes)
			(effects
				(font
					(size 1 1)
					(thickness 0.15)
				)
			)
		)
		(property "Manufacturer" "Würth Elektronik"
			(at 0 0 90)
			(unlocked yes)
			(layer "F.Fab")
			(hide yes)
			(effects
				(font
					(size 1 1)
					(thickness 0.15)
				)
			)
		)
		(property "MPN" "744302015"
			(at 0 0 90)
			(unlocked yes)
			(layer "F.Fab")
			(hide yes)
			(effects
				(font
					(size 1 1)
					(thickness 0.15)
				)
			)
		)
		(property "ISat" "35 A"
			(at 0 0 90)
			(unlocked yes)
			(layer "F.Fab")
			(hide yes)
			(effects
				(font
					(size 1 1)
					(thickness 0.15)
				)
			)
		)
		(property "IMax" "30 A"
			(at 0 0 90)
			(unlocked yes)
			(layer "F.Fab")
			(hide yes)
			(effects
				(font
					(size 1 1)
					(thickness 0.15)
				)
			)
		)
		(property "Size" "7.15x7"
			(at 0 0 90)
			(unlocked yes)
			(layer "F.Fab")
			(hide yes)
			(effects
				(font
					(size 1 1)
					(thickness 0.15)
				)
			)
		)
		(property "Author" "Antmicro"
			(at 0 0 90)
			(unlocked yes)
			(layer "F.Fab")
			(hide yes)
			(effects
				(font
					(size 1 1)
					(thickness 0.15)
				)
			)
		)
		(property "License" "Apache-2.0"
			(at 0 0 90)
			(unlocked yes)
			(layer "F.Fab")
			(hide yes)
			(effects
				(font
					(size 1 1)
					(thickness 0.15)
				)
			)
		)
		(sheetname "/Supply/DC-DC VCCINT/")
		(sheetfile "dc-dc-vccint.kicad_sch")
		(attr smd)
		(fp_line
			(start 3.6 -3.6)
			(end -3.6 -3.6)
			(stroke
				(width 0.15)
				(type solid)
			)
			(layer "F.SilkS")
		)
		(fp_line
			(start -3.6 -3.6)
			(end -3.6 -1.8)
			(stroke
				(width 0.15)
				(type solid)
			)
			(layer "F.SilkS")
		)
		(fp_line
			(start 3.6 -1.8)
			(end 3.6 -3.6)
			(stroke
				(width 0.15)
				(type solid)
			)
			(layer "F.SilkS")
		)
		(fp_line
			(start 3.6 1.8)
			(end 3.6 3.6)
			(stroke
				(width 0.15)
				(type solid)
			)
			(layer "F.SilkS")
		)
		(fp_line
			(start -3.6 1.8)
			(end -3.6 3.6)
			(stroke
				(width 0.15)
				(type solid)
			)
			(layer "F.SilkS")
		)
		(fp_line
			(start 3.6 3.6)
			(end -3.6 3.6)
			(stroke
				(width 0.15)
				(type solid)
			)
			(layer "F.SilkS")
		)
		(fp_rect
			(start -3.9 -3.75)
			(end 3.9 3.75)
			(stroke
				(width 0.05)
				(type solid)
			)
			(fill no)
			(layer "F.CrtYd")
		)
		(fp_rect
			(start -3.5 -3.5)
			(end 3.5 3.5)
			(stroke
				(width 0.15)
				(type solid)
			)
			(fill no)
			(layer "F.Fab")
		)
		(fp_text user "License: Apache-2.0"
			(at -4.25 8.4 90)
			(layer "F.Fab")
			(effects
				(font
					(size 0.7 0.7)
					(thickness 0.15)
				)
				(justify left bottom)
			)
		)
		(fp_text user "${REFERENCE}"
			(at -4.25 7.2 90)
			(layer "F.Fab")
			(effects
				(font
					(size 0.7 0.7)
					(thickness 0.15)
				)
				(justify left bottom)
			)
		)
		(fp_text user "Author: Antmicro"
			(at -4.25 9.6 90)
			(layer "F.Fab")
			(effects
				(font
					(size 0.7 0.7)
					(thickness 0.15)
				)
				(justify left bottom)
			)
		)
		(pad "1" smd roundrect
			(at -2.65 0 90)
			(size 2 3.05)
			(layers "F.Cu" "F.Mask" "F.Paste")
			(roundrect_rratio 0.1)
			(net 207 "Net-(C216-Pad2)")
			(pintype "passive")
		)
		(pad "2" smd roundrect
			(at 2.65 0 270)
			(size 2 3.05)
			(layers "F.Cu" "F.Mask" "F.Paste")
			(roundrect_rratio 0.1)
			(net 224 "/Supply/DC-DC VCCINT/0V85_REG1")
			(pintype "passive")
		)
	)
	(footprint "antmicro-footprints:C_0603_1608Metric"
		(layer "F.Cu")
		(at 248.87 173.972001 -90)
		(descr "Capacitor SMD 0603")
		(tags "capacitor 0603")
		(property "Reference" "C187"
			(at 1.277999 -0.63 90)
			(layer "F.SilkS")
			(effects
				(font
					(size 0.7 0.7)
					(thickness 0.15)
				)
				(justify right bottom)
			)
		)
		(property "Value" "C_22u_0603"
			(at -1.42757 1.770288 90)
			(layer "F.Fab")
			(effects
				(font
					(size 0.7 0.7)
					(thickness 0.15)
				)
				(justify right bottom)
			)
		)
		(property "Datasheet" "https://www.murata.com/products/productdetail?partno=GRM188R60J226MEA0%23"
			(at 0 0 270)
			(layer "F.Fab")
			(hide yes)
			(effects
				(font
					(size 1.27 1.27)
					(thickness 0.15)
				)
			)
		)
		(property "Manufacturer" "Murata"
			(at 0 0 270)
			(unlocked yes)
			(layer "F.Fab")
			(hide yes)
			(effects
				(font
					(size 1 1)
					(thickness 0.15)
				)
			)
		)
		(property "MPN" "GRM188R60J226MEA0D"
			(at 0 0 270)
			(unlocked yes)
			(layer "F.Fab")
			(hide yes)
			(effects
				(font
					(size 1 1)
					(thickness 0.15)
				)
			)
		)
		(property "Val" "22u"
			(at 0 0 270)
			(unlocked yes)
			(layer "F.Fab")
			(hide yes)
			(effects
				(font
					(size 1 1)
					(thickness 0.15)
				)
			)
		)
		(property "License" "Apache-2.0"
			(at 0 0 270)
			(unlocked yes)
			(layer "F.Fab")
			(hide yes)
			(effects
				(font
					(size 1 1)
					(thickness 0.15)
				)
			)
		)
		(property "Author" "Antmicro"
			(at 0 0 270)
			(unlocked yes)
			(layer "F.Fab")
			(hide yes)
			(effects
				(font
					(size 1 1)
					(thickness 0.15)
				)
			)
		)
		(property "Voltage" ""
			(at 0 0 270)
			(unlocked yes)
			(layer "F.Fab")
			(hide yes)
			(effects
				(font
					(size 1 1)
					(thickness 0.15)
				)
			)
		)
		(property "Dielectric" ""
			(at 0 0 270)
			(unlocked yes)
			(layer "F.Fab")
			(hide yes)
			(effects
				(font
					(size 1 1)
					(thickness 0.15)
				)
			)
		)
		(sheetname "/Supply/DC-DC AUX, MGT/")
		(sheetfile "dc-dc-aux-mgt.kicad_sch")
		(attr smd)
		(fp_line
			(start -0.15 0.4)
			(end 0.15 0.4)
			(stroke
				(width 0.15)
				(type solid)
			)
			(layer "F.SilkS")
		)
		(fp_line
			(start -0.15 -0.4)
			(end 0.15 -0.4)
			(stroke
				(width 0.15)
				(type solid)
			)
			(layer "F.SilkS")
		)
		(fp_rect
			(start -1.25 -0.65)
			(end 1.25 0.65)
			(stroke
				(width 0.05)
				(type solid)
			)
			(fill no)
			(layer "F.CrtYd")
		)
		(fp_rect
			(start -0.8 -0.4)
			(end 0.8 0.4)
			(stroke
				(width 0.15)
				(type solid)
			)
			(fill no)
			(layer "F.Fab")
		)
		(fp_text user "Author: Antmicro"
			(at -1.682 4.894 270)
			(layer "F.Fab")
			(effects
				(font
					(size 0.7 0.7)
					(thickness 0.15)
				)
				(justify left bottom)
			)
		)
		(fp_text user "License: Apache-2.0"
			(at -1.682 5.895 270)
			(layer "F.Fab")
			(effects
				(font
					(size 0.7 0.7)
					(thickness 0.15)
				)
				(justify left bottom)
			)
		)
		(fp_text user "${REFERENCE}"
			(at -1.682 3.895 270)
			(layer "F.Fab")
			(effects
				(font
					(size 0.7 0.7)
					(thickness 0.15)
				)
				(justify left bottom)
			)
		)
		(pad "1" smd roundrect
			(at -0.7 0 270)
			(size 0.8 1)
			(layers "F.Cu" "F.Mask" "F.Paste")
			(roundrect_rratio 0.2)
			(net 1 "GND")
			(pintype "passive")
		)
		(pad "2" smd roundrect
			(at 0.7 0 270)
			(size 0.8 1)
			(layers "F.Cu" "F.Mask" "F.Paste")
			(roundrect_rratio 0.2)
			(net 37 "/Supply/DC-DC AUX, MGT/1V8_local")
			(pintype "passive")
		)
	)
	(footprint "antmicro-footprints:R_0402_1005Metric"
		(layer "F.Cu")
		(at 116.256 177.3375)
		(descr "Resistor SMD 0402")
		(tags "resistor SMD 0402")
		(property "Reference" "R73"
			(at 0.9 0.45 0)
			(layer "F.SilkS")
			(effects
				(font
					(size 0.7 0.7)
					(thickness 0.15)
				)
				(justify left bottom)
			)
		)
		(property "Value" "R_2k2_0402"
			(at -1.011843 1.772047 0)
			(layer "F.Fab")
			(effects
				(font
					(size 0.7 0.7)
					(thickness 0.15)
				)
				(justify left bottom)
			)
		)
		(property "Datasheet" "https://www.bourns.com/docs/product-datasheets/cr.pdf"
			(at 0 0 0)
			(layer "F.Fab")
			(hide yes)
			(effects
				(font
					(size 1.27 1.27)
					(thickness 0.15)
				)
			)
		)
		(property "MPN" "CR0402-FX-2201GLF"
			(at 0 0 0)
			(unlocked yes)
			(layer "F.Fab")
			(hide yes)
			(effects
				(font
					(size 1 1)
					(thickness 0.15)
				)
			)
		)
		(property "Manufacturer" "Bourns"
			(at 0 0 0)
			(unlocked yes)
			(layer "F.Fab")
			(hide yes)
			(effects
				(font
					(size 1 1)
					(thickness 0.15)
				)
			)
		)
		(property "License" "Apache-2.0"
			(at 0 0 0)
			(unlocked yes)
			(layer "F.Fab")
			(hide yes)
			(effects
				(font
					(size 1 1)
					(thickness 0.15)
				)
			)
		)
		(property "Author" "Antmicro"
			(at 0 0 0)
			(unlocked yes)
			(layer "F.Fab")
			(hide yes)
			(effects
				(font
					(size 1 1)
					(thickness 0.15)
				)
			)
		)
		(property "Val" "2k2"
			(at 0 0 0)
			(unlocked yes)
			(layer "F.Fab")
			(hide yes)
			(effects
				(font
					(size 1 1)
					(thickness 0.15)
				)
			)
		)
		(property "Tolerance" "1%"
			(at 0 0 0)
			(unlocked yes)
			(layer "F.Fab")
			(hide yes)
			(effects
				(font
					(size 1 1)
					(thickness 0.15)
				)
			)
		)
		(property "Public" ""
			(at 0 0 0)
			(unlocked yes)
			(layer "F.Fab")
			(hide yes)
			(effects
				(font
					(size 1 1)
					(thickness 0.15)
				)
			)
		)
		(sheetname "/HDMI + SD Card/")
		(sheetfile "hdmi-sd-card.kicad_sch")
		(attr smd)
		(fp_rect
			(start -0.925 -0.47)
			(end 0.925 0.47)
			(stroke
				(width 0.05)
				(type default)
			)
			(fill no)
			(layer "F.CrtYd")
		)
		(fp_rect
			(start -0.5 -0.25)
			(end 0.5 0.25)
			(stroke
				(width 0.15)
				(type solid)
			)
			(fill no)
			(layer "F.Fab")
		)
		(fp_text user "License: Apache-2.0"
			(at -0.95 5.169 0)
			(layer "F.Fab")
			(effects
				(font
					(size 0.7 0.7)
					(thickness 0.15)
				)
				(justify left bottom)
			)
		)
		(fp_text user "Author: Antmicro"
			(at -0.95 4.169 0)
			(layer "F.Fab")
			(effects
				(font
					(size 0.7 0.7)
					(thickness 0.15)
				)
				(justify left bottom)
			)
		)
		(fp_text user "${REFERENCE}"
			(at -0.95 3.168 0)
			(layer "F.Fab")
			(effects
				(font
					(size 0.7 0.7)
					(thickness 0.15)
				)
				(justify left bottom)
			)
		)
		(pad "1" smd roundrect
			(at -0.48 0)
			(size 0.59 0.64)
			(layers "F.Cu" "F.Mask" "F.Paste")
			(roundrect_rratio 0.25)
			(net 467 "/HDMI + SD Card/HDMI_OUT_C.SCL")
			(pintype "passive")
		)
		(pad "2" smd roundrect
			(at 0.48 0)
			(size 0.59 0.64)
			(layers "F.Cu" "F.Mask" "F.Paste")
			(roundrect_rratio 0.25)
			(net 8 "/HDMI + SD Card/HDMI_CONN_5V")
			(pintype "passive")
		)
	)
	(footprint "antmicro-footprints:TP_SMD_1mm"
		(layer "F.Cu")
		(at 256.824499 134.649)
		(property "Reference" "TP19"
			(at 0 -0.731898 0)
			(layer "F.SilkS")
			(hide yes)
			(effects
				(font
					(size 0.7 0.7)
					(thickness 0.15)
				)
				(justify left bottom)
			)
		)
		(property "Value" "TP_1mm_SMD"
			(at 0 1.4 0)
			(layer "F.Fab")
			(effects
				(font
					(size 0.7 0.7)
					(thickness 0.15)
				)
				(justify left bottom)
			)
		)
		(property "MPN" ""
			(at 0 0 0)
			(unlocked yes)
			(layer "F.Fab")
			(hide yes)
			(effects
				(font
					(size 1 1)
					(thickness 0.15)
				)
			)
		)
		(property "Manufacturer" ""
			(at 0 0 0)
			(unlocked yes)
			(layer "F.Fab")
			(hide yes)
			(effects
				(font
					(size 1 1)
					(thickness 0.15)
				)
			)
		)
		(property "Author" "Antmicro"
			(at 0 0 0)
			(unlocked yes)
			(layer "F.Fab")
			(hide yes)
			(effects
				(font
					(size 1 1)
					(thickness 0.15)
				)
			)
		)
		(property "License" "Apache-2.0"
			(at 0 0 0)
			(unlocked yes)
			(layer "F.Fab")
			(hide yes)
			(effects
				(font
					(size 1 1)
					(thickness 0.15)
				)
			)
		)
		(sheetname "/Supply/")
		(sheetfile "supply.kicad_sch")
		(attr exclude_from_pos_files)
		(fp_circle
			(center 0 0)
			(end 0.6 0)
			(stroke
				(width 0.05)
				(type default)
			)
			(fill no)
			(layer "F.CrtYd")
		)
		(fp_text user "License: Apache-2.0"
			(at -0.5 5.2 0)
			(layer "F.Fab")
			(effects
				(font
					(size 0.7 0.7)
					(thickness 0.15)
				)
				(justify left bottom)
			)
		)
		(fp_text user "${REFERENCE}"
			(at -0.5 2.8 0)
			(layer "F.Fab")
			(effects
				(font
					(size 0.7 0.7)
					(thickness 0.15)
				)
				(justify left bottom)
			)
		)
		(fp_text user "Author: Antmicro"
			(at -0.5 4 0)
			(layer "F.Fab")
			(effects
				(font
					(size 0.7 0.7)
					(thickness 0.15)
				)
				(justify left bottom)
			)
		)
		(pad "1" smd circle
			(at 0 0)
			(size 1 1)
			(layers "F.Cu" "F.Mask")
			(net 38 "+3V3_AON")
			(pinfunction "1")
			(pintype "passive")
		)
	)
	(footprint "antmicro-footprints:USON-10_2.5x1mm_P0.5mm"
		(layer "F.Cu")
		(at 113.530499 182.5525 180)
		(descr "USON-10 2.5x1mm_ Pitch 0.5mm")
		(tags "USON-10 2.5x1mm Pitch 0.5mm")
		(property "Reference" "U10"
			(at -1.819501 0.7025 90)
			(layer "F.SilkS")
			(effects
				(font
					(size 0.7 0.7)
					(thickness 0.15)
				)
				(justify right bottom)
			)
		)
		(property "Value" "TPD4E05U06QDQARQ1"
			(at 0.018 2.499 0)
			(layer "F.Fab")
			(effects
				(font
					(size 0.7 0.7)
					(thickness 0.15)
				)
				(justify right bottom)
			)
		)
		(property "Datasheet" "https://www.ti.com/lit/ds/symlink/tpd4e05u06-q1.pdf?HQS=dis-mous-null-mousermode-dsf-pf-null-wwe&ts=1663591265741&ref_url=https%253A%252F%252Fwww.mouser.com%252F"
			(at 0 0 180)
			(layer "F.Fab")
			(hide yes)
			(effects
				(font
					(size 1.27 1.27)
					(thickness 0.15)
				)
			)
		)
		(property "Manufacturer" "Texas Instruments"
			(at 0 0 180)
			(unlocked yes)
			(layer "F.Fab")
			(hide yes)
			(effects
				(font
					(size 1 1)
					(thickness 0.15)
				)
			)
		)
		(property "MPN" "TPD4E05U06QDQARQ1"
			(at 0 0 180)
			(unlocked yes)
			(layer "F.Fab")
			(hide yes)
			(effects
				(font
					(size 1 1)
					(thickness 0.15)
				)
			)
		)
		(property "Author" "Antmicro"
			(at 0 0 180)
			(unlocked yes)
			(layer "F.Fab")
			(hide yes)
			(effects
				(font
					(size 1 1)
					(thickness 0.15)
				)
			)
		)
		(property "License" "Apache-2.0"
			(at 0 0 180)
			(unlocked yes)
			(layer "F.Fab")
			(hide yes)
			(effects
				(font
					(size 1 1)
					(thickness 0.15)
				)
			)
		)
		(sheetname "/HDMI + SD Card/")
		(sheetfile "hdmi-sd-card.kicad_sch")
		(attr smd)
		(fp_line
			(start 0.498 1.398)
			(end -0.5 1.398)
			(stroke
				(width 0.15)
				(type solid)
			)
			(layer "F.SilkS")
		)
		(fp_line
			(start 0.498 -1.401)
			(end -0.5 -1.401)
			(stroke
				(width 0.15)
				(type solid)
			)
			(layer "F.SilkS")
		)
		(fp_circle
			(center -0.68 -1.27)
			(end -0.63 -1.27)
			(stroke
				(width 0.15)
				(type solid)
			)
			(fill yes)
			(layer "F.SilkS")
		)
		(fp_rect
			(start -0.8 -1.5)
			(end 0.8 1.499)
			(stroke
				(width 0.05)
				(type solid)
			)
			(fill no)
			(layer "F.CrtYd")
		)
		(fp_line
			(start 0.498 -1.25)
			(end 0.498 1.249)
			(stroke
				(width 0.15)
				(type solid)
			)
			(layer "F.Fab")
		)
		(fp_line
			(start 0.498 -1.25)
			(end -0.25 -1.25)
			(stroke
				(width 0.15)
				(type solid)
			)
			(layer "F.Fab")
		)
		(fp_line
			(start -0.25 -1.25)
			(end -0.5 -1)
			(stroke
				(width 0.15)
				(type solid)
			)
			(layer "F.Fab")
		)
		(fp_line
			(start -0.5 1.249)
			(end 0.498 1.249)
			(stroke
				(width 0.15)
				(type solid)
			)
			(layer "F.Fab")
		)
		(fp_line
			(start -0.5 -1)
			(end -0.5 1.249)
			(stroke
				(width 0.15)
				(type solid)
			)
			(layer "F.Fab")
		)
		(fp_text user "License: Apache-2.0"
			(at -0.802 6.9 180)
			(layer "F.Fab")
			(effects
				(font
					(size 0.7 0.7)
					(thickness 0.15)
				)
				(justify left bottom)
			)
		)
		(fp_text user "${REFERENCE}"
			(at -0.802 4.498 180)
			(layer "F.Fab")
			(effects
				(font
					(size 0.7 0.7)
					(thickness 0.15)
				)
				(justify left bottom)
			)
		)
		(fp_text user "Author: Antmicro"
			(at -0.802 5.7 180)
			(layer "F.Fab")
			(effects
				(font
					(size 0.7 0.7)
					(thickness 0.15)
				)
				(justify left bottom)
			)
		)
		(pad "1" smd roundrect
			(at -0.387 -1 90)
			(size 0.25 0.55)
			(layers "F.Cu" "F.Mask" "F.Paste")
			(roundrect_rratio 0.25)
			(net 654 "/HDMI + SD Card/HDMI_OUT_CONN_D2_P")
			(pintype "passive")
		)
		(pad "2" smd roundrect
			(at -0.387 -0.5 90)
			(size 0.25 0.55)
			(layers "F.Cu" "F.Mask" "F.Paste")
			(roundrect_rratio 0.25)
			(net 655 "/HDMI + SD Card/HDMI_OUT_CONN_D2_N")
			(pintype "passive")
		)
		(pad "3" smd roundrect
			(at -0.387 0 90)
			(size 0.4 0.55)
			(layers "F.Cu" "F.Mask" "F.Paste")
			(roundrect_rratio 0.25)
			(net 1 "GND")
			(pintype "power_in")
		)
		(pad "4" smd roundrect
			(at -0.387 0.498 90)
			(size 0.25 0.55)
			(layers "F.Cu" "F.Mask" "F.Paste")
			(roundrect_rratio 0.25)
			(net 656 "/HDMI + SD Card/HDMI_OUT_CONN_D1_P")
			(pintype "passive")
		)
		(pad "5" smd roundrect
			(at -0.387 0.998 90)
			(size 0.25 0.55)
			(layers "F.Cu" "F.Mask" "F.Paste")
			(roundrect_rratio 0.25)
			(net 657 "/HDMI + SD Card/HDMI_OUT_CONN_D1_N")
			(pintype "passive")
		)
		(pad "6" smd roundrect
			(at 0.385 0.998 90)
			(size 0.25 0.55)
			(layers "F.Cu" "F.Mask" "F.Paste")
			(roundrect_rratio 0.25)
			(net 657 "/HDMI + SD Card/HDMI_OUT_CONN_D1_N")
			(pintype "passive")
		)
		(pad "7" smd roundrect
			(at 0.385 0.498 90)
			(size 0.25 0.55)
			(layers "F.Cu" "F.Mask" "F.Paste")
			(roundrect_rratio 0.25)
			(net 656 "/HDMI + SD Card/HDMI_OUT_CONN_D1_P")
			(pintype "passive")
		)
		(pad "8" smd roundrect
			(at 0.385 0 90)
			(size 0.4 0.55)
			(layers "F.Cu" "F.Mask" "F.Paste")
			(roundrect_rratio 0.25)
			(net 1 "GND")
			(pintype "passive")
		)
		(pad "9" smd roundrect
			(at 0.385 -0.5 90)
			(size 0.25 0.55)
			(layers "F.Cu" "F.Mask" "F.Paste")
			(roundrect_rratio 0.25)
			(net 655 "/HDMI + SD Card/HDMI_OUT_CONN_D2_N")
			(pintype "passive")
		)
		(pad "10" smd roundrect
			(at 0.385 -1 90)
			(size 0.25 0.55)
			(layers "F.Cu" "F.Mask" "F.Paste")
			(roundrect_rratio 0.25)
			(net 654 "/HDMI + SD Card/HDMI_OUT_CONN_D2_P")
			(pintype "passive")
		)
	)
	(footprint "antmicro-footprints:LGA-33_7x7mm_P0.65mm"
		(layer "F.Cu")
		(at 255.618 155.3085 -90)
		(property "Reference" "U20"
			(at 4.9915 4.868 0)
			(layer "F.SilkS")
			(effects
				(font
					(size 0.7 0.7)
					(thickness 0.15)
				)
				(justify left bottom)
			)
		)
		(property "Value" "MPM54304GMN"
			(at 0 5 90)
			(layer "F.Fab")
			(effects
				(font
					(size 0.7 0.7)
					(thickness 0.15)
				)
				(justify right bottom)
			)
		)
		(property "Datasheet" "https://www.monolithicpower.com/en/documentview/productdocument/index/version/2/document_type/Datasheet/lang/en/sku/MPM54304/document_id/4982/"
			(at 0 0 270)
			(layer "F.Fab")
			(hide yes)
			(effects
				(font
					(size 1.27 1.27)
					(thickness 0.15)
				)
			)
		)
		(property "MPN" "MPM54304GMN-0000"
			(at 0 0 270)
			(unlocked yes)
			(layer "F.Fab")
			(hide yes)
			(effects
				(font
					(size 1 1)
					(thickness 0.15)
				)
			)
		)
		(property "Manufacturer" "Monolithic Power Systems"
			(at 0 0 270)
			(unlocked yes)
			(layer "F.Fab")
			(hide yes)
			(effects
				(font
					(size 1 1)
					(thickness 0.15)
				)
			)
		)
		(property "Author" "Antmicro"
			(at 0 0 270)
			(unlocked yes)
			(layer "F.Fab")
			(hide yes)
			(effects
				(font
					(size 1 1)
					(thickness 0.15)
				)
			)
		)
		(property "License" "Apache-2.0"
			(at 0 0 270)
			(unlocked yes)
			(layer "F.Fab")
			(hide yes)
			(effects
				(font
					(size 1 1)
					(thickness 0.15)
				)
			)
		)
		(property ki_fp_filters "CP_48_13_ADI CP_48_13_ADI-M CP_48_13_ADI-L")
		(sheetname "/Supply/DC-DC IO/")
		(sheetfile "dc-dc-io.kicad_sch")
		(solder_paste_margin_ratio -0.1)
		(attr smd)
		(fp_line
			(start -3.65 3.648)
			(end -3.65 2.922)
			(stroke
				(width 0.15)
				(type solid)
			)
			(layer "F.SilkS")
		)
		(fp_line
			(start -2.926 3.648)
			(end -3.65 3.648)
			(stroke
				(width 0.15)
				(type solid)
			)
			(layer "F.SilkS")
		)
		(fp_line
			(start 2.922 3.648)
			(end 3.648 3.648)
			(stroke
				(width 0.15)
				(type solid)
			)
			(layer "F.SilkS")
		)
		(fp_line
			(start 3.648 3.648)
			(end 3.648 2.922)
			(stroke
				(width 0.15)
				(type solid)
			)
			(layer "F.SilkS")
		)
		(fp_line
			(start -3.665 -2.928)
			(end -3.665 -3.653)
			(stroke
				(width 0.15)
				(type solid)
			)
			(layer "F.SilkS")
		)
		(fp_line
			(start 2.922 -3.65)
			(end 3.648 -3.65)
			(stroke
				(width 0.15)
				(type solid)
			)
			(layer "F.SilkS")
		)
		(fp_line
			(start 3.648 -3.65)
			(end 3.648 -2.926)
			(stroke
				(width 0.15)
				(type solid)
			)
			(layer "F.SilkS")
		)
		(fp_line
			(start -3.665 -3.653)
			(end -2.94 -3.653)
			(stroke
				(width 0.15)
				(type solid)
			)
			(layer "F.SilkS")
		)
		(fp_circle
			(center -3.8 -1.925)
			(end -3.75 -1.925)
			(stroke
				(width 0.15)
				(type solid)
			)
			(fill yes)
			(layer "F.SilkS")
		)
		(fp_rect
			(start -4 -4)
			(end 3.999 3.999)
			(stroke
				(width 0.05)
				(type solid)
			)
			(fill no)
			(layer "F.CrtYd")
		)
		(fp_line
			(start -3.5 3.499)
			(end 3.499 3.499)
			(stroke
				(width 0.15)
				(type solid)
			)
			(layer "F.Fab")
		)
		(fp_line
			(start 3.499 3.499)
			(end 3.499 -3.5)
			(stroke
				(width 0.15)
				(type solid)
			)
			(layer "F.Fab")
		)
		(fp_line
			(start -3.5 -3.5)
			(end -3.5 3.499)
			(stroke
				(width 0.15)
				(type solid)
			)
			(layer "F.Fab")
		)
		(fp_line
			(start -3.101 -3.5)
			(end -3.5 -3.101)
			(stroke
				(width 0.15)
				(type solid)
			)
			(layer "F.Fab")
		)
		(fp_line
			(start 3.499 -3.5)
			(end -3.5 -3.5)
			(stroke
				(width 0.15)
				(type solid)
			)
			(layer "F.Fab")
		)
		(fp_text user "License: Apache-2.0"
			(at -4.35 9.699 270)
			(layer "F.Fab")
			(effects
				(font
					(size 0.7 0.7)
					(thickness 0.15)
				)
				(justify left bottom)
			)
		)
		(fp_text user "${REFERENCE}"
			(at -4.35 8.499 270)
			(layer "F.Fab")
			(effects
				(font
					(size 0.7 0.7)
					(thickness 0.15)
				)
				(justify left bottom)
			)
		)
		(fp_text user "Author: Antmicro"
			(at -4.35 7.299 270)
			(layer "F.Fab")
			(effects
				(font
					(size 0.7 0.7)
					(thickness 0.15)
				)
				(justify left bottom)
			)
		)
		(pad "1" smd rect
			(at -3.138 -1.625)
			(size 0.3 1.125)
			(layers "F.Cu" "F.Mask" "F.Paste")
			(net 158 "/Supply/DC-DC IO/VDDQ_local")
			(pinfunction "VOUT3")
			(pintype "power_out")
		)
		(pad "2" smd rect
			(at -3.138 -0.975)
			(size 0.3 1.125)
			(layers "F.Cu" "F.Mask" "F.Paste")
			(net 1 "GND")
			(pinfunction "GND")
			(pintype "passive")
		)
		(pad "3" smd rect
			(at -3.138 -0.328)
			(size 0.3 1.125)
			(layers "F.Cu" "F.Mask" "F.Paste")
			(net 533 "/I^{2}C + I3C/PWR.SDA")
			(pinfunction "SDA")
			(pintype "bidirectional")
		)
		(pad "4" smd rect
			(at -3.138 0.325)
			(size 0.3 1.125)
			(layers "F.Cu" "F.Mask" "F.Paste")
			(net 215 "/Supply/QDCDC2_SCL")
			(pinfunction "SCL")
			(pintype "input")
		)
		(pad "5" smd rect
			(at -3.138 0.972)
			(size 0.3 1.125)
			(layers "F.Cu" "F.Mask" "F.Paste")
			(net 1 "GND")
			(pinfunction "GND")
			(pintype "passive")
		)
		(pad "6" smd rect
			(at -3.138 1.624)
			(size 0.3 1.125)
			(layers "F.Cu" "F.Mask" "F.Paste")
			(net 715 "/Supply/DC-DC IO/FB6")
			(pinfunction "FB2")
			(pintype "input")
		)
		(pad "7" smd rect
			(at -2.926 3.136 90)
			(size 0.3 1.125)
			(layers "F.Cu" "F.Mask" "F.Paste")
			(net 1 "GND")
			(pinfunction "GND")
			(pintype "passive")
		)
		(pad "8" smd rect
			(at -2.275 3.136 90)
			(size 0.3 1.125)
			(layers "F.Cu" "F.Mask" "F.Paste")
			(net 46 "/Supply/DC-DC IO/5V_local")
			(pinfunction "VOUT2")
			(pintype "power_out")
		)
		(pad "9" smd rect
			(at -1.625 3.136 270)
			(size 0.3 1.125)
			(layers "F.Cu" "F.Mask" "F.Paste")
			(net 46 "/Supply/DC-DC IO/5V_local")
			(pinfunction "VOUT2")
			(pintype "passive")
		)
		(pad "10" smd rect
			(at -0.975 3.136 270)
			(size 0.3 1.125)
			(layers "F.Cu" "F.Mask" "F.Paste")
			(net 1 "GND")
			(pinfunction "GND")
			(pintype "passive")
		)
		(pad "11" smd rect
			(at -0.328 3.136 270)
			(size 0.3 1.125)
			(layers "F.Cu" "F.Mask" "F.Paste")
			(net 432 "unconnected-(U20-SW2-Pad11)")
			(pinfunction "SW2")
			(pintype "power_out+no_connect")
		)
		(pad "12" smd rect
			(at 0.325 3.136 270)
			(size 0.3 1.125)
			(layers "F.Cu" "F.Mask" "F.Paste")
			(net 433 "unconnected-(U20-SW1-Pad12)")
			(pinfunction "SW1")
			(pintype "power_out+no_connect")
		)
		(pad "13" smd rect
			(at 0.972 3.136 270)
			(size 0.3 1.125)
			(layers "F.Cu" "F.Mask" "F.Paste")
			(net 1 "GND")
			(pinfunction "GND")
			(pintype "passive")
		)
		(pad "14" smd rect
			(at 1.624 3.136 270)
			(size 0.3 1.125)
			(layers "F.Cu" "F.Mask" "F.Paste")
			(net 45 "/Supply/DC-DC IO/3V3_local")
			(pinfunction "VOUT1")
			(pintype "power_out")
		)
		(pad "15" smd rect
			(at 2.273 3.136 270)
			(size 0.3 1.125)
			(layers "F.Cu" "F.Mask" "F.Paste")
			(net 45 "/Supply/DC-DC IO/3V3_local")
			(pinfunction "VOUT1")
			(pintype "passive")
		)
		(pad "16" smd rect
			(at 2.922 3.136 270)
			(size 0.3 1.125)
			(layers "F.Cu" "F.Mask" "F.Paste")
			(net 1 "GND")
			(pinfunction "GND")
			(pintype "passive")
		)
		(pad "17" smd rect
			(at 3.136 1.624)
			(size 0.3 1.125)
			(layers "F.Cu" "F.Mask" "F.Paste")
			(net 1 "GND")
			(pinfunction "SGND1")
			(pintype "power_out")
		)
		(pad "18" smd rect
			(at 3.136 0.972)
			(size 0.3 1.125)
			(layers "F.Cu" "F.Mask" "F.Paste")
			(net 714 "/Supply/DC-DC IO/FB5")
			(pinfunction "FB1")
			(pintype "input")
		)
		(pad "19" smd rect
			(at 3.136 0.325)
			(size 0.3 1.125)
			(layers "F.Cu" "F.Mask" "F.Paste")
			(net 170 "/Supply/EN3")
			(pinfunction "EN/SYNCI")
			(pintype "input")
		)
		(pad "20" smd rect
			(at 3.136 -0.328)
			(size 0.3 1.125)
			(layers "F.Cu" "F.Mask" "F.Paste")
			(net 1 "GND")
			(pinfunction "GND")
			(pintype "passive")
		)
		(pad "21" smd rect
			(at 3.136 -0.975)
			(size 0.3 1.125)
			(layers "F.Cu" "F.Mask" "F.Paste")
			(net 1 "GND")
			(pinfunction "GND")
			(pintype "passive")
		)
		(pad "22" smd rect
			(at 3.136 -1.625)
			(size 0.3 1.125)
			(layers "F.Cu" "F.Mask" "F.Paste")
			(net 159 "/Supply/DC-DC IO/1V2_local")
			(pinfunction "VOUT4")
			(pintype "power_out")
		)
		(pad "23" smd rect
			(at 2.922 -3.138 90)
			(size 0.3 1.125)
			(layers "F.Cu" "F.Mask" "F.Paste")
			(net 159 "/Supply/DC-DC IO/1V2_local")
			(pinfunction "VOUT4")
			(pintype "passive")
		)
		(pad "24" smd rect
			(at 2.273 -3.138 90)
			(size 0.3 1.125)
			(layers "F.Cu" "F.Mask" "F.Paste")
			(net 719 "/Supply/DC-DC IO/FB8")
			(pinfunction "FB4")
			(pintype "input")
		)
		(pad "25" smd rect
			(at 1.624 -3.138 270)
			(size 0.3 1.125)
			(layers "F.Cu" "F.Mask" "F.Paste")
			(net 36 "/Supply/DC-DC IO/QDCDC2_VCC")
			(pinfunction "VCC")
			(pintype "input")
		)
		(pad "26" smd rect
			(at 0.972 -3.138 270)
			(size 0.3 1.125)
			(layers "F.Cu" "F.Mask" "F.Paste")
			(net 485 "PG3")
			(pinfunction "GPIO")
			(pintype "input")
		)
		(pad "27" smd rect
			(at 0.325 -3.138 270)
			(size 0.3 1.125)
			(layers "F.Cu" "F.Mask" "F.Paste")
			(net 1 "GND")
			(pinfunction "GND")
			(pintype "passive")
		)
		(pad "28" smd rect
			(at -0.328 -3.138 270)
			(size 0.3 1.125)
			(layers "F.Cu" "F.Mask" "F.Paste")
			(net 35 "VDC")
			(pinfunction "VIN")
			(pintype "input")
		)
		(pad "29" smd rect
			(at -0.975 -3.138 270)
			(size 0.3 1.125)
			(layers "F.Cu" "F.Mask" "F.Paste")
			(net 35 "VDC")
			(pinfunction "VIN")
			(pintype "passive")
		)
		(pad "30" smd rect
			(at -1.625 -3.138 270)
			(size 0.3 1.125)
			(layers "F.Cu" "F.Mask" "F.Paste")
			(net 1 "GND")
			(pinfunction "SGND2")
			(pintype "power_out")
		)
		(pad "31" smd rect
			(at -2.275 -3.138 270)
			(size 0.3 1.125)
			(layers "F.Cu" "F.Mask" "F.Paste")
			(net 718 "/Supply/DC-DC IO/FB7")
			(pinfunction "FB3")
			(pintype "input")
		)
		(pad "32" smd rect
			(at -2.926 -3.138 270)
			(size 0.3 1.125)
			(layers "F.Cu" "F.Mask" "F.Paste")
			(net 158 "/Supply/DC-DC IO/VDDQ_local")
			(pinfunction "VOUT3")
			(pintype "passive")
		)
		(pad "33" smd rect
			(at -0.863 -0.863 270)
			(size 1.725 1.725)
			(layers "F.Cu" "F.Mask" "F.Paste")
			(net 1 "GND")
			(pinfunction "GND")
			(pintype "passive")
			(solder_paste_margin -0.1)
		)
		(pad "33" smd rect
			(at -0.863 0.86 270)
			(size 1.725 1.725)
			(layers "F.Cu" "F.Mask" "F.Paste")
			(net 1 "GND")
			(pinfunction "GND")
			(pintype "passive")
			(solder_paste_margin -0.1)
		)
		(pad "33" smd rect
			(at 0.86 -0.863 270)
			(size 1.725 1.725)
			(layers "F.Cu" "F.Mask" "F.Paste")
			(net 1 "GND")
			(pinfunction "GND")
			(pintype "passive")
			(solder_paste_margin -0.1)
		)
		(pad "33" smd rect
			(at 0.86 0.86 270)
			(size 1.725 1.725)
			(layers "F.Cu" "F.Mask" "F.Paste")
			(net 1 "GND")
			(pinfunction "GND")
			(pintype "passive")
			(solder_paste_margin -0.1)
		)
	)
	(footprint "antmicro-footprints:LGA-33_7x7mm_P0.65mm"
		(layer "F.Cu")
		(at 255.645 172.7595 -90)
		(property "Reference" "U19"
			(at 5.0405 4.795 0)
			(layer "F.SilkS")
			(effects
				(font
					(size 0.7 0.7)
					(thickness 0.15)
				)
				(justify left bottom)
			)
		)
		(property "Value" "MPM54304GMN"
			(at 0 5 90)
			(layer "F.Fab")
			(effects
				(font
					(size 0.7 0.7)
					(thickness 0.15)
				)
				(justify right bottom)
			)
		)
		(property "Datasheet" "https://www.monolithicpower.com/en/documentview/productdocument/index/version/2/document_type/Datasheet/lang/en/sku/MPM54304/document_id/4982/"
			(at 0 0 270)
			(layer "F.Fab")
			(hide yes)
			(effects
				(font
					(size 1.27 1.27)
					(thickness 0.15)
				)
			)
		)
		(property "MPN" "MPM54304GMN-0000"
			(at 0 0 270)
			(unlocked yes)
			(layer "F.Fab")
			(hide yes)
			(effects
				(font
					(size 1 1)
					(thickness 0.15)
				)
			)
		)
		(property "Manufacturer" "Monolithic Power Systems"
			(at 0 0 270)
			(unlocked yes)
			(layer "F.Fab")
			(hide yes)
			(effects
				(font
					(size 1 1)
					(thickness 0.15)
				)
			)
		)
		(property "Author" "Antmicro"
			(at 0 0 270)
			(unlocked yes)
			(layer "F.Fab")
			(hide yes)
			(effects
				(font
					(size 1 1)
					(thickness 0.15)
				)
			)
		)
		(property "License" "Apache-2.0"
			(at 0 0 270)
			(unlocked yes)
			(layer "F.Fab")
			(hide yes)
			(effects
				(font
					(size 1 1)
					(thickness 0.15)
				)
			)
		)
		(property ki_fp_filters "CP_48_13_ADI CP_48_13_ADI-M CP_48_13_ADI-L")
		(sheetname "/Supply/DC-DC AUX, MGT/")
		(sheetfile "dc-dc-aux-mgt.kicad_sch")
		(solder_paste_margin_ratio -0.1)
		(attr smd)
		(fp_line
			(start -3.65 3.648)
			(end -3.65 2.922)
			(stroke
				(width 0.15)
				(type solid)
			)
			(layer "F.SilkS")
		)
		(fp_line
			(start -2.926 3.648)
			(end -3.65 3.648)
			(stroke
				(width 0.15)
				(type solid)
			)
			(layer "F.SilkS")
		)
		(fp_line
			(start 2.922 3.648)
			(end 3.648 3.648)
			(stroke
				(width 0.15)
				(type solid)
			)
			(layer "F.SilkS")
		)
		(fp_line
			(start 3.648 3.648)
			(end 3.648 2.922)
			(stroke
				(width 0.15)
				(type solid)
			)
			(layer "F.SilkS")
		)
		(fp_line
			(start -3.665 -2.928)
			(end -3.665 -3.653)
			(stroke
				(width 0.15)
				(type solid)
			)
			(layer "F.SilkS")
		)
		(fp_line
			(start 2.922 -3.65)
			(end 3.648 -3.65)
			(stroke
				(width 0.15)
				(type solid)
			)
			(layer "F.SilkS")
		)
		(fp_line
			(start 3.648 -3.65)
			(end 3.648 -2.926)
			(stroke
				(width 0.15)
				(type solid)
			)
			(layer "F.SilkS")
		)
		(fp_line
			(start -3.665 -3.653)
			(end -2.94 -3.653)
			(stroke
				(width 0.15)
				(type solid)
			)
			(layer "F.SilkS")
		)
		(fp_circle
			(center -3.8 -1.925)
			(end -3.75 -1.925)
			(stroke
				(width 0.15)
				(type solid)
			)
			(fill yes)
			(layer "F.SilkS")
		)
		(fp_rect
			(start -4 -4)
			(end 3.999 3.999)
			(stroke
				(width 0.05)
				(type solid)
			)
			(fill no)
			(layer "F.CrtYd")
		)
		(fp_line
			(start -3.5 3.499)
			(end 3.499 3.499)
			(stroke
				(width 0.15)
				(type solid)
			)
			(layer "F.Fab")
		)
		(fp_line
			(start 3.499 3.499)
			(end 3.499 -3.5)
			(stroke
				(width 0.15)
				(type solid)
			)
			(layer "F.Fab")
		)
		(fp_line
			(start -3.5 -3.5)
			(end -3.5 3.499)
			(stroke
				(width 0.15)
				(type solid)
			)
			(layer "F.Fab")
		)
		(fp_line
			(start -3.101 -3.5)
			(end -3.5 -3.101)
			(stroke
				(width 0.15)
				(type solid)
			)
			(layer "F.Fab")
		)
		(fp_line
			(start 3.499 -3.5)
			(end -3.5 -3.5)
			(stroke
				(width 0.15)
				(type solid)
			)
			(layer "F.Fab")
		)
		(fp_text user "License: Apache-2.0"
			(at -4.35 9.699 270)
			(layer "F.Fab")
			(effects
				(font
					(size 0.7 0.7)
					(thickness 0.15)
				)
				(justify left bottom)
			)
		)
		(fp_text user "Author: Antmicro"
			(at -4.35 7.299 270)
			(layer "F.Fab")
			(effects
				(font
					(size 0.7 0.7)
					(thickness 0.15)
				)
				(justify left bottom)
			)
		)
		(fp_text user "${REFERENCE}"
			(at -4.35 8.499 270)
			(layer "F.Fab")
			(effects
				(font
					(size 0.7 0.7)
					(thickness 0.15)
				)
				(justify left bottom)
			)
		)
		(pad "1" smd rect
			(at -3.138 -1.625)
			(size 0.3 1.125)
			(layers "F.Cu" "F.Mask" "F.Paste")
			(net 47 "/Supply/DC-DC AUX, MGT/MGTAVCC_local")
			(pinfunction "VOUT3")
			(pintype "power_out")
		)
		(pad "2" smd rect
			(at -3.138 -0.975)
			(size 0.3 1.125)
			(layers "F.Cu" "F.Mask" "F.Paste")
			(net 1 "GND")
			(pinfunction "GND")
			(pintype "passive")
		)
		(pad "3" smd rect
			(at -3.138 -0.328)
			(size 0.3 1.125)
			(layers "F.Cu" "F.Mask" "F.Paste")
			(net 533 "/I^{2}C + I3C/PWR.SDA")
			(pinfunction "SDA")
			(pintype "bidirectional")
		)
		(pad "4" smd rect
			(at -3.138 0.325)
			(size 0.3 1.125)
			(layers "F.Cu" "F.Mask" "F.Paste")
			(net 749 "/I^{2}C + I3C/PWR.SCL")
			(pinfunction "SCL")
			(pintype "input")
		)
		(pad "5" smd rect
			(at -3.138 0.972)
			(size 0.3 1.125)
			(layers "F.Cu" "F.Mask" "F.Paste")
			(net 1 "GND")
			(pinfunction "GND")
			(pintype "passive")
		)
		(pad "6" smd rect
			(at -3.138 1.624)
			(size 0.3 1.125)
			(layers "F.Cu" "F.Mask" "F.Paste")
			(net 713 "/Supply/DC-DC AUX, MGT/FB2")
			(pinfunction "FB2")
			(pintype "input")
		)
		(pad "7" smd rect
			(at -2.926 3.136 90)
			(size 0.3 1.125)
			(layers "F.Cu" "F.Mask" "F.Paste")
			(net 1 "GND")
			(pinfunction "GND")
			(pintype "passive")
		)
		(pad "8" smd rect
			(at -2.275 3.136 90)
			(size 0.3 1.125)
			(layers "F.Cu" "F.Mask" "F.Paste")
			(net 48 "/Supply/DC-DC AUX, MGT/MGTAVTT_local")
			(pinfunction "VOUT2")
			(pintype "power_out")
		)
		(pad "9" smd rect
			(at -1.625 3.136 270)
			(size 0.3 1.125)
			(layers "F.Cu" "F.Mask" "F.Paste")
			(net 48 "/Supply/DC-DC AUX, MGT/MGTAVTT_local")
			(pinfunction "VOUT2")
			(pintype "passive")
		)
		(pad "10" smd rect
			(at -0.975 3.136 270)
			(size 0.3 1.125)
			(layers "F.Cu" "F.Mask" "F.Paste")
			(net 1 "GND")
			(pinfunction "GND")
			(pintype "passive")
		)
		(pad "11" smd rect
			(at -0.328 3.136 270)
			(size 0.3 1.125)
			(layers "F.Cu" "F.Mask" "F.Paste")
			(net 430 "unconnected-(U19-SW2-Pad11)")
			(pinfunction "SW2")
			(pintype "power_out+no_connect")
		)
		(pad "12" smd rect
			(at 0.325 3.136 270)
			(size 0.3 1.125)
			(layers "F.Cu" "F.Mask" "F.Paste")
			(net 431 "unconnected-(U19-SW1-Pad12)")
			(pinfunction "SW1")
			(pintype "power_out+no_connect")
		)
		(pad "13" smd rect
			(at 0.972 3.136 270)
			(size 0.3 1.125)
			(layers "F.Cu" "F.Mask" "F.Paste")
			(net 1 "GND")
			(pinfunction "GND")
			(pintype "passive")
		)
		(pad "14" smd rect
			(at 1.624 3.136 270)
			(size 0.3 1.125)
			(layers "F.Cu" "F.Mask" "F.Paste")
			(net 37 "/Supply/DC-DC AUX, MGT/1V8_local")
			(pinfunction "VOUT1")
			(pintype "power_out")
		)
		(pad "15" smd rect
			(at 2.273 3.136 270)
			(size 0.3 1.125)
			(layers "F.Cu" "F.Mask" "F.Paste")
			(net 37 "/Supply/DC-DC AUX, MGT/1V8_local")
			(pinfunction "VOUT1")
			(pintype "passive")
		)
		(pad "16" smd rect
			(at 2.922 3.136 270)
			(size 0.3 1.125)
			(layers "F.Cu" "F.Mask" "F.Paste")
			(net 1 "GND")
			(pinfunction "GND")
			(pintype "passive")
		)
		(pad "17" smd rect
			(at 3.136 1.624)
			(size 0.3 1.125)
			(layers "F.Cu" "F.Mask" "F.Paste")
			(net 1 "GND")
			(pinfunction "SGND1")
			(pintype "power_out")
		)
		(pad "18" smd rect
			(at 3.136 0.972)
			(size 0.3 1.125)
			(layers "F.Cu" "F.Mask" "F.Paste")
			(net 712 "/Supply/DC-DC AUX, MGT/FB1")
			(pinfunction "FB1")
			(pintype "input")
		)
		(pad "19" smd rect
			(at 3.136 0.325)
			(size 0.3 1.125)
			(layers "F.Cu" "F.Mask" "F.Paste")
			(net 169 "/Supply/EN2")
			(pinfunction "EN/SYNCI")
			(pintype "input")
		)
		(pad "20" smd rect
			(at 3.136 -0.328)
			(size 0.3 1.125)
			(layers "F.Cu" "F.Mask" "F.Paste")
			(net 1 "GND")
			(pinfunction "GND")
			(pintype "passive")
		)
		(pad "21" smd rect
			(at 3.136 -0.975)
			(size 0.3 1.125)
			(layers "F.Cu" "F.Mask" "F.Paste")
			(net 1 "GND")
			(pinfunction "GND")
			(pintype "passive")
		)
		(pad "22" smd rect
			(at 3.136 -1.625)
			(size 0.3 1.125)
			(layers "F.Cu" "F.Mask" "F.Paste")
			(net 225 "/Supply/DC-DC AUX, MGT/MGTAVCCAUX_local")
			(pinfunction "VOUT4")
			(pintype "power_out")
		)
		(pad "23" smd rect
			(at 2.922 -3.138 90)
			(size 0.3 1.125)
			(layers "F.Cu" "F.Mask" "F.Paste")
			(net 225 "/Supply/DC-DC AUX, MGT/MGTAVCCAUX_local")
			(pinfunction "VOUT4")
			(pintype "passive")
		)
		(pad "24" smd rect
			(at 2.273 -3.138 90)
			(size 0.3 1.125)
			(layers "F.Cu" "F.Mask" "F.Paste")
			(net 717 "/Supply/DC-DC AUX, MGT/FB4")
			(pinfunction "FB4")
			(pintype "input")
		)
		(pad "25" smd rect
			(at 1.624 -3.138 270)
			(size 0.3 1.125)
			(layers "F.Cu" "F.Mask" "F.Paste")
			(net 9 "/Supply/DC-DC AUX, MGT/QDCDC1_VCC")
			(pinfunction "VCC")
			(pintype "input")
		)
		(pad "26" smd rect
			(at 0.972 -3.138 270)
			(size 0.3 1.125)
			(layers "F.Cu" "F.Mask" "F.Paste")
			(net 484 "PG2")
			(pinfunction "GPIO")
			(pintype "input")
		)
		(pad "27" smd rect
			(at 0.325 -3.138 270)
			(size 0.3 1.125)
			(layers "F.Cu" "F.Mask" "F.Paste")
			(net 1 "GND")
			(pinfunction "GND")
			(pintype "passive")
		)
		(pad "28" smd rect
			(at -0.328 -3.138 270)
			(size 0.3 1.125)
			(layers "F.Cu" "F.Mask" "F.Paste")
			(net 35 "VDC")
			(pinfunction "VIN")
			(pintype "input")
		)
		(pad "29" smd rect
			(at -0.975 -3.138 270)
			(size 0.3 1.125)
			(layers "F.Cu" "F.Mask" "F.Paste")
			(net 35 "VDC")
			(pinfunction "VIN")
			(pintype "passive")
		)
		(pad "30" smd rect
			(at -1.625 -3.138 270)
			(size 0.3 1.125)
			(layers "F.Cu" "F.Mask" "F.Paste")
			(net 1 "GND")
			(pinfunction "SGND2")
			(pintype "power_out")
		)
		(pad "31" smd rect
			(at -2.275 -3.138 270)
			(size 0.3 1.125)
			(layers "F.Cu" "F.Mask" "F.Paste")
			(net 716 "/Supply/DC-DC AUX, MGT/FB3")
			(pinfunction "FB3")
			(pintype "input")
		)
		(pad "32" smd rect
			(at -2.926 -3.138 270)
			(size 0.3 1.125)
			(layers "F.Cu" "F.Mask" "F.Paste")
			(net 47 "/Supply/DC-DC AUX, MGT/MGTAVCC_local")
			(pinfunction "VOUT3")
			(pintype "passive")
		)
		(pad "33" smd rect
			(at -0.863 -0.863 270)
			(size 1.725 1.725)
			(layers "F.Cu" "F.Mask" "F.Paste")
			(net 1 "GND")
			(pinfunction "GND")
			(pintype "passive")
			(solder_paste_margin -0.1)
		)
		(pad "33" smd rect
			(at -0.863 0.86 270)
			(size 1.725 1.725)
			(layers "F.Cu" "F.Mask" "F.Paste")
			(net 1 "GND")
			(pinfunction "GND")
			(pintype "passive")
			(solder_paste_margin -0.1)
		)
		(pad "33" smd rect
			(at 0.86 -0.863 270)
			(size 1.725 1.725)
			(layers "F.Cu" "F.Mask" "F.Paste")
			(net 1 "GND")
			(pinfunction "GND")
			(pintype "passive")
			(solder_paste_margin -0.1)
		)
		(pad "33" smd rect
			(at 0.86 0.86 270)
			(size 1.725 1.725)
			(layers "F.Cu" "F.Mask" "F.Paste")
			(net 1 "GND")
			(pinfunction "GND")
			(pintype "passive")
			(solder_paste_margin -0.1)
		)
	)
	(footprint "antmicro-footprints:R_0402_1005Metric"
		(layer "F.Cu")
		(at 117.088 112.722921 -90)
		(descr "Resistor SMD 0402")
		(tags "resistor SMD 0402")
		(property "Reference" "R19"
			(at -1.072921 0.563 90)
			(layer "F.SilkS")
			(effects
				(font
					(size 0.7 0.7)
					(thickness 0.15)
				)
				(justify right bottom)
			)
		)
		(property "Value" "R_330R_0402"
			(at -1.011843 1.772047 90)
			(layer "F.Fab")
			(effects
				(font
					(size 0.7 0.7)
					(thickness 0.15)
				)
				(justify right bottom)
			)
		)
		(property "Datasheet" "https://www.bourns.com/docs/product-datasheets/cr.pdf"
			(at 0 0 270)
			(layer "F.Fab")
			(hide yes)
			(effects
				(font
					(size 1.27 1.27)
					(thickness 0.15)
				)
			)
		)
		(property "Manufacturer" "Bourns"
			(at 0 0 270)
			(unlocked yes)
			(layer "F.Fab")
			(hide yes)
			(effects
				(font
					(size 1 1)
					(thickness 0.15)
				)
			)
		)
		(property "MPN" "CR0402-FX-3300GLF"
			(at 0 0 270)
			(unlocked yes)
			(layer "F.Fab")
			(hide yes)
			(effects
				(font
					(size 1 1)
					(thickness 0.15)
				)
			)
		)
		(property "Val" "330R"
			(at 0 0 270)
			(unlocked yes)
			(layer "F.Fab")
			(hide yes)
			(effects
				(font
					(size 1 1)
					(thickness 0.15)
				)
			)
		)
		(property "License" "Apache-2.0"
			(at 0 0 270)
			(unlocked yes)
			(layer "F.Fab")
			(hide yes)
			(effects
				(font
					(size 1 1)
					(thickness 0.15)
				)
			)
		)
		(property "Author" "Antmicro"
			(at 0 0 270)
			(unlocked yes)
			(layer "F.Fab")
			(hide yes)
			(effects
				(font
					(size 1 1)
					(thickness 0.15)
				)
			)
		)
		(property "Tolerance" "1%"
			(at 0 0 270)
			(unlocked yes)
			(layer "F.Fab")
			(hide yes)
			(effects
				(font
					(size 1 1)
					(thickness 0.15)
				)
			)
		)
		(sheetname "/FPGA Config/")
		(sheetfile "fpga-config.kicad_sch")
		(attr smd)
		(fp_rect
			(start -0.925 -0.47)
			(end 0.925 0.47)
			(stroke
				(width 0.05)
				(type default)
			)
			(fill no)
			(layer "F.CrtYd")
		)
		(fp_rect
			(start -0.5 -0.25)
			(end 0.5 0.25)
			(stroke
				(width 0.15)
				(type solid)
			)
			(fill no)
			(layer "F.Fab")
		)
		(fp_text user "Author: Antmicro"
			(at -0.95 4.169 270)
			(layer "F.Fab")
			(effects
				(font
					(size 0.7 0.7)
					(thickness 0.15)
				)
				(justify left bottom)
			)
		)
		(fp_text user "License: Apache-2.0"
			(at -0.95 5.169 270)
			(layer "F.Fab")
			(effects
				(font
					(size 0.7 0.7)
					(thickness 0.15)
				)
				(justify left bottom)
			)
		)
		(fp_text user "${REFERENCE}"
			(at -0.95 3.168 270)
			(layer "F.Fab")
			(effects
				(font
					(size 0.7 0.7)
					(thickness 0.15)
				)
				(justify left bottom)
			)
		)
		(pad "1" smd roundrect
			(at -0.48 0 270)
			(size 0.59 0.64)
			(layers "F.Cu" "F.Mask" "F.Paste")
			(roundrect_rratio 0.25)
			(net 797 "+1V8")
			(pintype "passive")
		)
		(pad "2" smd roundrect
			(at 0.48 0 270)
			(size 0.59 0.64)
			(layers "F.Cu" "F.Mask" "F.Paste")
			(roundrect_rratio 0.25)
			(net 340 "/FPGA Config/DONE")
			(pintype "passive")
		)
	)
	(footprint "antmicro-footprints:DFN-10-1EP_3x3mm"
		(layer "F.Cu")
		(at 239.274499 170.2)
		(property "Reference" "U25"
			(at -1.049499 3.025 0)
			(layer "F.SilkS")
			(effects
				(font
					(size 0.7 0.7)
					(thickness 0.15)
				)
				(justify left bottom)
			)
		)
		(property "Value" "PAC1720-1"
			(at 0 2.8 0)
			(layer "F.Fab")
			(effects
				(font
					(size 0.7 0.7)
					(thickness 0.15)
				)
				(justify left bottom)
			)
		)
		(property "Datasheet" "https://ww1.microchip.com/downloads/aemDocuments/documents/MSLD/ProductDocuments/DataSheets/PAC1710-PAC1720-Data-Sheet-DS20005386.pdf"
			(at 0 0 0)
			(layer "F.Fab")
			(hide yes)
			(effects
				(font
					(size 1.27 1.27)
					(thickness 0.15)
				)
			)
		)
		(property "MPN" "PAC1720-1-AIA-TR"
			(at 0 0 0)
			(unlocked yes)
			(layer "F.Fab")
			(hide yes)
			(effects
				(font
					(size 1 1)
					(thickness 0.15)
				)
			)
		)
		(property "Manufacturer" "Microchip Technology"
			(at 0 0 0)
			(unlocked yes)
			(layer "F.Fab")
			(hide yes)
			(effects
				(font
					(size 1 1)
					(thickness 0.15)
				)
			)
		)
		(property "Author" "Antmicro"
			(at 0 0 0)
			(unlocked yes)
			(layer "F.Fab")
			(hide yes)
			(effects
				(font
					(size 1 1)
					(thickness 0.15)
				)
			)
		)
		(property "License" "Apache-2.0"
			(at 0 0 0)
			(unlocked yes)
			(layer "F.Fab")
			(hide yes)
			(effects
				(font
					(size 1 1)
					(thickness 0.15)
				)
			)
		)
		(property ki_fp_filters "UQFN*1EP*4x4mm*P0.65mm*")
		(sheetname "/Supply/DC-DC AUX, MGT/")
		(sheetfile "dc-dc-aux-mgt.kicad_sch")
		(attr smd)
		(fp_line
			(start -1.624 -1.226)
			(end -1.773 -1.226)
			(stroke
				(width 0.15)
				(type solid)
			)
			(layer "F.SilkS")
		)
		(fp_line
			(start -1.6 1.6)
			(end -1.6 1.35)
			(stroke
				(width 0.15)
				(type solid)
			)
			(layer "F.SilkS")
		)
		(fp_line
			(start -1.6 1.6)
			(end -1.35 1.6)
			(stroke
				(width 0.15)
				(type solid)
			)
			(layer "F.SilkS")
		)
		(fp_line
			(start -1.249 -1.601)
			(end -1.624 -1.226)
			(stroke
				(width 0.15)
				(type solid)
			)
			(layer "F.SilkS")
		)
		(fp_line
			(start -1.249 -1.601)
			(end -0.824 -1.601)
			(stroke
				(width 0.15)
				(type solid)
			)
			(layer "F.SilkS")
		)
		(fp_line
			(start 1.601 -1.601)
			(end 1.351 -1.601)
			(stroke
				(width 0.15)
				(type solid)
			)
			(layer "F.SilkS")
		)
		(fp_line
			(start 1.601 -1.601)
			(end 1.601 -1.401)
			(stroke
				(width 0.15)
				(type solid)
			)
			(layer "F.SilkS")
		)
		(fp_line
			(start 1.601 1.6)
			(end 1.401 1.6)
			(stroke
				(width 0.15)
				(type solid)
			)
			(layer "F.SilkS")
		)
		(fp_line
			(start 1.601 1.6)
			(end 1.601 1.35)
			(stroke
				(width 0.15)
				(type solid)
			)
			(layer "F.SilkS")
		)
		(fp_circle
			(center -1.8 -1.6)
			(end -1.8 -1.551)
			(stroke
				(width 0.15)
				(type solid)
			)
			(fill yes)
			(layer "F.SilkS")
		)
		(fp_line
			(start -1.91 -1.73)
			(end 1.89 -1.73)
			(stroke
				(width 0.05)
				(type solid)
			)
			(layer "F.CrtYd")
		)
		(fp_line
			(start -1.91 1.75)
			(end -1.91 -1.73)
			(stroke
				(width 0.05)
				(type solid)
			)
			(layer "F.CrtYd")
		)
		(fp_line
			(start 1.89 1.75)
			(end -1.91 1.75)
			(stroke
				(width 0.05)
				(type solid)
			)
			(layer "F.CrtYd")
		)
		(fp_line
			(start 1.89 1.75)
			(end 1.89 -1.73)
			(stroke
				(width 0.05)
				(type solid)
			)
			(layer "F.CrtYd")
		)
		(fp_line
			(start -1.499 -1.18)
			(end -1.179 -1.5)
			(stroke
				(width 0.15)
				(type solid)
			)
			(layer "F.Fab")
		)
		(fp_line
			(start -1.499 1.499)
			(end -1.499 -1.176)
			(stroke
				(width 0.15)
				(type solid)
			)
			(layer "F.Fab")
		)
		(fp_line
			(start 1.5 -1.5)
			(end -1.175 -1.5)
			(stroke
				(width 0.15)
				(type solid)
			)
			(layer "F.Fab")
		)
		(fp_line
			(start 1.5 -1.5)
			(end 1.5 1.499)
			(stroke
				(width 0.15)
				(type solid)
			)
			(layer "F.Fab")
		)
		(fp_line
			(start 1.5 1.499)
			(end -1.499 1.499)
			(stroke
				(width 0.15)
				(type solid)
			)
			(layer "F.Fab")
		)
		(fp_text user "Author: Antmicro"
			(at -1.75 7.2 0)
			(layer "F.Fab")
			(effects
				(font
					(size 0.7 0.7)
					(thickness 0.15)
				)
				(justify left bottom)
			)
		)
		(fp_text user "License: Apache-2.0"
			(at -1.75 8.4 0)
			(layer "F.Fab")
			(effects
				(font
					(size 0.7 0.7)
					(thickness 0.15)
				)
				(justify left bottom)
			)
		)
		(fp_text user "${REFERENCE}"
			(at -1.75 5.999 0)
			(layer "F.Fab")
			(effects
				(font
					(size 0.7 0.7)
					(thickness 0.15)
				)
				(justify left bottom)
			)
		)
		(pad "1" smd roundrect
			(at -1.425 -1 270)
			(size 0.25 0.7)
			(layers "F.Cu" "F.Mask" "F.Paste")
			(roundrect_rratio 0.25)
			(net 683 "/Supply/DC-DC AUX, MGT/MGTAVCC_SEN_+")
			(pinfunction "IN1+")
			(pintype "input")
		)
		(pad "2" smd roundrect
			(at -1.425 -0.5 270)
			(size 0.25 0.7)
			(layers "F.Cu" "F.Mask" "F.Paste")
			(roundrect_rratio 0.25)
			(net 691 "/Supply/DC-DC AUX, MGT/MGTAVCC_SEN_-")
			(pinfunction "IN1-")
			(pintype "input")
		)
		(pad "3" smd roundrect
			(at -1.425 0 270)
			(size 0.25 0.7)
			(layers "F.Cu" "F.Mask" "F.Paste")
			(roundrect_rratio 0.25)
			(net 682 "/Supply/DC-DC AUX, MGT/MGTAVTT_SEN_+")
			(pinfunction "IN2+")
			(pintype "input")
		)
		(pad "4" smd roundrect
			(at -1.425 0.498 270)
			(size 0.25 0.7)
			(layers "F.Cu" "F.Mask" "F.Paste")
			(roundrect_rratio 0.25)
			(net 690 "/Supply/DC-DC AUX, MGT/MGTAVTT_SEN_-")
			(pinfunction "IN2-")
			(pintype "input")
		)
		(pad "5" smd roundrect
			(at -1.425 0.998 270)
			(size 0.25 0.7)
			(layers "F.Cu" "F.Mask" "F.Paste")
			(roundrect_rratio 0.25)
			(net 1 "GND")
			(pinfunction "GND")
			(pintype "power_in")
		)
		(pad "6" smd roundrect
			(at 1.426 0.998 270)
			(size 0.25 0.7)
			(layers "F.Cu" "F.Mask" "F.Paste")
			(roundrect_rratio 0.25)
			(net 735 "Net-(U25-ADDRSEL)")
			(pinfunction "ADDRSEL")
			(pintype "bidirectional")
		)
		(pad "7" smd roundrect
			(at 1.426 0.498 270)
			(size 0.25 0.7)
			(layers "F.Cu" "F.Mask" "F.Paste")
			(roundrect_rratio 0.25)
			(net 731 "Net-(U25-~{ALERT})")
			(pinfunction "~{ALERT}")
			(pintype "bidirectional")
		)
		(pad "8" smd roundrect
			(at 1.426 0 270)
			(size 0.25 0.7)
			(layers "F.Cu" "F.Mask" "F.Paste")
			(roundrect_rratio 0.25)
			(net 533 "/I^{2}C + I3C/PWR.SDA")
			(pinfunction "SDA")
			(pintype "bidirectional")
		)
		(pad "9" smd roundrect
			(at 1.426 -0.5 270)
			(size 0.25 0.7)
			(layers "F.Cu" "F.Mask" "F.Paste")
			(roundrect_rratio 0.25)
			(net 749 "/I^{2}C + I3C/PWR.SCL")
			(pinfunction "SCL")
			(pintype "input")
		)
		(pad "10" smd roundrect
			(at 1.426 -1 270)
			(size 0.25 0.7)
			(layers "F.Cu" "F.Mask" "F.Paste")
			(roundrect_rratio 0.25)
			(net 38 "+3V3_AON")
			(pinfunction "VDD")
			(pintype "power_in")
		)
		(pad "11" smd roundrect
			(at 0 0 270)
			(size 2.38 1.65)
			(layers "F.Cu" "F.Mask" "F.Paste")
			(roundrect_rratio 0.05)
			(net 1 "GND")
			(pinfunction "EP")
			(pintype "passive")
		)
	)
	(footprint "antmicro-footprints:R_0402_1005Metric"
		(layer "F.Cu")
		(at 252.785 143.45 180)
		(descr "Resistor SMD 0402")
		(tags "resistor SMD 0402")
		(property "Reference" "R63"
			(at -3.065 -0.5 0)
			(layer "F.SilkS")
			(effects
				(font
					(size 0.7 0.7)
					(thickness 0.15)
				)
				(justify right bottom)
			)
		)
		(property "Value" "R_330R_0402"
			(at -1.011843 1.772047 0)
			(layer "F.Fab")
			(effects
				(font
					(size 0.7 0.7)
					(thickness 0.15)
				)
				(justify right bottom)
			)
		)
		(property "Datasheet" "https://www.bourns.com/docs/product-datasheets/cr.pdf"
			(at 0 0 180)
			(layer "F.Fab")
			(hide yes)
			(effects
				(font
					(size 1.27 1.27)
					(thickness 0.15)
				)
			)
		)
		(property "Manufacturer" "Bourns"
			(at 0 0 180)
			(unlocked yes)
			(layer "F.Fab")
			(hide yes)
			(effects
				(font
					(size 1 1)
					(thickness 0.15)
				)
			)
		)
		(property "MPN" "CR0402-FX-3300GLF"
			(at 0 0 180)
			(unlocked yes)
			(layer "F.Fab")
			(hide yes)
			(effects
				(font
					(size 1 1)
					(thickness 0.15)
				)
			)
		)
		(property "Val" "330R"
			(at 0 0 180)
			(unlocked yes)
			(layer "F.Fab")
			(hide yes)
			(effects
				(font
					(size 1 1)
					(thickness 0.15)
				)
			)
		)
		(property "License" "Apache-2.0"
			(at 0 0 180)
			(unlocked yes)
			(layer "F.Fab")
			(hide yes)
			(effects
				(font
					(size 1 1)
					(thickness 0.15)
				)
			)
		)
		(property "Author" "Antmicro"
			(at 0 0 180)
			(unlocked yes)
			(layer "F.Fab")
			(hide yes)
			(effects
				(font
					(size 1 1)
					(thickness 0.15)
				)
			)
		)
		(property "Tolerance" "1%"
			(at 0 0 180)
			(unlocked yes)
			(layer "F.Fab")
			(hide yes)
			(effects
				(font
					(size 1 1)
					(thickness 0.15)
				)
			)
		)
		(sheetname "/DDR5 RDIMM/")
		(sheetfile "ddr5-rdimm.kicad_sch")
		(attr smd)
		(fp_rect
			(start -0.925 -0.47)
			(end 0.925 0.47)
			(stroke
				(width 0.05)
				(type default)
			)
			(fill no)
			(layer "F.CrtYd")
		)
		(fp_rect
			(start -0.5 -0.25)
			(end 0.5 0.25)
			(stroke
				(width 0.15)
				(type solid)
			)
			(fill no)
			(layer "F.Fab")
		)
		(fp_text user "License: Apache-2.0"
			(at -0.95 5.169 180)
			(layer "F.Fab")
			(effects
				(font
					(size 0.7 0.7)
					(thickness 0.15)
				)
				(justify left bottom)
			)
		)
		(fp_text user "${REFERENCE}"
			(at -0.95 3.168 180)
			(layer "F.Fab")
			(effects
				(font
					(size 0.7 0.7)
					(thickness 0.15)
				)
				(justify left bottom)
			)
		)
		(fp_text user "Author: Antmicro"
			(at -0.95 4.169 180)
			(layer "F.Fab")
			(effects
				(font
					(size 0.7 0.7)
					(thickness 0.15)
				)
				(justify left bottom)
			)
		)
		(pad "1" smd roundrect
			(at -0.48 0 180)
			(size 0.59 0.64)
			(layers "F.Cu" "F.Mask" "F.Paste")
			(roundrect_rratio 0.25)
			(net 221 "Net-(D20-C_{R})")
			(pintype "passive")
		)
		(pad "2" smd roundrect
			(at 0.48 0 180)
			(size 0.59 0.64)
			(layers "F.Cu" "F.Mask" "F.Paste")
			(roundrect_rratio 0.25)
			(net 283 "Net-(Q11-D)")
			(pintype "passive")
		)
	)
	(footprint "antmicro-footprints:TP_SMD_1mm"
		(layer "F.Cu")
		(at 244.024499 179.299)
		(property "Reference" "TP18"
			(at 0 -0.731898 0)
			(layer "F.SilkS")
			(hide yes)
			(effects
				(font
					(size 0.7 0.7)
					(thickness 0.15)
				)
				(justify left bottom)
			)
		)
		(property "Value" "TP_1mm_SMD"
			(at 0 1.4 0)
			(layer "F.Fab")
			(effects
				(font
					(size 0.7 0.7)
					(thickness 0.15)
				)
				(justify left bottom)
			)
		)
		(property "MPN" ""
			(at 0 0 0)
			(unlocked yes)
			(layer "F.Fab")
			(hide yes)
			(effects
				(font
					(size 1 1)
					(thickness 0.15)
				)
			)
		)
		(property "Manufacturer" ""
			(at 0 0 0)
			(unlocked yes)
			(layer "F.Fab")
			(hide yes)
			(effects
				(font
					(size 1 1)
					(thickness 0.15)
				)
			)
		)
		(property "Author" "Antmicro"
			(at 0 0 0)
			(unlocked yes)
			(layer "F.Fab")
			(hide yes)
			(effects
				(font
					(size 1 1)
					(thickness 0.15)
				)
			)
		)
		(property "License" "Apache-2.0"
			(at 0 0 0)
			(unlocked yes)
			(layer "F.Fab")
			(hide yes)
			(effects
				(font
					(size 1 1)
					(thickness 0.15)
				)
			)
		)
		(sheetname "/Supply/DC-DC AUX, MGT/")
		(sheetfile "dc-dc-aux-mgt.kicad_sch")
		(attr exclude_from_pos_files)
		(fp_circle
			(center 0 0)
			(end 0.6 0)
			(stroke
				(width 0.05)
				(type default)
			)
			(fill no)
			(layer "F.CrtYd")
		)
		(fp_text user "Author: Antmicro"
			(at -0.5 4 0)
			(layer "F.Fab")
			(effects
				(font
					(size 0.7 0.7)
					(thickness 0.15)
				)
				(justify left bottom)
			)
		)
		(fp_text user "License: Apache-2.0"
			(at -0.5 5.2 0)
			(layer "F.Fab")
			(effects
				(font
					(size 0.7 0.7)
					(thickness 0.15)
				)
				(justify left bottom)
			)
		)
		(fp_text user "${REFERENCE}"
			(at -0.5 2.8 0)
			(layer "F.Fab")
			(effects
				(font
					(size 0.7 0.7)
					(thickness 0.15)
				)
				(justify left bottom)
			)
		)
		(pad "1" smd circle
			(at 0 0)
			(size 1 1)
			(layers "F.Cu" "F.Mask")
			(net 573 "+1V8_MGTVCCAUX")
			(pinfunction "1")
			(pintype "passive")
		)
	)
	(footprint "antmicro-footprints:C_0805_2012Metric"
		(layer "F.Cu")
		(at 230.010001 187.669999)
		(descr "Capacitor SMD 0805")
		(tags "capacitor SMD 0805")
		(property "Reference" "C314"
			(at 1.915 0.45 0)
			(layer "F.SilkS")
			(effects
				(font
					(size 0.7 0.7)
					(thickness 0.15)
				)
				(justify left bottom)
			)
		)
		(property "Value" "C_22u_25V_0805"
			(at -2.055717 1.963152 0)
			(layer "F.Fab")
			(effects
				(font
					(size 0.7 0.7)
					(thickness 0.15)
				)
				(justify left bottom)
			)
		)
		(property "Datasheet" "https://product.samsungsem.com/mlcc/CL21A226MAYNNN.do"
			(at 0 0 0)
			(layer "F.Fab")
			(hide yes)
			(effects
				(font
					(size 1.27 1.27)
					(thickness 0.15)
				)
			)
		)
		(property "MPN" "CL21A226MAYNNNE"
			(at 0 0 0)
			(unlocked yes)
			(layer "F.Fab")
			(hide yes)
			(effects
				(font
					(size 1 1)
					(thickness 0.15)
				)
			)
		)
		(property "Manufacturer" "Samsung Electro-Mechanics"
			(at 0 0 0)
			(unlocked yes)
			(layer "F.Fab")
			(hide yes)
			(effects
				(font
					(size 1 1)
					(thickness 0.15)
				)
			)
		)
		(property "License" "Apache-2.0"
			(at 0 0 0)
			(unlocked yes)
			(layer "F.Fab")
			(hide yes)
			(effects
				(font
					(size 1 1)
					(thickness 0.15)
				)
			)
		)
		(property "Author" "Antmicro"
			(at 0 0 0)
			(unlocked yes)
			(layer "F.Fab")
			(hide yes)
			(effects
				(font
					(size 1 1)
					(thickness 0.15)
				)
			)
		)
		(property "Val" "22u"
			(at 0 0 0)
			(unlocked yes)
			(layer "F.Fab")
			(hide yes)
			(effects
				(font
					(size 1 1)
					(thickness 0.15)
				)
			)
		)
		(property "Voltage" "25V"
			(at 0 0 0)
			(unlocked yes)
			(layer "F.Fab")
			(hide yes)
			(effects
				(font
					(size 1 1)
					(thickness 0.15)
				)
			)
		)
		(property "Dielectric" "X5R"
			(at 0 0 0)
			(unlocked yes)
			(layer "F.Fab")
			(hide yes)
			(effects
				(font
					(size 1 1)
					(thickness 0.15)
				)
			)
		)
		(property "Public" "False"
			(at 0 0 0)
			(unlocked yes)
			(layer "F.Fab")
			(hide yes)
			(effects
				(font
					(size 1 1)
					(thickness 0.15)
				)
			)
		)
		(sheetname "/Supply/DC-DC VCCINT/")
		(sheetfile "dc-dc-vccint.kicad_sch")
		(attr smd exclude_from_bom)
		(fp_line
			(start -0.3 -0.7)
			(end 0.3 -0.7)
			(stroke
				(width 0.15)
				(type solid)
			)
			(layer "F.SilkS")
		)
		(fp_line
			(start -0.3 0.7)
			(end 0.3 0.7)
			(stroke
				(width 0.15)
				(type solid)
			)
			(layer "F.SilkS")
		)
		(fp_rect
			(start 1.95 -0.9)
			(end -1.95 0.9)
			(stroke
				(width 0.05)
				(type default)
			)
			(fill no)
			(layer "F.CrtYd")
		)
		(fp_rect
			(start -0.95 -0.675)
			(end 0.95 0.675)
			(stroke
				(width 0.15)
				(type solid)
			)
			(fill no)
			(layer "F.Fab")
		)
		(fp_text user "${REFERENCE}"
			(at -1.9 3.947 0)
			(layer "F.Fab")
			(effects
				(font
					(size 0.7 0.7)
					(thickness 0.15)
				)
				(justify left bottom)
			)
		)
		(fp_text user "License: Apache-2.0"
			(at -1.9 4.947 0)
			(layer "F.Fab")
			(effects
				(font
					(size 0.7 0.7)
					(thickness 0.15)
				)
				(justify left bottom)
			)
		)
		(fp_text user "Author: Antmicro"
			(at -1.9 5.947 0)
			(layer "F.Fab")
			(effects
				(font
					(size 0.7 0.7)
					(thickness 0.15)
				)
				(justify left bottom)
			)
		)
		(pad "1" smd roundrect
			(at -1.1 0)
			(size 1.2 1.3)
			(layers "F.Cu" "F.Mask" "F.Paste")
			(roundrect_rratio 0.25)
			(net 1 "GND")
			(pintype "passive")
		)
		(pad "2" smd roundrect
			(at 1.1 0)
			(size 1.2 1.3)
			(layers "F.Cu" "F.Mask" "F.Paste")
			(roundrect_rratio 0.25)
			(net 35 "VDC")
			(pintype "passive")
		)
	)
	(footprint "antmicro-footprints:C_0402_1005Metric"
		(layer "F.Cu")
		(at 241.774499 168.71 90)
		(descr "Capacitor SMD 0402")
		(tags "capacitor SMD 0402")
		(property "Reference" "C214"
			(at -3.69 0.775501 90)
			(layer "F.SilkS")
			(effects
				(font
					(size 0.7 0.7)
					(thickness 0.15)
				)
				(justify left bottom)
			)
		)
		(property "Value" "C_100n_0402"
			(at -1.022927 2.155213 90)
			(layer "F.Fab")
			(effects
				(font
					(size 0.7 0.7)
					(thickness 0.15)
				)
				(justify left bottom)
			)
		)
		(property "Datasheet" "https://www.murata.com/products/productdetail?partno=GRM155R61H104KE14%23"
			(at 0 0 90)
			(layer "F.Fab")
			(hide yes)
			(effects
				(font
					(size 1.27 1.27)
					(thickness 0.15)
				)
			)
		)
		(property "Manufacturer" "Murata"
			(at 0 0 90)
			(unlocked yes)
			(layer "F.Fab")
			(hide yes)
			(effects
				(font
					(size 1 1)
					(thickness 0.15)
				)
			)
		)
		(property "MPN" "GRM155R61H104KE14D"
			(at 0 0 90)
			(unlocked yes)
			(layer "F.Fab")
			(hide yes)
			(effects
				(font
					(size 1 1)
					(thickness 0.15)
				)
			)
		)
		(property "Val" "100n"
			(at 0 0 90)
			(unlocked yes)
			(layer "F.Fab")
			(hide yes)
			(effects
				(font
					(size 1 1)
					(thickness 0.15)
				)
			)
		)
		(property "License" "Apache-2.0"
			(at 0 0 90)
			(unlocked yes)
			(layer "F.Fab")
			(hide yes)
			(effects
				(font
					(size 1 1)
					(thickness 0.15)
				)
			)
		)
		(property "Author" "Antmicro"
			(at 0 0 90)
			(unlocked yes)
			(layer "F.Fab")
			(hide yes)
			(effects
				(font
					(size 1 1)
					(thickness 0.15)
				)
			)
		)
		(property "Voltage" "50V"
			(at 0 0 90)
			(unlocked yes)
			(layer "F.Fab")
			(hide yes)
			(effects
				(font
					(size 1 1)
					(thickness 0.15)
				)
			)
		)
		(property "Dielectric" "X5R"
			(at 0 0 90)
			(unlocked yes)
			(layer "F.Fab")
			(hide yes)
			(effects
				(font
					(size 1 1)
					(thickness 0.15)
				)
			)
		)
		(sheetname "/Supply/DC-DC AUX, MGT/")
		(sheetfile "dc-dc-aux-mgt.kicad_sch")
		(attr smd)
		(fp_rect
			(start -0.925 -0.47)
			(end 0.925 0.47)
			(stroke
				(width 0.05)
				(type default)
			)
			(fill no)
			(layer "F.CrtYd")
		)
		(fp_line
			(start 0.504 -0.25)
			(end 0.504 0.248)
			(stroke
				(width 0.15)
				(type solid)
			)
			(layer "F.Fab")
		)
		(fp_line
			(start -0.494 -0.25)
			(end 0.504 -0.25)
			(stroke
				(width 0.15)
				(type solid)
			)
			(layer "F.Fab")
		)
		(fp_line
			(start 0.504 0.248)
			(end -0.494 0.248)
			(stroke
				(width 0.15)
				(type solid)
			)
			(layer "F.Fab")
		)
		(fp_line
			(start -0.494 0.248)
			(end -0.494 -0.25)
			(stroke
				(width 0.15)
				(type solid)
			)
			(layer "F.Fab")
		)
		(fp_text user "License: Apache-2.0"
			(at -0.939 5.799 90)
			(layer "F.Fab")
			(effects
				(font
					(size 0.7 0.7)
					(thickness 0.15)
				)
				(justify left bottom)
			)
		)
		(fp_text user "${REFERENCE}"
			(at -0.939 4.599 90)
			(layer "F.Fab")
			(effects
				(font
					(size 0.7 0.7)
					(thickness 0.15)
				)
				(justify left bottom)
			)
		)
		(fp_text user "Author: Antmicro"
			(at -0.939 3.399 90)
			(layer "F.Fab")
			(effects
				(font
					(size 0.7 0.7)
					(thickness 0.15)
				)
				(justify left bottom)
			)
		)
		(pad "1" smd roundrect
			(at -0.48 0 90)
			(size 0.59 0.64)
			(layers "F.Cu" "F.Mask" "F.Paste")
			(roundrect_rratio 0.25)
			(net 38 "+3V3_AON")
			(pintype "passive")
		)
		(pad "2" smd roundrect
			(at 0.48 0 90)
			(size 0.59 0.64)
			(layers "F.Cu" "F.Mask" "F.Paste")
			(roundrect_rratio 0.25)
			(net 1 "GND")
			(pintype "passive")
		)
	)
	(footprint "antmicro-footprints:LED_0402_1005Metric_G"
		(layer "F.Cu")
		(at 107.19 114.725 180)
		(property "Reference" "D3"
			(at 0 -0.6 180)
			(unlocked yes)
			(layer "F.SilkS")
			(hide yes)
			(effects
				(font
					(size 0.7 0.7)
					(thickness 0.15)
				)
				(justify left bottom)
			)
		)
		(property "Value" "LED_G_0402_VLMTG1500-GS08"
			(at 0 1.5 180)
			(unlocked yes)
			(layer "F.Fab")
			(effects
				(font
					(size 0.7 0.7)
					(thickness 0.15)
				)
				(justify left bottom)
			)
		)
		(property "Datasheet" "https://www.vishay.com/docs/82554/vlmo1500.pdf"
			(at 0 0 180)
			(layer "F.Fab")
			(hide yes)
			(effects
				(font
					(size 1.27 1.27)
					(thickness 0.15)
				)
			)
		)
		(property "MPN" "VLMTG1500-GS08"
			(at 0 0 180)
			(unlocked yes)
			(layer "F.Fab")
			(hide yes)
			(effects
				(font
					(size 1 1)
					(thickness 0.15)
				)
			)
		)
		(property "Manufacturer" "Vishay"
			(at 0 0 180)
			(unlocked yes)
			(layer "F.Fab")
			(hide yes)
			(effects
				(font
					(size 1 1)
					(thickness 0.15)
				)
			)
		)
		(property "Color" "Green"
			(at 0 0 180)
			(unlocked yes)
			(layer "F.Fab")
			(hide yes)
			(effects
				(font
					(size 1 1)
					(thickness 0.15)
				)
			)
		)
		(property "Author" "Antmicro"
			(at 0 0 180)
			(unlocked yes)
			(layer "F.Fab")
			(hide yes)
			(effects
				(font
					(size 1 1)
					(thickness 0.15)
				)
			)
		)
		(property "License" "Apache-2.0"
			(at 0 0 180)
			(unlocked yes)
			(layer "F.Fab")
			(hide yes)
			(effects
				(font
					(size 1 1)
					(thickness 0.15)
				)
			)
		)
		(sheetname "/FPGA Config/")
		(sheetfile "fpga-config.kicad_sch")
		(attr smd)
		(fp_line
			(start -0.175 0.4)
			(end 0.175 0.4)
			(stroke
				(width 0.15)
				(type solid)
			)
			(layer "F.SilkS")
		)
		(fp_line
			(start -0.175 -0.4)
			(end 0.175 -0.4)
			(stroke
				(width 0.15)
				(type solid)
			)
			(layer "F.SilkS")
		)
		(fp_line
			(start -0.9 -0.4)
			(end -0.9 0.4)
			(stroke
				(width 0.15)
				(type solid)
			)
			(layer "F.SilkS")
		)
		(fp_rect
			(start -0.925 -0.47)
			(end 0.925 0.47)
			(stroke
				(width 0.05)
				(type default)
			)
			(fill no)
			(layer "F.CrtYd")
		)
		(fp_line
			(start 0.501 0.26)
			(end 0.501 -0.248)
			(stroke
				(width 0.15)
				(type solid)
			)
			(layer "F.Fab")
		)
		(fp_line
			(start 0.501 0.26)
			(end 0.501 -0.248)
			(stroke
				(width 0.15)
				(type solid)
			)
			(layer "F.Fab")
		)
		(fp_line
			(start 0.501 -0.248)
			(end 0.172 -0.248)
			(stroke
				(width 0.15)
				(type solid)
			)
			(layer "F.Fab")
		)
		(fp_line
			(start 0.501 -0.248)
			(end -0.489 -0.248)
			(stroke
				(width 0.15)
				(type solid)
			)
			(layer "F.Fab")
		)
		(fp_line
			(start 0.228 0.202)
			(end 0.228 0)
			(stroke
				(width 0.15)
				(type solid)
			)
			(layer "F.Fab")
		)
		(fp_line
			(start 0.228 0)
			(end 0.228 -0.202)
			(stroke
				(width 0.15)
				(type solid)
			)
			(layer "F.Fab")
		)
		(fp_line
			(start 0.228 -0.202)
			(end -0.074 0)
			(stroke
				(width 0.15)
				(type solid)
			)
			(layer "F.Fab")
		)
		(fp_line
			(start 0.172 0.26)
			(end 0.501 0.26)
			(stroke
				(width 0.15)
				(type solid)
			)
			(layer "F.Fab")
		)
		(fp_line
			(start 0.172 -0.248)
			(end 0.172 0.26)
			(stroke
				(width 0.15)
				(type solid)
			)
			(layer "F.Fab")
		)
		(fp_line
			(start -0.074 0)
			(end 0.228 0.202)
			(stroke
				(width 0.15)
				(type solid)
			)
			(layer "F.Fab")
		)
		(fp_line
			(start -0.158 0.26)
			(end -0.158 -0.248)
			(stroke
				(width 0.15)
				(type solid)
			)
			(layer "F.Fab")
		)
		(fp_line
			(start -0.158 -0.248)
			(end -0.489 -0.248)
			(stroke
				(width 0.15)
				(type solid)
			)
			(layer "F.Fab")
		)
		(fp_line
			(start -0.173 0.202)
			(end -0.173 0.102)
			(stroke
				(width 0.15)
				(type solid)
			)
			(layer "F.Fab")
		)
		(fp_line
			(start -0.173 -0.202)
			(end -0.173 0.102)
			(stroke
				(width 0.15)
				(type solid)
			)
			(layer "F.Fab")
		)
		(fp_line
			(start -0.489 0.26)
			(end 0.501 0.26)
			(stroke
				(width 0.15)
				(type solid)
			)
			(layer "F.Fab")
		)
		(fp_line
			(start -0.489 0.26)
			(end -0.158 0.26)
			(stroke
				(width 0.15)
				(type solid)
			)
			(layer "F.Fab")
		)
		(fp_line
			(start -0.489 -0.248)
			(end -0.489 0.26)
			(stroke
				(width 0.15)
				(type solid)
			)
			(layer "F.Fab")
		)
		(fp_line
			(start -0.489 -0.248)
			(end -0.489 0.26)
			(stroke
				(width 0.15)
				(type solid)
			)
			(layer "F.Fab")
		)
		(fp_text user "License: Apache-2.0"
			(at 0 5.35 180)
			(layer "F.Fab")
			(effects
				(font
					(size 0.7 0.7)
					(thickness 0.15)
				)
				(justify left bottom)
			)
		)
		(fp_text user "${REFERENCE}"
			(at 0 2.95 180)
			(unlocked yes)
			(layer "F.Fab")
			(effects
				(font
					(size 0.7 0.7)
					(thickness 0.15)
				)
				(justify left bottom)
			)
		)
		(fp_text user "Author: Antmicro"
			(at 0 4.15 180)
			(layer "F.Fab")
			(effects
				(font
					(size 0.7 0.7)
					(thickness 0.15)
				)
				(justify left bottom)
			)
		)
		(pad "1" smd roundrect
			(at -0.48 0 180)
			(size 0.59 0.64)
			(layers "F.Cu" "F.Mask" "F.Paste")
			(roundrect_rratio 0.25)
			(net 785 "Net-(D3-C)")
			(pinfunction "C")
			(pintype "passive")
		)
		(pad "2" smd roundrect
			(at 0.48 0 180)
			(size 0.59 0.64)
			(layers "F.Cu" "F.Mask" "F.Paste")
			(roundrect_rratio 0.25)
			(net 151 "+3V3")
			(pinfunction "A")
			(pintype "passive")
		)
	)
	(footprint "antmicro-footprints:MP_Pad6mm_Drill3mm"
		(layer "F.Cu")
		(at 107.5 108)
		(property "Reference" "MP1"
			(at 0 -3.2 0)
			(layer "F.SilkS")
			(hide yes)
			(effects
				(font
					(size 0.7 0.7)
					(thickness 0.15)
				)
				(justify left bottom)
			)
		)
		(property "Value" "MP_Pad6mm_Drill3mm"
			(at 0 3.9 0)
			(layer "F.Fab")
			(effects
				(font
					(size 0.7 0.7)
					(thickness 0.15)
				)
				(justify left bottom)
			)
		)
		(attr board_only exclude_from_pos_files exclude_from_bom)
		(fp_circle
			(center 0 0)
			(end 3.25 0)
			(stroke
				(width 0.05)
				(type default)
			)
			(fill no)
			(layer "F.CrtYd")
		)
		(fp_text user "${REFERENCE}"
			(at -0.178 6.025 0)
			(layer "F.Fab")
			(effects
				(font
					(size 0.7 0.7)
					(thickness 0.15)
				)
				(justify left bottom)
			)
		)
		(fp_text user "License: Apache-2.0"
			(at -0.178 8.425 0)
			(layer "F.Fab")
			(effects
				(font
					(size 0.7 0.7)
					(thickness 0.15)
				)
				(justify left bottom)
			)
		)
		(fp_text user "Author: Antmicro"
			(at -0.178 7.225 0)
			(layer "F.Fab")
			(effects
				(font
					(size 0.7 0.7)
					(thickness 0.15)
				)
				(justify left bottom)
			)
		)
		(pad "1" thru_hole circle
			(at 0 0)
			(size 6 6)
			(drill 3)
			(layers "*.Cu" "*.Mask")
			(remove_unused_layers no)
			(net 1 "GND")
		)
	)
	(footprint "antmicro-footprints:NetTie-2_SMD_Pad0.127mm"
		(layer "F.Cu")
		(at 256.063 179.78 180)
		(descr "Net tie, 2 pin, 0.127mm  SMD pads")
		(tags "net tie")
		(property "Reference" "NT12"
			(at -0.128 -1.345 0)
			(layer "F.SilkS")
			(hide yes)
			(effects
				(font
					(size 0.7 0.7)
					(thickness 0.15)
				)
				(justify right bottom)
			)
		)
		(property "Value" "Net-Tie_P0.127mm"
			(at 0 1.199 0)
			(layer "F.Fab")
			(effects
				(font
					(size 0.7 0.7)
					(thickness 0.15)
				)
				(justify right bottom)
			)
		)
		(property "MPN" ""
			(at 0 0 180)
			(unlocked yes)
			(layer "F.Fab")
			(hide yes)
			(effects
				(font
					(size 1 1)
					(thickness 0.15)
				)
			)
		)
		(property "Manufacturer" ""
			(at 0 0 180)
			(unlocked yes)
			(layer "F.Fab")
			(hide yes)
			(effects
				(font
					(size 1 1)
					(thickness 0.15)
				)
			)
		)
		(property "Author" "Antmicro"
			(at 0 0 180)
			(unlocked yes)
			(layer "F.Fab")
			(hide yes)
			(effects
				(font
					(size 1 1)
					(thickness 0.15)
				)
			)
		)
		(property "License" "Apache-2.0"
			(at 0 0 180)
			(unlocked yes)
			(layer "F.Fab")
			(hide yes)
			(effects
				(font
					(size 1 1)
					(thickness 0.15)
				)
			)
		)
		(property ki_fp_filters "Net*Tie*")
		(sheetname "/Supply/DC-DC AUX, MGT/")
		(sheetfile "dc-dc-aux-mgt.kicad_sch")
		(attr through_hole exclude_from_pos_files exclude_from_bom)
		(net_tie_pad_groups "1, 2")
		(fp_poly
			(pts
				(xy -0.0635 -0.0635) (xy 0.0625 -0.0635) (xy 0.0625 0.0635) (xy -0.0635 0.0635)
			)
			(stroke
				(width 0)
				(type solid)
			)
			(fill yes)
			(layer "F.Cu")
		)
		(fp_poly
			(pts
				(xy 0.2 -0.16) (xy 0.29 -0.07) (xy 0.29 0.07) (xy 0.2 0.16) (xy -0.2 0.16) (xy -0.29 0.07) (xy -0.29 -0.06)
				(xy -0.19 -0.16)
			)
			(stroke
				(width 0.05)
				(type solid)
			)
			(fill no)
			(layer "F.CrtYd")
		)
		(fp_text user "License: Apache-2.0"
			(at -0.128 5.6 180)
			(layer "F.Fab")
			(effects
				(font
					(size 0.7 0.7)
					(thickness 0.15)
				)
				(justify left bottom)
			)
		)
		(fp_text user "${REFERENCE}"
			(at -0.128 3.2 180)
			(layer "F.Fab")
			(effects
				(font
					(size 0.7 0.7)
					(thickness 0.15)
				)
				(justify left bottom)
			)
		)
		(fp_text user "Author: Antmicro"
			(at -0.128 4.4 180)
			(layer "F.Fab")
			(effects
				(font
					(size 0.7 0.7)
					(thickness 0.15)
				)
				(justify left bottom)
			)
		)
		(pad "1" smd roundrect
			(at -0.127 0)
			(size 0.127 0.127)
			(layers "F.Cu")
			(roundrect_rratio 0.5)
			(chamfer_ratio 0)
			(chamfer top_left bottom_left)
			(net 692 "/Supply/DC-DC AUX, MGT/MGTAVCCAUX_SEN_-")
			(pinfunction "1")
			(pintype "passive")
		)
		(pad "2" smd roundrect
			(at 0.126 0 180)
			(size 0.127 0.127)
			(layers "F.Cu")
			(roundrect_rratio 0.5)
			(chamfer_ratio 0)
			(chamfer top_left bottom_left)
			(net 573 "+1V8_MGTVCCAUX")
			(pinfunction "2")
			(pintype "passive")
		)
	)
	(footprint "antmicro-footprints:L_0402_1005Metric"
		(layer "F.Cu")
		(at 121.025 153.61 180)
		(descr "Inductor SMD 0402")
		(tags "Inductor SMD 0402")
		(property "Reference" "L8"
			(at -5.425 -0.415 0)
			(layer "F.SilkS")
			(effects
				(font
					(size 0.7 0.7)
					(thickness 0.15)
				)
				(justify right bottom)
			)
		)
		(property "Value" "L_20n_0.35A_0402"
			(at 0 1.4 0)
			(layer "F.Fab")
			(effects
				(font
					(size 0.7 0.7)
					(thickness 0.15)
				)
				(justify right bottom)
			)
		)
		(property "Datasheet" "https://product.tdk.com/system/files/dam/doc/product/inductor/inductor/smd/catalog/inductor_automotive_high-frequency_mlg1005s_en.pdf?ref_disty=mouser"
			(at 0 0 180)
			(layer "F.Fab")
			(hide yes)
			(effects
				(font
					(size 1.27 1.27)
					(thickness 0.15)
				)
			)
		)
		(property "Val" "20n/0.35A"
			(at 0 0 180)
			(unlocked yes)
			(layer "F.Fab")
			(hide yes)
			(effects
				(font
					(size 1 1)
					(thickness 0.15)
				)
			)
		)
		(property "Manufacturer" "TDK"
			(at 0 0 180)
			(unlocked yes)
			(layer "F.Fab")
			(hide yes)
			(effects
				(font
					(size 1 1)
					(thickness 0.15)
				)
			)
		)
		(property "MPN" "MLG1005S20NJTD25"
			(at 0 0 180)
			(unlocked yes)
			(layer "F.Fab")
			(hide yes)
			(effects
				(font
					(size 1 1)
					(thickness 0.15)
				)
			)
		)
		(property "ISat" ""
			(at 0 0 180)
			(unlocked yes)
			(layer "F.Fab")
			(hide yes)
			(effects
				(font
					(size 1 1)
					(thickness 0.15)
				)
			)
		)
		(property "IMax" "0.35 A"
			(at 0 0 180)
			(unlocked yes)
			(layer "F.Fab")
			(hide yes)
			(effects
				(font
					(size 1 1)
					(thickness 0.15)
				)
			)
		)
		(property "Size" "1.0x0.5"
			(at 0 0 180)
			(unlocked yes)
			(layer "F.Fab")
			(hide yes)
			(effects
				(font
					(size 1 1)
					(thickness 0.15)
				)
			)
		)
		(property "Author" "Antmicro"
			(at 0 0 180)
			(unlocked yes)
			(layer "F.Fab")
			(hide yes)
			(effects
				(font
					(size 1 1)
					(thickness 0.15)
				)
			)
		)
		(property "License" "Apache-2.0"
			(at 0 0 180)
			(unlocked yes)
			(layer "F.Fab")
			(hide yes)
			(effects
				(font
					(size 1 1)
					(thickness 0.15)
				)
			)
		)
		(sheetname "/HDMI + SD Card/")
		(sheetfile "hdmi-sd-card.kicad_sch")
		(attr smd)
		(fp_rect
			(start -0.925 -0.47)
			(end 0.925 0.47)
			(stroke
				(width 0.05)
				(type default)
			)
			(fill no)
			(layer "F.CrtYd")
		)
		(fp_rect
			(start -0.499 -0.249)
			(end 0.499 0.249)
			(stroke
				(width 0.15)
				(type solid)
			)
			(fill no)
			(layer "F.Fab")
		)
		(fp_text user "Author: Antmicro"
			(at -0.932 4.17 180)
			(layer "F.Fab")
			(effects
				(font
					(size 0.7 0.7)
					(thickness 0.15)
				)
				(justify left bottom)
			)
		)
		(fp_text user "${REFERENCE}"
			(at -0.932 3.168 180)
			(layer "F.Fab")
			(effects
				(font
					(size 0.7 0.7)
					(thickness 0.15)
				)
				(justify left bottom)
			)
		)
		(fp_text user "License: Apache-2.0"
			(at -0.932 5.17 180)
			(layer "F.Fab")
			(effects
				(font
					(size 0.7 0.7)
					(thickness 0.15)
				)
				(justify left bottom)
			)
		)
		(pad "1" smd roundrect
			(at -0.48 0 180)
			(size 0.59 0.64)
			(layers "F.Cu" "F.Mask" "F.Paste")
			(roundrect_rratio 0.25)
			(net 269 "/FPGA MGT Interface/HDMI_IN.CLK_P")
			(pintype "passive")
		)
		(pad "2" smd roundrect
			(at 0.48 0 180)
			(size 0.59 0.64)
			(layers "F.Cu" "F.Mask" "F.Paste")
			(roundrect_rratio 0.25)
			(net 678 "Net-(L8-Pad2)")
			(pintype "passive")
		)
	)
	(footprint "antmicro-footprints:LED_0402_1005Metric_G"
		(layer "F.Cu")
		(at 116.48 139.083 -90)
		(property "Reference" "D17"
			(at -1.033 -0.37 90)
			(unlocked yes)
			(layer "F.SilkS")
			(effects
				(font
					(size 0.7 0.7)
					(thickness 0.15)
				)
				(justify left bottom)
			)
		)
		(property "Value" "LED_G_0402_VLMTG1500-GS08"
			(at 0 1.5 270)
			(unlocked yes)
			(layer "F.Fab")
			(effects
				(font
					(size 0.7 0.7)
					(thickness 0.15)
				)
				(justify left bottom)
			)
		)
		(property "Datasheet" "https://www.vishay.com/docs/82554/vlmo1500.pdf"
			(at 0 0 90)
			(layer "F.Fab")
			(hide yes)
			(effects
				(font
					(size 1.27 1.27)
					(thickness 0.15)
				)
			)
		)
		(property "MPN" "VLMTG1500-GS08"
			(at 0 0 270)
			(unlocked yes)
			(layer "F.Fab")
			(hide yes)
			(effects
				(font
					(size 1 1)
					(thickness 0.15)
				)
			)
		)
		(property "Manufacturer" "Vishay"
			(at 0 0 270)
			(unlocked yes)
			(layer "F.Fab")
			(hide yes)
			(effects
				(font
					(size 1 1)
					(thickness 0.15)
				)
			)
		)
		(property "Color" "Green"
			(at 0 0 270)
			(unlocked yes)
			(layer "F.Fab")
			(hide yes)
			(effects
				(font
					(size 1 1)
					(thickness 0.15)
				)
			)
		)
		(property "Author" "Antmicro"
			(at 0 0 270)
			(unlocked yes)
			(layer "F.Fab")
			(hide yes)
			(effects
				(font
					(size 1 1)
					(thickness 0.15)
				)
			)
		)
		(property "License" "Apache-2.0"
			(at 0 0 270)
			(unlocked yes)
			(layer "F.Fab")
			(hide yes)
			(effects
				(font
					(size 1 1)
					(thickness 0.15)
				)
			)
		)
		(sheetname "/Debug FTDI + VNA/")
		(sheetfile "debug-ftdi.kicad_sch")
		(attr smd)
		(fp_line
			(start -0.175 0.4)
			(end 0.175 0.4)
			(stroke
				(width 0.15)
				(type solid)
			)
			(layer "F.SilkS")
		)
		(fp_line
			(start -0.9 -0.4)
			(end -0.9 0.4)
			(stroke
				(width 0.15)
				(type solid)
			)
			(layer "F.SilkS")
		)
		(fp_line
			(start -0.175 -0.4)
			(end 0.175 -0.4)
			(stroke
				(width 0.15)
				(type solid)
			)
			(layer "F.SilkS")
		)
		(fp_rect
			(start -0.925 -0.47)
			(end 0.925 0.47)
			(stroke
				(width 0.05)
				(type default)
			)
			(fill no)
			(layer "F.CrtYd")
		)
		(fp_line
			(start -0.489 0.26)
			(end -0.158 0.26)
			(stroke
				(width 0.15)
				(type solid)
			)
			(layer "F.Fab")
		)
		(fp_line
			(start -0.489 0.26)
			(end 0.501 0.26)
			(stroke
				(width 0.15)
				(type solid)
			)
			(layer "F.Fab")
		)
		(fp_line
			(start -0.158 0.26)
			(end -0.158 -0.248)
			(stroke
				(width 0.15)
				(type solid)
			)
			(layer "F.Fab")
		)
		(fp_line
			(start 0.172 0.26)
			(end 0.501 0.26)
			(stroke
				(width 0.15)
				(type solid)
			)
			(layer "F.Fab")
		)
		(fp_line
			(start 0.501 0.26)
			(end 0.501 -0.248)
			(stroke
				(width 0.15)
				(type solid)
			)
			(layer "F.Fab")
		)
		(fp_line
			(start 0.501 0.26)
			(end 0.501 -0.248)
			(stroke
				(width 0.15)
				(type solid)
			)
			(layer "F.Fab")
		)
		(fp_line
			(start -0.173 0.202)
			(end -0.173 0.102)
			(stroke
				(width 0.15)
				(type solid)
			)
			(layer "F.Fab")
		)
		(fp_line
			(start 0.228 0.202)
			(end 0.228 0)
			(stroke
				(width 0.15)
				(type solid)
			)
			(layer "F.Fab")
		)
		(fp_line
			(start -0.074 0)
			(end 0.228 0.202)
			(stroke
				(width 0.15)
				(type solid)
			)
			(layer "F.Fab")
		)
		(fp_line
			(start 0.228 0)
			(end 0.228 -0.202)
			(stroke
				(width 0.15)
				(type solid)
			)
			(layer "F.Fab")
		)
		(fp_line
			(start -0.173 -0.202)
			(end -0.173 0.102)
			(stroke
				(width 0.15)
				(type solid)
			)
			(layer "F.Fab")
		)
		(fp_line
			(start 0.228 -0.202)
			(end -0.074 0)
			(stroke
				(width 0.15)
				(type solid)
			)
			(layer "F.Fab")
		)
		(fp_line
			(start -0.489 -0.248)
			(end -0.489 0.26)
			(stroke
				(width 0.15)
				(type solid)
			)
			(layer "F.Fab")
		)
		(fp_line
			(start -0.489 -0.248)
			(end -0.489 0.26)
			(stroke
				(width 0.15)
				(type solid)
			)
			(layer "F.Fab")
		)
		(fp_line
			(start -0.158 -0.248)
			(end -0.489 -0.248)
			(stroke
				(width 0.15)
				(type solid)
			)
			(layer "F.Fab")
		)
		(fp_line
			(start 0.172 -0.248)
			(end 0.172 0.26)
			(stroke
				(width 0.15)
				(type solid)
			)
			(layer "F.Fab")
		)
		(fp_line
			(start 0.501 -0.248)
			(end -0.489 -0.248)
			(stroke
				(width 0.15)
				(type solid)
			)
			(layer "F.Fab")
		)
		(fp_line
			(start 0.501 -0.248)
			(end 0.172 -0.248)
			(stroke
				(width 0.15)
				(type solid)
			)
			(layer "F.Fab")
		)
		(fp_text user "Author: Antmicro"
			(at 0 4.15 270)
			(layer "F.Fab")
			(effects
				(font
					(size 0.7 0.7)
					(thickness 0.15)
				)
				(justify left bottom)
			)
		)
		(fp_text user "${REFERENCE}"
			(at 0 2.95 270)
			(unlocked yes)
			(layer "F.Fab")
			(effects
				(font
					(size 0.7 0.7)
					(thickness 0.15)
				)
				(justify left bottom)
			)
		)
		(fp_text user "License: Apache-2.0"
			(at 0 5.35 270)
			(layer "F.Fab")
			(effects
				(font
					(size 0.7 0.7)
					(thickness 0.15)
				)
				(justify left bottom)
			)
		)
		(pad "1" smd roundrect
			(at -0.48 0 270)
			(size 0.59 0.64)
			(layers "F.Cu" "F.Mask" "F.Paste")
			(roundrect_rratio 0.25)
			(net 220 "Net-(D17-C)")
			(pinfunction "C")
			(pintype "passive")
		)
		(pad "2" smd roundrect
			(at 0.48 0 270)
			(size 0.59 0.64)
			(layers "F.Cu" "F.Mask" "F.Paste")
			(roundrect_rratio 0.25)
			(net 818 "Net-(D17-A)")
			(pinfunction "A")
			(pintype "passive")
		)
	)
	(footprint "antmicro-footprints:R_1206_3216Metric"
		(layer "F.Cu")
		(at 256.6 179.775 180)
		(property "Reference" "R151"
			(at 5 -0.275 180)
			(layer "F.SilkS")
			(effects
				(font
					(size 0.7 0.7)
					(thickness 0.15)
				)
				(justify left bottom)
			)
		)
		(property "Value" "R_0R01_1206"
			(at -2.422356 2.103591 180)
			(layer "F.Fab")
			(effects
				(font
					(size 0.7 0.7)
					(thickness 0.15)
				)
				(justify left bottom)
			)
		)
		(property "Datasheet" "https://www.yageo.com/upload/media/product/productsearch/datasheet/rchip/PYu-RL_Group_521_RoHS_L_2.pdf"
			(at 0 0 180)
			(layer "F.Fab")
			(hide yes)
			(effects
				(font
					(size 1.27 1.27)
					(thickness 0.15)
				)
			)
		)
		(property "Manufacturer" "YAGEO"
			(at 0 0 180)
			(unlocked yes)
			(layer "F.Fab")
			(hide yes)
			(effects
				(font
					(size 1 1)
					(thickness 0.15)
				)
			)
		)
		(property "MPN" "RL1206FR-7W0R01L"
			(at 0 0 180)
			(unlocked yes)
			(layer "F.Fab")
			(hide yes)
			(effects
				(font
					(size 1 1)
					(thickness 0.15)
				)
			)
		)
		(property "Val" "0R01"
			(at 0 0 180)
			(unlocked yes)
			(layer "F.Fab")
			(hide yes)
			(effects
				(font
					(size 1 1)
					(thickness 0.15)
				)
			)
		)
		(property "License" "Apache-2.0"
			(at 0 0 180)
			(unlocked yes)
			(layer "F.Fab")
			(hide yes)
			(effects
				(font
					(size 1 1)
					(thickness 0.15)
				)
			)
		)
		(property "Author" "Antmicro"
			(at 0 0 180)
			(unlocked yes)
			(layer "F.Fab")
			(hide yes)
			(effects
				(font
					(size 1 1)
					(thickness 0.15)
				)
			)
		)
		(property "Tolerance" "1%"
			(at 0 0 180)
			(unlocked yes)
			(layer "F.Fab")
			(hide yes)
			(effects
				(font
					(size 1 1)
					(thickness 0.15)
				)
			)
		)
		(sheetname "/Supply/DC-DC AUX, MGT/")
		(sheetfile "dc-dc-aux-mgt.kicad_sch")
		(attr smd)
		(fp_line
			(start 0.8 0.901)
			(end -0.8 0.901)
			(stroke
				(width 0.15)
				(type solid)
			)
			(layer "F.SilkS")
		)
		(fp_line
			(start 0.8 -0.899)
			(end -0.8 -0.899)
			(stroke
				(width 0.15)
				(type solid)
			)
			(layer "F.SilkS")
		)
		(fp_rect
			(start -2.325 -1.15)
			(end 2.325 1.15)
			(stroke
				(width 0.05)
				(type default)
			)
			(fill no)
			(layer "F.CrtYd")
		)
		(fp_line
			(start 1.6 -0.802)
			(end 1.6 0.8)
			(stroke
				(width 0.15)
				(type solid)
			)
			(layer "F.Fab")
		)
		(fp_line
			(start -1.601 0.8)
			(end 1.6 0.8)
			(stroke
				(width 0.15)
				(type solid)
			)
			(layer "F.Fab")
		)
		(fp_line
			(start -1.601 -0.802)
			(end 1.6 -0.802)
			(stroke
				(width 0.15)
				(type solid)
			)
			(layer "F.Fab")
		)
		(fp_line
			(start -1.601 -0.802)
			(end -1.601 0.8)
			(stroke
				(width 0.15)
				(type solid)
			)
			(layer "F.Fab")
		)
		(fp_text user "License: Apache-2.0"
			(at -2.401 6.3 180)
			(layer "F.Fab")
			(effects
				(font
					(size 0.7 0.7)
					(thickness 0.15)
				)
				(justify left bottom)
			)
		)
		(fp_text user "${REFERENCE}"
			(at -2.401 3.5 180)
			(layer "F.Fab")
			(effects
				(font
					(size 0.7 0.7)
					(thickness 0.15)
				)
				(justify left bottom)
			)
		)
		(fp_text user "Author: Antmicro"
			(at -2.401 4.899 180)
			(layer "F.Fab")
			(effects
				(font
					(size 0.7 0.7)
					(thickness 0.15)
				)
				(justify left bottom)
			)
		)
		(pad "1" smd roundrect
			(at -1.5 0.001 180)
			(size 1.15 1.8)
			(layers "F.Cu" "F.Mask" "F.Paste")
			(roundrect_rratio 0.25)
			(net 225 "/Supply/DC-DC AUX, MGT/MGTAVCCAUX_local")
			(pintype "passive")
		)
		(pad "2" smd roundrect
			(at 1.5 0.001 180)
			(size 1.15 1.8)
			(layers "F.Cu" "F.Mask" "F.Paste")
			(roundrect_rratio 0.25)
			(net 573 "+1V8_MGTVCCAUX")
			(pintype "passive")
		)
	)
	(footprint "antmicro-footprints:TP_SMD_1mm"
		(layer "F.Cu")
		(at 118.231 175.369)
		(property "Reference" "TP2"
			(at -2.65 0.65 0)
			(layer "F.SilkS")
			(hide yes)
			(effects
				(font
					(size 0.7 0.7)
					(thickness 0.15)
				)
				(justify left bottom)
			)
		)
		(property "Value" "TP_1mm_SMD"
			(at 0 1.4 0)
			(layer "F.Fab")
			(effects
				(font
					(size 0.7 0.7)
					(thickness 0.15)
				)
				(justify left bottom)
			)
		)
		(property "MPN" ""
			(at 0 0 0)
			(unlocked yes)
			(layer "F.Fab")
			(hide yes)
			(effects
				(font
					(size 1 1)
					(thickness 0.15)
				)
			)
		)
		(property "Manufacturer" ""
			(at 0 0 0)
			(unlocked yes)
			(layer "F.Fab")
			(hide yes)
			(effects
				(font
					(size 1 1)
					(thickness 0.15)
				)
			)
		)
		(property "Author" "Antmicro"
			(at 0 0 0)
			(unlocked yes)
			(layer "F.Fab")
			(hide yes)
			(effects
				(font
					(size 1 1)
					(thickness 0.15)
				)
			)
		)
		(property "License" "Apache-2.0"
			(at 0 0 0)
			(unlocked yes)
			(layer "F.Fab")
			(hide yes)
			(effects
				(font
					(size 1 1)
					(thickness 0.15)
				)
			)
		)
		(sheetname "/HDMI + SD Card/")
		(sheetfile "hdmi-sd-card.kicad_sch")
		(attr exclude_from_pos_files)
		(fp_circle
			(center 0 0)
			(end 0.6 0)
			(stroke
				(width 0.05)
				(type default)
			)
			(fill no)
			(layer "F.CrtYd")
		)
		(fp_text user "Author: Antmicro"
			(at -0.5 4 0)
			(layer "F.Fab")
			(effects
				(font
					(size 0.7 0.7)
					(thickness 0.15)
				)
				(justify left bottom)
			)
		)
		(fp_text user "License: Apache-2.0"
			(at -0.5 5.2 0)
			(layer "F.Fab")
			(effects
				(font
					(size 0.7 0.7)
					(thickness 0.15)
				)
				(justify left bottom)
			)
		)
		(fp_text user "${REFERENCE}"
			(at -0.5 2.8 0)
			(layer "F.Fab")
			(effects
				(font
					(size 0.7 0.7)
					(thickness 0.15)
				)
				(justify left bottom)
			)
		)
		(pad "1" smd circle
			(at 0 0)
			(size 1 1)
			(layers "F.Cu" "F.Mask")
			(net 8 "/HDMI + SD Card/HDMI_CONN_5V")
			(pinfunction "1")
			(pintype "passive")
		)
	)
	(footprint "antmicro-footprints:SOT-583"
		(layer "F.Cu")
		(at 123.45 163.25 90)
		(property "Reference" "U43"
			(at 1.525 3.2 0)
			(layer "F.SilkS")
			(effects
				(font
					(size 0.7 0.7)
					(thickness 0.15)
				)
				(justify left bottom)
			)
		)
		(property "Value" "TPS2116DRLR"
			(at 0 2.3 90)
			(layer "F.Fab")
			(effects
				(font
					(size 0.7 0.7)
					(thickness 0.15)
				)
				(justify left bottom)
			)
		)
		(property "Datasheet" "https://www.ti.com/lit/ds/symlink/tps2116.pdf?ts=1647438832100&ref_url=https%253A%252F%252Fwww.ti.com%252Fproduct%252FTPS2116"
			(at 0 0 90)
			(layer "F.Fab")
			(hide yes)
			(effects
				(font
					(size 1.27 1.27)
					(thickness 0.15)
				)
			)
		)
		(property "Manufacturer" "Texas Instruments"
			(at 0 0 90)
			(unlocked yes)
			(layer "F.Fab")
			(hide yes)
			(effects
				(font
					(size 1 1)
					(thickness 0.15)
				)
			)
		)
		(property "MPN" "TPS2116DRLR"
			(at 0 0 90)
			(unlocked yes)
			(layer "F.Fab")
			(hide yes)
			(effects
				(font
					(size 1 1)
					(thickness 0.15)
				)
			)
		)
		(property "Author" "Antmicro"
			(at 0 0 90)
			(unlocked yes)
			(layer "F.Fab")
			(hide yes)
			(effects
				(font
					(size 1 1)
					(thickness 0.15)
				)
			)
		)
		(property "License" "Apache-2.0"
			(at 0 0 90)
			(unlocked yes)
			(layer "F.Fab")
			(hide yes)
			(effects
				(font
					(size 1 1)
					(thickness 0.15)
				)
			)
		)
		(property ki_fp_filters "DRL0008A-MFG")
		(sheetname "/HDMI + SD Card/")
		(sheetfile "hdmi-sd-card.kicad_sch")
		(attr smd)
		(fp_line
			(start -0.65 -1.15)
			(end 0.65 -1.15)
			(stroke
				(width 0.15)
				(type solid)
			)
			(layer "F.SilkS")
		)
		(fp_line
			(start -0.651 1.15)
			(end 0.651 1.15)
			(stroke
				(width 0.15)
				(type solid)
			)
			(layer "F.SilkS")
		)
		(fp_circle
			(center -0.9 -1.1)
			(end -0.85 -1.05)
			(stroke
				(width 0.15)
				(type solid)
			)
			(fill yes)
			(layer "F.SilkS")
		)
		(fp_rect
			(start -1.15 -1.3)
			(end 1.15 1.3)
			(stroke
				(width 0.05)
				(type solid)
			)
			(fill no)
			(layer "F.CrtYd")
		)
		(fp_line
			(start -0.651 -1.1005)
			(end 0.651 -1.1005)
			(stroke
				(width 0.15)
				(type solid)
			)
			(layer "F.Fab")
		)
		(fp_line
			(start 0.651 1.1005)
			(end 0.651 -1.1005)
			(stroke
				(width 0.15)
				(type solid)
			)
			(layer "F.Fab")
		)
		(fp_line
			(start -0.651 1.1005)
			(end -0.651 -1.1005)
			(stroke
				(width 0.15)
				(type solid)
			)
			(layer "F.Fab")
		)
		(fp_line
			(start -0.651 1.1005)
			(end 0.651 1.1005)
			(stroke
				(width 0.15)
				(type solid)
			)
			(layer "F.Fab")
		)
		(fp_text user "License: Apache-2.0"
			(at -0.06 6.025 90)
			(layer "F.Fab")
			(effects
				(font
					(size 0.7 0.7)
					(thickness 0.15)
				)
				(justify left bottom)
			)
		)
		(fp_text user "${REFERENCE}"
			(at -0.06 4.025 90)
			(layer "F.Fab")
			(effects
				(font
					(size 0.7 0.7)
					(thickness 0.15)
				)
				(justify left bottom)
			)
		)
		(fp_text user "Author: Antmicro"
			(at -0.06 5.025 90)
			(layer "F.Fab")
			(effects
				(font
					(size 0.7 0.7)
					(thickness 0.15)
				)
				(justify left bottom)
			)
		)
		(pad "1" smd roundrect
			(at -0.739 -0.7495 90)
			(size 0.670001 0.299999)
			(layers "F.Cu" "F.Mask" "F.Paste")
			(roundrect_rratio 0.25)
			(net 1 "GND")
			(pinfunction "GND")
			(pintype "power_in")
		)
		(pad "2" smd roundrect
			(at -0.739 -0.2505 90)
			(size 0.670001 0.299999)
			(layers "F.Cu" "F.Mask" "F.Paste")
			(roundrect_rratio 0.25)
			(net 647 "/HDMI + SD Card/VCCB")
			(pinfunction "VOUT")
			(pintype "power_out")
		)
		(pad "3" smd roundrect
			(at -0.739 0.2495 90)
			(size 0.670001 0.299999)
			(layers "F.Cu" "F.Mask" "F.Paste")
			(roundrect_rratio 0.25)
			(net 797 "+1V8")
			(pinfunction "VIN1")
			(pintype "power_in")
		)
		(pad "4" smd roundrect
			(at -0.739 0.7495 90)
			(size 0.670001 0.299999)
			(layers "F.Cu" "F.Mask" "F.Paste")
			(roundrect_rratio 0.25)
			(net 772 "SD_SEL")
			(pinfunction "PR1")
			(pintype "input")
		)
		(pad "5" smd roundrect
			(at 0.74 0.7495 90)
			(size 0.670001 0.299999)
			(layers "F.Cu" "F.Mask" "F.Paste")
			(roundrect_rratio 0.25)
			(net 151 "+3V3")
			(pinfunction "MODE")
			(pintype "input")
		)
		(pad "6" smd roundrect
			(at 0.74 0.2495 90)
			(size 0.670001 0.299999)
			(layers "F.Cu" "F.Mask" "F.Paste")
			(roundrect_rratio 0.25)
			(net 151 "+3V3")
			(pinfunction "VIN2")
			(pintype "power_in")
		)
		(pad "7" smd roundrect
			(at 0.74 -0.2505 90)
			(size 0.670001 0.299999)
			(layers "F.Cu" "F.Mask" "F.Paste")
			(roundrect_rratio 0.25)
			(net 647 "/HDMI + SD Card/VCCB")
			(pinfunction "VOUT")
			(pintype "passive")
		)
		(pad "8" smd roundrect
			(at 0.74 -0.7495 90)
			(size 0.670001 0.299999)
			(layers "F.Cu" "F.Mask" "F.Paste")
			(roundrect_rratio 0.25)
			(net 663 "Net-(U43-ST)")
			(pinfunction "ST")
			(pintype "output")
		)
	)
	(footprint "antmicro-footprints:L_0402_1005Metric"
		(layer "F.Cu")
		(at 121.025 154.61 180)
		(descr "Inductor SMD 0402")
		(tags "Inductor SMD 0402")
		(property "Reference" "L7"
			(at -5.425 -0.415 0)
			(layer "F.SilkS")
			(effects
				(font
					(size 0.7 0.7)
					(thickness 0.15)
				)
				(justify right bottom)
			)
		)
		(property "Value" "L_20n_0.35A_0402"
			(at 0 1.4 0)
			(layer "F.Fab")
			(effects
				(font
					(size 0.7 0.7)
					(thickness 0.15)
				)
				(justify right bottom)
			)
		)
		(property "Datasheet" "https://product.tdk.com/system/files/dam/doc/product/inductor/inductor/smd/catalog/inductor_automotive_high-frequency_mlg1005s_en.pdf?ref_disty=mouser"
			(at 0 0 180)
			(layer "F.Fab")
			(hide yes)
			(effects
				(font
					(size 1.27 1.27)
					(thickness 0.15)
				)
			)
		)
		(property "Val" "20n/0.35A"
			(at 0 0 180)
			(unlocked yes)
			(layer "F.Fab")
			(hide yes)
			(effects
				(font
					(size 1 1)
					(thickness 0.15)
				)
			)
		)
		(property "Manufacturer" "TDK"
			(at 0 0 180)
			(unlocked yes)
			(layer "F.Fab")
			(hide yes)
			(effects
				(font
					(size 1 1)
					(thickness 0.15)
				)
			)
		)
		(property "MPN" "MLG1005S20NJTD25"
			(at 0 0 180)
			(unlocked yes)
			(layer "F.Fab")
			(hide yes)
			(effects
				(font
					(size 1 1)
					(thickness 0.15)
				)
			)
		)
		(property "ISat" ""
			(at 0 0 180)
			(unlocked yes)
			(layer "F.Fab")
			(hide yes)
			(effects
				(font
					(size 1 1)
					(thickness 0.15)
				)
			)
		)
		(property "IMax" "0.35 A"
			(at 0 0 180)
			(unlocked yes)
			(layer "F.Fab")
			(hide yes)
			(effects
				(font
					(size 1 1)
					(thickness 0.15)
				)
			)
		)
		(property "Size" "1.0x0.5"
			(at 0 0 180)
			(unlocked yes)
			(layer "F.Fab")
			(hide yes)
			(effects
				(font
					(size 1 1)
					(thickness 0.15)
				)
			)
		)
		(property "Author" "Antmicro"
			(at 0 0 180)
			(unlocked yes)
			(layer "F.Fab")
			(hide yes)
			(effects
				(font
					(size 1 1)
					(thickness 0.15)
				)
			)
		)
		(property "License" "Apache-2.0"
			(at 0 0 180)
			(unlocked yes)
			(layer "F.Fab")
			(hide yes)
			(effects
				(font
					(size 1 1)
					(thickness 0.15)
				)
			)
		)
		(sheetname "/HDMI + SD Card/")
		(sheetfile "hdmi-sd-card.kicad_sch")
		(attr smd)
		(fp_rect
			(start -0.925 -0.47)
			(end 0.925 0.47)
			(stroke
				(width 0.05)
				(type default)
			)
			(fill no)
			(layer "F.CrtYd")
		)
		(fp_rect
			(start -0.499 -0.249)
			(end 0.499 0.249)
			(stroke
				(width 0.15)
				(type solid)
			)
			(fill no)
			(layer "F.Fab")
		)
		(fp_text user "${REFERENCE}"
			(at -0.932 3.168 180)
			(layer "F.Fab")
			(effects
				(font
					(size 0.7 0.7)
					(thickness 0.15)
				)
				(justify left bottom)
			)
		)
		(fp_text user "License: Apache-2.0"
			(at -0.932 5.17 180)
			(layer "F.Fab")
			(effects
				(font
					(size 0.7 0.7)
					(thickness 0.15)
				)
				(justify left bottom)
			)
		)
		(fp_text user "Author: Antmicro"
			(at -0.932 4.17 180)
			(layer "F.Fab")
			(effects
				(font
					(size 0.7 0.7)
					(thickness 0.15)
				)
				(justify left bottom)
			)
		)
		(pad "1" smd roundrect
			(at -0.48 0 180)
			(size 0.59 0.64)
			(layers "F.Cu" "F.Mask" "F.Paste")
			(roundrect_rratio 0.25)
			(net 292 "/FPGA MGT Interface/HDMI_IN.CLK_N")
			(pintype "passive")
		)
		(pad "2" smd roundrect
			(at 0.48 0 180)
			(size 0.59 0.64)
			(layers "F.Cu" "F.Mask" "F.Paste")
			(roundrect_rratio 0.25)
			(net 677 "Net-(L7-Pad2)")
			(pintype "passive")
		)
	)
	(footprint "antmicro-footprints:Oscillator_SMD_Epson_SG3225EEN_3.2x2.5x1.2mm"
		(layer "F.Cu")
		(at 169.385 158.45 90)
		(property "Reference" "Y3"
			(at -2.77 0.535 0)
			(unlocked yes)
			(layer "F.SilkS")
			(effects
				(font
					(size 0.7 0.7)
					(thickness 0.15)
				)
				(justify left bottom)
			)
		)
		(property "Value" "Oscillator_100MHz_SG3225VAN"
			(at 0 3 90)
			(unlocked yes)
			(layer "F.Fab")
			(effects
				(font
					(size 0.7 0.7)
					(thickness 0.15)
				)
				(justify left bottom)
			)
		)
		(property "Datasheet" "https://support.epson.biz/td/api/doc_check.php?dl=brief_SG5032VAN&lang=en"
			(at 0 0 90)
			(layer "F.Fab")
			(hide yes)
			(effects
				(font
					(size 1.27 1.27)
					(thickness 0.15)
				)
			)
		)
		(property "Manufacturer" "Epson"
			(at 0 0 90)
			(unlocked yes)
			(layer "F.Fab")
			(hide yes)
			(effects
				(font
					(size 1 1)
					(thickness 0.15)
				)
			)
		)
		(property "MPN" "SG3225VAN_100.000000M-KEGA3"
			(at 0 0 90)
			(unlocked yes)
			(layer "F.Fab")
			(hide yes)
			(effects
				(font
					(size 1 1)
					(thickness 0.15)
				)
			)
		)
		(property "Val" "100MHz"
			(at 0 0 90)
			(unlocked yes)
			(layer "F.Fab")
			(hide yes)
			(effects
				(font
					(size 1 1)
					(thickness 0.15)
				)
			)
		)
		(property "Author" "Antmicro"
			(at 0 0 90)
			(unlocked yes)
			(layer "F.Fab")
			(hide yes)
			(effects
				(font
					(size 1 1)
					(thickness 0.15)
				)
			)
		)
		(property "License" "Apache-2.0"
			(at 0 0 90)
			(unlocked yes)
			(layer "F.Fab")
			(hide yes)
			(effects
				(font
					(size 1 1)
					(thickness 0.15)
				)
			)
		)
		(sheetname "/FPGA banks HP/")
		(sheetfile "fpga-hp-banks.kicad_sch")
		(attr smd)
		(fp_line
			(start 1.25 -1.825)
			(end -1.25 -1.825)
			(stroke
				(width 0.15)
				(type solid)
			)
			(layer "F.SilkS")
		)
		(fp_line
			(start 1.25 1.925)
			(end -1.25 1.925)
			(stroke
				(width 0.15)
				(type solid)
			)
			(layer "F.SilkS")
		)
		(fp_circle
			(center -1.57 -1.87)
			(end -1.57 -1.82)
			(stroke
				(width 0.15)
				(type solid)
			)
			(fill yes)
			(layer "F.SilkS")
		)
		(fp_rect
			(start 1.58 -1.85)
			(end -1.6 1.96)
			(stroke
				(width 0.05)
				(type solid)
			)
			(fill no)
			(layer "F.CrtYd")
		)
		(fp_text user "${REFERENCE}"
			(at -2.29 5.11 90)
			(unlocked yes)
			(layer "F.Fab")
			(effects
				(font
					(size 0.7 0.7)
					(thickness 0.15)
				)
				(justify left bottom)
			)
		)
		(fp_text user "License: Apache-2.0"
			(at -2.29 3.91 90)
			(layer "F.Fab")
			(effects
				(font
					(size 0.7 0.7)
					(thickness 0.15)
				)
				(justify left bottom)
			)
		)
		(fp_text user "Author: Antmicro"
			(at -2.29 6.31 90)
			(layer "F.Fab")
			(effects
				(font
					(size 0.7 0.7)
					(thickness 0.15)
				)
				(justify left bottom)
			)
		)
		(pad "1" smd rect
			(at -0.925 -1.24)
			(size 0.92 1.05)
			(layers "F.Cu" "F.Mask" "F.Paste")
			(net 151 "+3V3")
			(pinfunction "EN")
			(pintype "input")
			(solder_mask_margin 0.05)
		)
		(pad "2" smd rect
			(at -0.925 0.05)
			(size 0.8 1.05)
			(layers "F.Cu" "F.Mask" "F.Paste")
			(net 645 "unconnected-(Y3-NC-Pad2)")
			(pinfunction "NC")
			(pintype "no_connect")
			(solder_mask_margin 0.05)
		)
		(pad "3" smd rect
			(at -0.925 1.34)
			(size 0.92 1.05)
			(layers "F.Cu" "F.Mask" "F.Paste")
			(net 1 "GND")
			(pinfunction "GND")
			(pintype "power_in")
			(solder_mask_margin 0.05)
		)
		(pad "4" smd rect
			(at 0.925 1.34)
			(size 0.92 1.05)
			(layers "F.Cu" "F.Mask" "F.Paste")
			(net 543 "/FPGA banks HP/GCLK_100_LVDS+")
			(pinfunction "OUT+")
			(pintype "output")
			(solder_mask_margin 0.05)
		)
		(pad "5" smd rect
			(at 0.925 0.05)
			(size 0.8 1.05)
			(layers "F.Cu" "F.Mask" "F.Paste")
			(net 544 "/FPGA banks HP/GCLK_100_LVDS-")
			(pinfunction "OUT-")
			(pintype "output")
			(solder_mask_margin 0.05)
		)
		(pad "6" smd rect
			(at 0.925 -1.24)
			(size 0.92 1.05)
			(layers "F.Cu" "F.Mask" "F.Paste")
			(net 151 "+3V3")
			(pinfunction "VCC")
			(pintype "power_in")
			(solder_mask_margin 0.05)
		)
	)
	(footprint "antmicro-footprints:C_0402_1005Metric"
		(layer "F.Cu")
		(at 122.076 176.032 90)
		(descr "Capacitor SMD 0402")
		(tags "capacitor SMD 0402")
		(property "Reference" "C280"
			(at 1.21 0.41 90)
			(layer "F.SilkS")
			(effects
				(font
					(size 0.7 0.7)
					(thickness 0.15)
				)
				(justify left bottom)
			)
		)
		(property "Value" "C_100n_0402"
			(at -1.022927 2.155213 90)
			(layer "F.Fab")
			(effects
				(font
					(size 0.7 0.7)
					(thickness 0.15)
				)
				(justify left bottom)
			)
		)
		(property "Datasheet" "https://www.murata.com/products/productdetail?partno=GRM155R61H104KE14%23"
			(at 0 0 90)
			(layer "F.Fab")
			(hide yes)
			(effects
				(font
					(size 1.27 1.27)
					(thickness 0.15)
				)
			)
		)
		(property "MPN" "GRM155R61H104KE14D"
			(at 0 0 90)
			(unlocked yes)
			(layer "F.Fab")
			(hide yes)
			(effects
				(font
					(size 1 1)
					(thickness 0.15)
				)
			)
		)
		(property "Manufacturer" "Murata"
			(at 0 0 90)
			(unlocked yes)
			(layer "F.Fab")
			(hide yes)
			(effects
				(font
					(size 1 1)
					(thickness 0.15)
				)
			)
		)
		(property "License" "Apache-2.0"
			(at 0 0 90)
			(unlocked yes)
			(layer "F.Fab")
			(hide yes)
			(effects
				(font
					(size 1 1)
					(thickness 0.15)
				)
			)
		)
		(property "Author" "Antmicro"
			(at 0 0 90)
			(unlocked yes)
			(layer "F.Fab")
			(hide yes)
			(effects
				(font
					(size 1 1)
					(thickness 0.15)
				)
			)
		)
		(property "Val" "100n"
			(at 0 0 90)
			(unlocked yes)
			(layer "F.Fab")
			(hide yes)
			(effects
				(font
					(size 1 1)
					(thickness 0.15)
				)
			)
		)
		(property "Voltage" "50V"
			(at 0 0 90)
			(unlocked yes)
			(layer "F.Fab")
			(hide yes)
			(effects
				(font
					(size 1 1)
					(thickness 0.15)
				)
			)
		)
		(property "Dielectric" "X5R"
			(at 0 0 90)
			(unlocked yes)
			(layer "F.Fab")
			(hide yes)
			(effects
				(font
					(size 1 1)
					(thickness 0.15)
				)
			)
		)
		(property "Public" ""
			(at 0 0 90)
			(unlocked yes)
			(layer "F.Fab")
			(hide yes)
			(effects
				(font
					(size 1 1)
					(thickness 0.15)
				)
			)
		)
		(sheetname "/HDMI + SD Card/")
		(sheetfile "hdmi-sd-card.kicad_sch")
		(attr smd)
		(fp_rect
			(start -0.925 -0.47)
			(end 0.925 0.47)
			(stroke
				(width 0.05)
				(type default)
			)
			(fill no)
			(layer "F.CrtYd")
		)
		(fp_line
			(start 0.504 -0.25)
			(end 0.504 0.248)
			(stroke
				(width 0.15)
				(type solid)
			)
			(layer "F.Fab")
		)
		(fp_line
			(start -0.494 -0.25)
			(end 0.504 -0.25)
			(stroke
				(width 0.15)
				(type solid)
			)
			(layer "F.Fab")
		)
		(fp_line
			(start 0.504 0.248)
			(end -0.494 0.248)
			(stroke
				(width 0.15)
				(type solid)
			)
			(layer "F.Fab")
		)
		(fp_line
			(start -0.494 0.248)
			(end -0.494 -0.25)
			(stroke
				(width 0.15)
				(type solid)
			)
			(layer "F.Fab")
		)
		(fp_text user "Author: Antmicro"
			(at -0.939 3.399 90)
			(layer "F.Fab")
			(effects
				(font
					(size 0.7 0.7)
					(thickness 0.15)
				)
				(justify left bottom)
			)
		)
		(fp_text user "${REFERENCE}"
			(at -0.939 4.599 90)
			(layer "F.Fab")
			(effects
				(font
					(size 0.7 0.7)
					(thickness 0.15)
				)
				(justify left bottom)
			)
		)
		(fp_text user "License: Apache-2.0"
			(at -0.939 5.799 90)
			(layer "F.Fab")
			(effects
				(font
					(size 0.7 0.7)
					(thickness 0.15)
				)
				(justify left bottom)
			)
		)
		(pad "1" smd roundrect
			(at -0.48 0 90)
			(size 0.59 0.64)
			(layers "F.Cu" "F.Mask" "F.Paste")
			(roundrect_rratio 0.25)
			(net 810 "/HDMI + SD Card/HDMI_VDD")
			(pintype "passive")
		)
		(pad "2" smd roundrect
			(at 0.48 0 90)
			(size 0.59 0.64)
			(layers "F.Cu" "F.Mask" "F.Paste")
			(roundrect_rratio 0.25)
			(net 1 "GND")
			(pintype "passive")
		)
	)
	(footprint "antmicro-footprints:LED_0603_1608Metric_G"
		(layer "F.Cu")
		(at 102.605 102.225 90)
		(descr "LED SMD 0603 Green")
		(tags "LED SMD 0603 Green")
		(property "Reference" "D8"
			(at -2.575 -0.305 90)
			(layer "F.SilkS")
			(hide yes)
			(effects
				(font
					(size 0.7 0.7)
					(thickness 0.15)
				)
				(justify left bottom)
			)
		)
		(property "Value" "LED_G_0603_KP-1608CGCK"
			(at -0.001 1.599 90)
			(layer "F.Fab")
			(effects
				(font
					(size 0.7 0.7)
					(thickness 0.15)
				)
				(justify left bottom)
			)
		)
		(property "Datasheet" "http://www.kingbright.com/attachments/file/psearch//000/00/00/KP-1608CGCK(Ver.23B).pdf"
			(at 0 0 90)
			(layer "F.Fab")
			(hide yes)
			(effects
				(font
					(size 1.27 1.27)
					(thickness 0.15)
				)
			)
		)
		(property "MPN" "KP-1608CGCK"
			(at 0 0 90)
			(unlocked yes)
			(layer "F.Fab")
			(hide yes)
			(effects
				(font
					(size 1 1)
					(thickness 0.15)
				)
			)
		)
		(property "Manufacturer" "Kingbright"
			(at 0 0 90)
			(unlocked yes)
			(layer "F.Fab")
			(hide yes)
			(effects
				(font
					(size 1 1)
					(thickness 0.15)
				)
			)
		)
		(property "Author" "Antmicro"
			(at 0 0 90)
			(unlocked yes)
			(layer "F.Fab")
			(hide yes)
			(effects
				(font
					(size 1 1)
					(thickness 0.15)
				)
			)
		)
		(property "License" "Apache-2.0"
			(at 0 0 90)
			(unlocked yes)
			(layer "F.Fab")
			(hide yes)
			(effects
				(font
					(size 1 1)
					(thickness 0.15)
				)
			)
		)
		(property "Color" "Green"
			(at 0 0 90)
			(unlocked yes)
			(layer "F.Fab")
			(hide yes)
			(effects
				(font
					(size 1 1)
					(thickness 0.15)
				)
			)
		)
		(sheetname "/FPGA banks HD/")
		(sheetfile "fpga-hd-banks.kicad_sch")
		(attr smd)
		(fp_line
			(start 0.22 -0.35)
			(end -0.22 -0.35)
			(stroke
				(width 0.15)
				(type solid)
			)
			(layer "F.SilkS")
		)
		(fp_line
			(start -1.18 -0.319)
			(end -1.18 0.321)
			(stroke
				(width 0.15)
				(type solid)
			)
			(layer "F.SilkS")
		)
		(fp_line
			(start 0.105328 0.001008)
			(end 0.24 0.001)
			(stroke
				(width 0.1)
				(type solid)
			)
			(layer "F.SilkS")
		)
		(fp_line
			(start -0.094672 0.001008)
			(end 0.105328 -0.198992)
			(stroke
				(width 0.1)
				(type solid)
			)
			(layer "F.SilkS")
		)
		(fp_line
			(start -0.094672 0.001008)
			(end -0.24 0.001008)
			(stroke
				(width 0.1)
				(type solid)
			)
			(layer "F.SilkS")
		)
		(fp_line
			(start 0.105328 0.201008)
			(end 0.105328 -0.198992)
			(stroke
				(width 0.1)
				(type solid)
			)
			(layer "F.SilkS")
		)
		(fp_line
			(start 0.105328 0.201008)
			(end -0.094672 0.001008)
			(stroke
				(width 0.1)
				(type solid)
			)
			(layer "F.SilkS")
		)
		(fp_line
			(start -0.094672 0.201008)
			(end -0.094672 -0.198992)
			(stroke
				(width 0.1)
				(type solid)
			)
			(layer "F.SilkS")
		)
		(fp_line
			(start 0.22 0.35)
			(end -0.22 0.35)
			(stroke
				(width 0.15)
				(type solid)
			)
			(layer "F.SilkS")
		)
		(fp_rect
			(start 1.25 0.65)
			(end -1.25 -0.65)
			(stroke
				(width 0.05)
				(type solid)
			)
			(fill no)
			(layer "F.CrtYd")
		)
		(fp_line
			(start 0.201 -0.202)
			(end -0.101 0)
			(stroke
				(width 0.15)
				(type solid)
			)
			(layer "F.Fab")
		)
		(fp_line
			(start -0.199 -0.202)
			(end -0.199 0.1)
			(stroke
				(width 0.15)
				(type solid)
			)
			(layer "F.Fab")
		)
		(fp_line
			(start 0.599 0)
			(end 0.201 0)
			(stroke
				(width 0.15)
				(type solid)
			)
			(layer "F.Fab")
		)
		(fp_line
			(start 0.201 0)
			(end 0.201 -0.202)
			(stroke
				(width 0.15)
				(type solid)
			)
			(layer "F.Fab")
		)
		(fp_line
			(start -0.101 0)
			(end 0.201 0.2)
			(stroke
				(width 0.15)
				(type solid)
			)
			(layer "F.Fab")
		)
		(fp_line
			(start -0.199 0)
			(end -0.597 0)
			(stroke
				(width 0.15)
				(type solid)
			)
			(layer "F.Fab")
		)
		(fp_line
			(start 0.201 0.2)
			(end 0.201 0)
			(stroke
				(width 0.15)
				(type solid)
			)
			(layer "F.Fab")
		)
		(fp_line
			(start -0.199 0.2)
			(end -0.199 0.1)
			(stroke
				(width 0.15)
				(type solid)
			)
			(layer "F.Fab")
		)
		(fp_rect
			(start 0.848 0.4)
			(end -0.85 -0.402)
			(stroke
				(width 0.15)
				(type solid)
			)
			(fill no)
			(layer "F.Fab")
		)
		(fp_text user "${REFERENCE}"
			(at -1.4224 5.999 90)
			(layer "F.Fab")
			(effects
				(font
					(size 0.7 0.7)
					(thickness 0.15)
				)
				(justify left bottom)
			)
		)
		(fp_text user "Author: Antmicro"
			(at -1.4224 4.799 90)
			(layer "F.Fab")
			(effects
				(font
					(size 0.7 0.7)
					(thickness 0.15)
				)
				(justify left bottom)
			)
		)
		(fp_text user "License: Apache-2.0"
			(at -1.4224 3.599 90)
			(layer "F.Fab")
			(effects
				(font
					(size 0.7 0.7)
					(thickness 0.15)
				)
				(justify left bottom)
			)
		)
		(pad "1" smd roundrect
			(at -0.7 0 270)
			(size 0.8 1)
			(layers "F.Cu" "F.Mask" "F.Paste")
			(roundrect_rratio 0.2)
			(net 151 "+3V3")
			(pinfunction "C")
			(pintype "passive")
		)
		(pad "2" smd roundrect
			(at 0.7 0 270)
			(size 0.8 1)
			(layers "F.Cu" "F.Mask" "F.Paste")
			(roundrect_rratio 0.2)
			(net 233 "Net-(D8-A)")
			(pinfunction "A")
			(pintype "passive")
		)
	)
	(footprint "antmicro-footprints:R_0402_1005Metric"
		(layer "F.Cu")
		(at 150.424499 173.249 -90)
		(descr "Resistor SMD 0402")
		(tags "resistor SMD 0402")
		(property "Reference" "R94"
			(at 0.921 -0.485501 90)
			(layer "F.SilkS")
			(effects
				(font
					(size 0.7 0.7)
					(thickness 0.15)
				)
				(justify right bottom)
			)
		)
		(property "Value" "R_4k7_0402"
			(at -1.011843 1.772047 90)
			(layer "F.Fab")
			(effects
				(font
					(size 0.7 0.7)
					(thickness 0.15)
				)
				(justify right bottom)
			)
		)
		(property "Datasheet" "https://www.bourns.com/docs/product-datasheets/cr.pdf"
			(at 0 0 270)
			(layer "F.Fab")
			(hide yes)
			(effects
				(font
					(size 1.27 1.27)
					(thickness 0.15)
				)
			)
		)
		(property "Manufacturer" "Bourns"
			(at 0 0 270)
			(unlocked yes)
			(layer "F.Fab")
			(hide yes)
			(effects
				(font
					(size 1 1)
					(thickness 0.15)
				)
			)
		)
		(property "MPN" "CR0402-FX-4701GLF"
			(at 0 0 270)
			(unlocked yes)
			(layer "F.Fab")
			(hide yes)
			(effects
				(font
					(size 1 1)
					(thickness 0.15)
				)
			)
		)
		(property "Val" "4k7"
			(at 0 0 270)
			(unlocked yes)
			(layer "F.Fab")
			(hide yes)
			(effects
				(font
					(size 1 1)
					(thickness 0.15)
				)
			)
		)
		(property "License" "Apache-2.0"
			(at 0 0 270)
			(unlocked yes)
			(layer "F.Fab")
			(hide yes)
			(effects
				(font
					(size 1 1)
					(thickness 0.15)
				)
			)
		)
		(property "Author" "Antmicro"
			(at 0 0 270)
			(unlocked yes)
			(layer "F.Fab")
			(hide yes)
			(effects
				(font
					(size 1 1)
					(thickness 0.15)
				)
			)
		)
		(property "Tolerance" "1%"
			(at 0 0 270)
			(unlocked yes)
			(layer "F.Fab")
			(hide yes)
			(effects
				(font
					(size 1 1)
					(thickness 0.15)
				)
			)
		)
		(sheetname "/Debug FTDI + VNA/")
		(sheetfile "debug-ftdi.kicad_sch")
		(attr smd)
		(fp_rect
			(start -0.925 -0.47)
			(end 0.925 0.47)
			(stroke
				(width 0.05)
				(type default)
			)
			(fill no)
			(layer "F.CrtYd")
		)
		(fp_rect
			(start -0.5 -0.25)
			(end 0.5 0.25)
			(stroke
				(width 0.15)
				(type solid)
			)
			(fill no)
			(layer "F.Fab")
		)
		(fp_text user "Author: Antmicro"
			(at -0.95 4.169 270)
			(layer "F.Fab")
			(effects
				(font
					(size 0.7 0.7)
					(thickness 0.15)
				)
				(justify left bottom)
			)
		)
		(fp_text user "${REFERENCE}"
			(at -0.95 3.168 270)
			(layer "F.Fab")
			(effects
				(font
					(size 0.7 0.7)
					(thickness 0.15)
				)
				(justify left bottom)
			)
		)
		(fp_text user "License: Apache-2.0"
			(at -0.95 5.169 270)
			(layer "F.Fab")
			(effects
				(font
					(size 0.7 0.7)
					(thickness 0.15)
				)
				(justify left bottom)
			)
		)
		(pad "1" smd roundrect
			(at -0.48 0 270)
			(size 0.59 0.64)
			(layers "F.Cu" "F.Mask" "F.Paste")
			(roundrect_rratio 0.25)
			(net 38 "+3V3_AON")
			(pintype "passive")
		)
		(pad "2" smd roundrect
			(at 0.48 0 270)
			(size 0.59 0.64)
			(layers "F.Cu" "F.Mask" "F.Paste")
			(roundrect_rratio 0.25)
			(net 526 "/Debug FTDI + VNA/FTDI.SCL")
			(pintype "passive")
		)
	)
	(footprint "antmicro-footprints:R_0402_1005Metric"
		(layer "F.Cu")
		(at 115.098 112.72 -90)
		(descr "Resistor SMD 0402")
		(tags "resistor SMD 0402")
		(property "Reference" "R13"
			(at -3.07 -0.452 90)
			(layer "F.SilkS")
			(effects
				(font
					(size 0.7 0.7)
					(thickness 0.15)
				)
				(justify right bottom)
			)
		)
		(property "Value" "R_330R_0402"
			(at -1.011843 1.772047 90)
			(layer "F.Fab")
			(effects
				(font
					(size 0.7 0.7)
					(thickness 0.15)
				)
				(justify right bottom)
			)
		)
		(property "Datasheet" "https://www.bourns.com/docs/product-datasheets/cr.pdf"
			(at 0 0 270)
			(layer "F.Fab")
			(hide yes)
			(effects
				(font
					(size 1.27 1.27)
					(thickness 0.15)
				)
			)
		)
		(property "Manufacturer" "Bourns"
			(at 0 0 270)
			(unlocked yes)
			(layer "F.Fab")
			(hide yes)
			(effects
				(font
					(size 1 1)
					(thickness 0.15)
				)
			)
		)
		(property "MPN" "CR0402-FX-3300GLF"
			(at 0 0 270)
			(unlocked yes)
			(layer "F.Fab")
			(hide yes)
			(effects
				(font
					(size 1 1)
					(thickness 0.15)
				)
			)
		)
		(property "Val" "330R"
			(at 0 0 270)
			(unlocked yes)
			(layer "F.Fab")
			(hide yes)
			(effects
				(font
					(size 1 1)
					(thickness 0.15)
				)
			)
		)
		(property "License" "Apache-2.0"
			(at 0 0 270)
			(unlocked yes)
			(layer "F.Fab")
			(hide yes)
			(effects
				(font
					(size 1 1)
					(thickness 0.15)
				)
			)
		)
		(property "Author" "Antmicro"
			(at 0 0 270)
			(unlocked yes)
			(layer "F.Fab")
			(hide yes)
			(effects
				(font
					(size 1 1)
					(thickness 0.15)
				)
			)
		)
		(property "Tolerance" "1%"
			(at 0 0 270)
			(unlocked yes)
			(layer "F.Fab")
			(hide yes)
			(effects
				(font
					(size 1 1)
					(thickness 0.15)
				)
			)
		)
		(sheetname "/FPGA Config/")
		(sheetfile "fpga-config.kicad_sch")
		(attr smd)
		(fp_rect
			(start -0.925 -0.47)
			(end 0.925 0.47)
			(stroke
				(width 0.05)
				(type default)
			)
			(fill no)
			(layer "F.CrtYd")
		)
		(fp_rect
			(start -0.5 -0.25)
			(end 0.5 0.25)
			(stroke
				(width 0.15)
				(type solid)
			)
			(fill no)
			(layer "F.Fab")
		)
		(fp_text user "Author: Antmicro"
			(at -0.95 4.169 270)
			(layer "F.Fab")
			(effects
				(font
					(size 0.7 0.7)
					(thickness 0.15)
				)
				(justify left bottom)
			)
		)
		(fp_text user "License: Apache-2.0"
			(at -0.95 5.169 270)
			(layer "F.Fab")
			(effects
				(font
					(size 0.7 0.7)
					(thickness 0.15)
				)
				(justify left bottom)
			)
		)
		(fp_text user "${REFERENCE}"
			(at -0.95 3.168 270)
			(layer "F.Fab")
			(effects
				(font
					(size 0.7 0.7)
					(thickness 0.15)
				)
				(justify left bottom)
			)
		)
		(pad "1" smd roundrect
			(at -0.48 0 270)
			(size 0.59 0.64)
			(layers "F.Cu" "F.Mask" "F.Paste")
			(roundrect_rratio 0.25)
			(net 784 "Net-(D2-C)")
			(pintype "passive")
		)
		(pad "2" smd roundrect
			(at 0.48 0 270)
			(size 0.59 0.64)
			(layers "F.Cu" "F.Mask" "F.Paste")
			(roundrect_rratio 0.25)
			(net 270 "Net-(Q2-D)")
			(pintype "passive")
		)
	)
	(footprint "antmicro-footprints:C_0603_1608Metric"
		(layer "F.Cu")
		(at 251.337998 128.389 -90)
		(descr "Capacitor SMD 0603")
		(tags "capacitor 0603")
		(property "Reference" "C181"
			(at -1.389 0.787998 90)
			(layer "F.SilkS")
			(effects
				(font
					(size 0.7 0.7)
					(thickness 0.15)
				)
				(justify right bottom)
			)
		)
		(property "Value" "C_1u_25V_0603"
			(at -1.42757 1.770288 90)
			(layer "F.Fab")
			(effects
				(font
					(size 0.7 0.7)
					(thickness 0.15)
				)
				(justify right bottom)
			)
		)
		(property "Datasheet" "https://product.samsungsem.com/mlcc/CL10A105KA8NNN.do"
			(at 0 0 270)
			(layer "F.Fab")
			(hide yes)
			(effects
				(font
					(size 1.27 1.27)
					(thickness 0.15)
				)
			)
		)
		(property "Manufacturer" "Samsung Electro-Mechanics"
			(at 0 0 270)
			(unlocked yes)
			(layer "F.Fab")
			(hide yes)
			(effects
				(font
					(size 1 1)
					(thickness 0.15)
				)
			)
		)
		(property "MPN" "CL10A105KA8NNNC"
			(at 0 0 270)
			(unlocked yes)
			(layer "F.Fab")
			(hide yes)
			(effects
				(font
					(size 1 1)
					(thickness 0.15)
				)
			)
		)
		(property "Val" "1u"
			(at 0 0 270)
			(unlocked yes)
			(layer "F.Fab")
			(hide yes)
			(effects
				(font
					(size 1 1)
					(thickness 0.15)
				)
			)
		)
		(property "License" "Apache-2.0"
			(at 0 0 270)
			(unlocked yes)
			(layer "F.Fab")
			(hide yes)
			(effects
				(font
					(size 1 1)
					(thickness 0.15)
				)
			)
		)
		(property "Author" "Antmicro"
			(at 0 0 270)
			(unlocked yes)
			(layer "F.Fab")
			(hide yes)
			(effects
				(font
					(size 1 1)
					(thickness 0.15)
				)
			)
		)
		(property "Voltage" "25V"
			(at 0 0 270)
			(unlocked yes)
			(layer "F.Fab")
			(hide yes)
			(effects
				(font
					(size 1 1)
					(thickness 0.15)
				)
			)
		)
		(property "Dielectric" ""
			(at 0 0 270)
			(unlocked yes)
			(layer "F.Fab")
			(hide yes)
			(effects
				(font
					(size 1 1)
					(thickness 0.15)
				)
			)
		)
		(sheetname "/Supply/")
		(sheetfile "supply.kicad_sch")
		(attr smd)
		(fp_line
			(start -0.15 0.4)
			(end 0.15 0.4)
			(stroke
				(width 0.15)
				(type solid)
			)
			(layer "F.SilkS")
		)
		(fp_line
			(start -0.15 -0.4)
			(end 0.15 -0.4)
			(stroke
				(width 0.15)
				(type solid)
			)
			(layer "F.SilkS")
		)
		(fp_rect
			(start -1.25 -0.65)
			(end 1.25 0.65)
			(stroke
				(width 0.05)
				(type solid)
			)
			(fill no)
			(layer "F.CrtYd")
		)
		(fp_rect
			(start -0.8 -0.4)
			(end 0.8 0.4)
			(stroke
				(width 0.15)
				(type solid)
			)
			(fill no)
			(layer "F.Fab")
		)
		(fp_text user "${REFERENCE}"
			(at -1.682 3.895 270)
			(layer "F.Fab")
			(effects
				(font
					(size 0.7 0.7)
					(thickness 0.15)
				)
				(justify left bottom)
			)
		)
		(fp_text user "Author: Antmicro"
			(at -1.682 4.894 270)
			(layer "F.Fab")
			(effects
				(font
					(size 0.7 0.7)
					(thickness 0.15)
				)
				(justify left bottom)
			)
		)
		(fp_text user "License: Apache-2.0"
			(at -1.682 5.895 270)
			(layer "F.Fab")
			(effects
				(font
					(size 0.7 0.7)
					(thickness 0.15)
				)
				(justify left bottom)
			)
		)
		(pad "1" smd roundrect
			(at -0.7 0 270)
			(size 0.8 1)
			(layers "F.Cu" "F.Mask" "F.Paste")
			(roundrect_rratio 0.2)
			(net 35 "VDC")
			(pintype "passive")
		)
		(pad "2" smd roundrect
			(at 0.7 0 270)
			(size 0.8 1)
			(layers "F.Cu" "F.Mask" "F.Paste")
			(roundrect_rratio 0.2)
			(net 1 "GND")
			(pintype "passive")
		)
	)
	(footprint "antmicro-footprints:R_0402_1005Metric"
		(layer "F.Cu")
		(at 230.2 159.39 -90)
		(descr "Resistor SMD 0402")
		(tags "resistor SMD 0402")
		(property "Reference" "R170"
			(at -1.46 -2.1 90)
			(layer "F.SilkS")
			(effects
				(font
					(size 0.7 0.7)
					(thickness 0.15)
				)
				(justify right bottom)
			)
		)
		(property "Value" "R_10k_0402"
			(at -1.011843 1.772047 90)
			(layer "F.Fab")
			(effects
				(font
					(size 0.7 0.7)
					(thickness 0.15)
				)
				(justify right bottom)
			)
		)
		(property "Datasheet" "https://www.bourns.com/docs/product-datasheets/cr.pdf"
			(at 0 0 270)
			(layer "F.Fab")
			(hide yes)
			(effects
				(font
					(size 1.27 1.27)
					(thickness 0.15)
				)
			)
		)
		(property "MPN" "CR0402-FX-1002GLF"
			(at 0 0 270)
			(unlocked yes)
			(layer "F.Fab")
			(hide yes)
			(effects
				(font
					(size 1 1)
					(thickness 0.15)
				)
			)
		)
		(property "Manufacturer" "Bourns"
			(at 0 0 270)
			(unlocked yes)
			(layer "F.Fab")
			(hide yes)
			(effects
				(font
					(size 1 1)
					(thickness 0.15)
				)
			)
		)
		(property "License" "Apache-2.0"
			(at 0 0 270)
			(unlocked yes)
			(layer "F.Fab")
			(hide yes)
			(effects
				(font
					(size 1 1)
					(thickness 0.15)
				)
			)
		)
		(property "Author" "Antmicro"
			(at 0 0 270)
			(unlocked yes)
			(layer "F.Fab")
			(hide yes)
			(effects
				(font
					(size 1 1)
					(thickness 0.15)
				)
			)
		)
		(property "Val" "10k"
			(at 0 0 270)
			(unlocked yes)
			(layer "F.Fab")
			(hide yes)
			(effects
				(font
					(size 1 1)
					(thickness 0.15)
				)
			)
		)
		(property "Tolerance" "1%"
			(at 0 0 270)
			(unlocked yes)
			(layer "F.Fab")
			(hide yes)
			(effects
				(font
					(size 1 1)
					(thickness 0.15)
				)
			)
		)
		(sheetname "/Supply/")
		(sheetfile "supply.kicad_sch")
		(attr smd)
		(fp_rect
			(start -0.925 -0.47)
			(end 0.925 0.47)
			(stroke
				(width 0.05)
				(type default)
			)
			(fill no)
			(layer "F.CrtYd")
		)
		(fp_rect
			(start -0.5 -0.25)
			(end 0.5 0.25)
			(stroke
				(width 0.15)
				(type solid)
			)
			(fill no)
			(layer "F.Fab")
		)
		(fp_text user "License: Apache-2.0"
			(at -0.95 5.169 270)
			(layer "F.Fab")
			(effects
				(font
					(size 0.7 0.7)
					(thickness 0.15)
				)
				(justify left bottom)
			)
		)
		(fp_text user "Author: Antmicro"
			(at -0.95 4.169 270)
			(layer "F.Fab")
			(effects
				(font
					(size 0.7 0.7)
					(thickness 0.15)
				)
				(justify left bottom)
			)
		)
		(fp_text user "${REFERENCE}"
			(at -0.95 3.168 270)
			(layer "F.Fab")
			(effects
				(font
					(size 0.7 0.7)
					(thickness 0.15)
				)
				(justify left bottom)
			)
		)
		(pad "1" smd roundrect
			(at -0.48 0 270)
			(size 0.59 0.64)
			(layers "F.Cu" "F.Mask" "F.Paste")
			(roundrect_rratio 0.25)
			(net 250 "Net-(Q15-D)")
			(pintype "passive")
		)
		(pad "2" smd roundrect
			(at 0.48 0 270)
			(size 0.59 0.64)
			(layers "F.Cu" "F.Mask" "F.Paste")
			(roundrect_rratio 0.25)
			(net 152 "+5V")
			(pintype "passive")
		)
	)
	(footprint "antmicro-footprints:C_0603_1608Metric"
		(layer "F.Cu")
		(at 215.944999 170.109999)
		(descr "Capacitor SMD 0603")
		(tags "capacitor 0603")
		(property "Reference" "C265"
			(at -4.144999 0.540001 0)
			(layer "F.SilkS")
			(effects
				(font
					(size 0.7 0.7)
					(thickness 0.15)
				)
				(justify left bottom)
			)
		)
		(property "Value" "C_22u_0603"
			(at -1.42757 1.770288 0)
			(layer "F.Fab")
			(effects
				(font
					(size 0.7 0.7)
					(thickness 0.15)
				)
				(justify left bottom)
			)
		)
		(property "Datasheet" "https://www.murata.com/products/productdetail?partno=GRM188R60J226MEA0%23"
			(at 0 0 0)
			(layer "F.Fab")
			(hide yes)
			(effects
				(font
					(size 1.27 1.27)
					(thickness 0.15)
				)
			)
		)
		(property "Manufacturer" "Murata"
			(at 0 0 0)
			(unlocked yes)
			(layer "F.Fab")
			(hide yes)
			(effects
				(font
					(size 1 1)
					(thickness 0.15)
				)
			)
		)
		(property "MPN" "GRM188R60J226MEA0D"
			(at 0 0 0)
			(unlocked yes)
			(layer "F.Fab")
			(hide yes)
			(effects
				(font
					(size 1 1)
					(thickness 0.15)
				)
			)
		)
		(property "Val" "22u"
			(at 0 0 0)
			(unlocked yes)
			(layer "F.Fab")
			(hide yes)
			(effects
				(font
					(size 1 1)
					(thickness 0.15)
				)
			)
		)
		(property "License" "Apache-2.0"
			(at 0 0 0)
			(unlocked yes)
			(layer "F.Fab")
			(hide yes)
			(effects
				(font
					(size 1 1)
					(thickness 0.15)
				)
			)
		)
		(property "Author" "Antmicro"
			(at 0 0 0)
			(unlocked yes)
			(layer "F.Fab")
			(hide yes)
			(effects
				(font
					(size 1 1)
					(thickness 0.15)
				)
			)
		)
		(property "Voltage" ""
			(at 0 0 0)
			(unlocked yes)
			(layer "F.Fab")
			(hide yes)
			(effects
				(font
					(size 1 1)
					(thickness 0.15)
				)
			)
		)
		(property "Dielectric" ""
			(at 0 0 0)
			(unlocked yes)
			(layer "F.Fab")
			(hide yes)
			(effects
				(font
					(size 1 1)
					(thickness 0.15)
				)
			)
		)
		(sheetname "/Supply/DC-DC VCCINT/")
		(sheetfile "dc-dc-vccint.kicad_sch")
		(attr smd)
		(fp_line
			(start -0.15 -0.4)
			(end 0.15 -0.4)
			(stroke
				(width 0.15)
				(type solid)
			)
			(layer "F.SilkS")
		)
		(fp_line
			(start -0.15 0.4)
			(end 0.15 0.4)
			(stroke
				(width 0.15)
				(type solid)
			)
			(layer "F.SilkS")
		)
		(fp_rect
			(start -1.25 -0.65)
			(end 1.25 0.65)
			(stroke
				(width 0.05)
				(type solid)
			)
			(fill no)
			(layer "F.CrtYd")
		)
		(fp_rect
			(start -0.8 -0.4)
			(end 0.8 0.4)
			(stroke
				(width 0.15)
				(type solid)
			)
			(fill no)
			(layer "F.Fab")
		)
		(fp_text user "Author: Antmicro"
			(at -1.682 4.894 0)
			(layer "F.Fab")
			(effects
				(font
					(size 0.7 0.7)
					(thickness 0.15)
				)
				(justify left bottom)
			)
		)
		(fp_text user "${REFERENCE}"
			(at -1.682 3.895 0)
			(layer "F.Fab")
			(effects
				(font
					(size 0.7 0.7)
					(thickness 0.15)
				)
				(justify left bottom)
			)
		)
		(fp_text user "License: Apache-2.0"
			(at -1.682 5.895 0)
			(layer "F.Fab")
			(effects
				(font
					(size 0.7 0.7)
					(thickness 0.15)
				)
				(justify left bottom)
			)
		)
		(pad "1" smd roundrect
			(at -0.7 0)
			(size 0.8 1)
			(layers "F.Cu" "F.Mask" "F.Paste")
			(roundrect_rratio 0.2)
			(net 1 "GND")
			(pintype "passive")
		)
		(pad "2" smd roundrect
			(at 0.7 0)
			(size 0.8 1)
			(layers "F.Cu" "F.Mask" "F.Paste")
			(roundrect_rratio 0.2)
			(net 223 "/Supply/DC-DC VCCINT/0V85_REG0")
			(pintype "passive")
		)
	)
	(footprint "antmicro-footprints:F_1206_3216Metric"
		(layer "F.Cu")
		(at 146.61 192.285 90)
		(property "Reference" "F2"
			(at 2.15 1.1 90)
			(layer "F.SilkS")
			(effects
				(font
					(size 0.7 0.7)
					(thickness 0.15)
				)
				(justify left bottom)
			)
		)
		(property "Value" "F_4A_1206"
			(at 0 2 90)
			(layer "F.Fab")
			(effects
				(font
					(size 0.7 0.7)
					(thickness 0.15)
				)
				(justify left bottom)
			)
		)
		(property "Datasheet" "https://www.littelfuse.com/media?resourcetype=datasheets&itemid=dbe9bcd7-6072-4adf-bf5b-d33e52a6b90f&filename=littelfuse-fuse-466-datasheet"
			(at 0 0 90)
			(layer "F.Fab")
			(hide yes)
			(effects
				(font
					(size 1.27 1.27)
					(thickness 0.15)
				)
			)
		)
		(property "Manufacturer" "Littelfuse"
			(at 0 0 90)
			(unlocked yes)
			(layer "F.Fab")
			(hide yes)
			(effects
				(font
					(size 1 1)
					(thickness 0.15)
				)
			)
		)
		(property "MPN" "0466004.NR "
			(at 0 0 90)
			(unlocked yes)
			(layer "F.Fab")
			(hide yes)
			(effects
				(font
					(size 1 1)
					(thickness 0.15)
				)
			)
		)
		(property "Author" "Antmicro"
			(at 0 0 90)
			(unlocked yes)
			(layer "F.Fab")
			(hide yes)
			(effects
				(font
					(size 1 1)
					(thickness 0.15)
				)
			)
		)
		(property "License" "Apache-2.0"
			(at 0 0 90)
			(unlocked yes)
			(layer "F.Fab")
			(hide yes)
			(effects
				(font
					(size 1 1)
					(thickness 0.15)
				)
			)
		)
		(sheetname "/Supply/")
		(sheetfile "supply.kicad_sch")
		(attr smd)
		(fp_line
			(start 0.8 -0.899)
			(end -0.8 -0.899)
			(stroke
				(width 0.15)
				(type solid)
			)
			(layer "F.SilkS")
		)
		(fp_line
			(start 0.8 0.901)
			(end -0.8 0.901)
			(stroke
				(width 0.15)
				(type solid)
			)
			(layer "F.SilkS")
		)
		(fp_rect
			(start -2.325 -1.15)
			(end 2.325 1.15)
			(stroke
				(width 0.05)
				(type default)
			)
			(fill no)
			(layer "F.CrtYd")
		)
		(fp_line
			(start 1.624 -0.861)
			(end 1.624 0.792)
			(stroke
				(width 0.15)
				(type solid)
			)
			(layer "F.Fab")
		)
		(fp_line
			(start -1.677 -0.861)
			(end 1.624 -0.861)
			(stroke
				(width 0.15)
				(type solid)
			)
			(layer "F.Fab")
		)
		(fp_line
			(start 1.624 0.792)
			(end -1.677 0.792)
			(stroke
				(width 0.15)
				(type solid)
			)
			(layer "F.Fab")
		)
		(fp_line
			(start -1.677 0.792)
			(end -1.677 -0.861)
			(stroke
				(width 0.15)
				(type solid)
			)
			(layer "F.Fab")
		)
		(fp_text user "Author: Antmicro"
			(at -1.95 6.4 90)
			(layer "F.Fab")
			(effects
				(font
					(size 0.7 0.7)
					(thickness 0.15)
				)
				(justify left bottom)
			)
		)
		(fp_text user "License: Apache-2.0"
			(at -1.95 5.2 90)
			(layer "F.Fab")
			(effects
				(font
					(size 0.7 0.7)
					(thickness 0.15)
				)
				(justify left bottom)
			)
		)
		(fp_text user "${REFERENCE}"
			(at -1.95 4 90)
			(layer "F.Fab")
			(effects
				(font
					(size 0.7 0.7)
					(thickness 0.15)
				)
				(justify left bottom)
			)
		)
		(pad "1" smd roundrect
			(at -1.5 0.001 90)
			(size 1.15 1.8)
			(layers "F.Cu" "F.Mask" "F.Paste")
			(roundrect_rratio 0.25)
			(net 10 "+12V")
			(pintype "passive")
		)
		(pad "2" smd roundrect
			(at 1.5 0.001 90)
			(size 1.15 1.8)
			(layers "F.Cu" "F.Mask" "F.Paste")
			(roundrect_rratio 0.25)
			(net 324 "/Supply/12V_PCIE_fused")
			(pintype "passive")
		)
	)
	(footprint "antmicro-footprints:SC70-3"
		(layer "F.Cu")
		(at 250.274499 143.3)
		(property "Reference" "Q11"
			(at 0.475501 1.04 90)
			(layer "F.SilkS")
			(effects
				(font
					(size 0.7 0.7)
					(thickness 0.15)
				)
				(justify left bottom)
			)
		)
		(property "Value" "BSS138PW"
			(at 0 2.3 0)
			(layer "F.Fab")
			(effects
				(font
					(size 0.7 0.7)
					(thickness 0.15)
				)
				(justify left bottom)
			)
		)
		(property "Datasheet" "https://assets.nexperia.com/documents/data-sheet/BSS138PW.pdf"
			(at 0 0 0)
			(layer "F.Fab")
			(hide yes)
			(effects
				(font
					(size 1.27 1.27)
					(thickness 0.15)
				)
			)
		)
		(property "MPN" "BSS138PW"
			(at 0 0 0)
			(unlocked yes)
			(layer "F.Fab")
			(hide yes)
			(effects
				(font
					(size 1 1)
					(thickness 0.15)
				)
			)
		)
		(property "Manufacturer" "Nexperia"
			(at 0 0 0)
			(unlocked yes)
			(layer "F.Fab")
			(hide yes)
			(effects
				(font
					(size 1 1)
					(thickness 0.15)
				)
			)
		)
		(property "Author" "Antmicro"
			(at 0 0 0)
			(unlocked yes)
			(layer "F.Fab")
			(hide yes)
			(effects
				(font
					(size 1 1)
					(thickness 0.15)
				)
			)
		)
		(property "License" "Apache-2.0"
			(at 0 0 0)
			(unlocked yes)
			(layer "F.Fab")
			(hide yes)
			(effects
				(font
					(size 1 1)
					(thickness 0.15)
				)
			)
		)
		(sheetname "/DDR5 RDIMM/")
		(sheetfile "ddr5-rdimm.kicad_sch")
		(attr smd)
		(fp_line
			(start -0.3 -1)
			(end 0.627 -0.999)
			(stroke
				(width 0.15)
				(type solid)
			)
			(layer "F.SilkS")
		)
		(fp_line
			(start -0.3 1)
			(end 0.627 1.001)
			(stroke
				(width 0.15)
				(type solid)
			)
			(layer "F.SilkS")
		)
		(fp_line
			(start 0.627 -0.6)
			(end 0.627 -0.999)
			(stroke
				(width 0.15)
				(type solid)
			)
			(layer "F.SilkS")
		)
		(fp_line
			(start 0.627 0.6)
			(end 0.627 1.001)
			(stroke
				(width 0.15)
				(type solid)
			)
			(layer "F.SilkS")
		)
		(fp_line
			(start -1.4 1)
			(end -1.4 -1)
			(stroke
				(width 0.05)
				(type solid)
			)
			(layer "F.CrtYd")
		)
		(fp_line
			(start -0.9 -1.3)
			(end -0.9 -1)
			(stroke
				(width 0.05)
				(type solid)
			)
			(layer "F.CrtYd")
		)
		(fp_line
			(start -0.9 -1.3)
			(end 0.9 -1.3)
			(stroke
				(width 0.05)
				(type solid)
			)
			(layer "F.CrtYd")
		)
		(fp_line
			(start -0.9 -1)
			(end -1.4 -1)
			(stroke
				(width 0.05)
				(type solid)
			)
			(layer "F.CrtYd")
		)
		(fp_line
			(start -0.9 1)
			(end -1.4 1)
			(stroke
				(width 0.05)
				(type solid)
			)
			(layer "F.CrtYd")
		)
		(fp_line
			(start -0.9 1.3)
			(end -0.9 1)
			(stroke
				(width 0.05)
				(type solid)
			)
			(layer "F.CrtYd")
		)
		(fp_line
			(start 0.9 -1.3)
			(end 0.9 -0.4)
			(stroke
				(width 0.05)
				(type solid)
			)
			(layer "F.CrtYd")
		)
		(fp_line
			(start 0.9 -0.4)
			(end 1.4 -0.4)
			(stroke
				(width 0.05)
				(type solid)
			)
			(layer "F.CrtYd")
		)
		(fp_line
			(start 0.9 0.4)
			(end 0.9 1.3)
			(stroke
				(width 0.05)
				(type solid)
			)
			(layer "F.CrtYd")
		)
		(fp_line
			(start 0.9 1.3)
			(end -0.9 1.3)
			(stroke
				(width 0.05)
				(type solid)
			)
			(layer "F.CrtYd")
		)
		(fp_line
			(start 1.4 -0.4)
			(end 1.4 0.4)
			(stroke
				(width 0.05)
				(type solid)
			)
			(layer "F.CrtYd")
		)
		(fp_line
			(start 1.4 0.4)
			(end 0.9 0.4)
			(stroke
				(width 0.05)
				(type solid)
			)
			(layer "F.CrtYd")
		)
		(fp_rect
			(start -0.623 -0.999)
			(end 0.627 1.001)
			(stroke
				(width 0.15)
				(type solid)
			)
			(fill no)
			(layer "F.Fab")
		)
		(fp_text user "Author: Antmicro"
			(at -1.45 5.782 0)
			(layer "F.Fab")
			(effects
				(font
					(size 0.7 0.7)
					(thickness 0.15)
				)
				(justify left bottom)
			)
		)
		(fp_text user "License: Apache-2.0"
			(at -1.45 6.782 0)
			(layer "F.Fab")
			(effects
				(font
					(size 0.7 0.7)
					(thickness 0.15)
				)
				(justify left bottom)
			)
		)
		(fp_text user "${REFERENCE}"
			(at -1.45 4.783 0)
			(layer "F.Fab")
			(effects
				(font
					(size 0.7 0.7)
					(thickness 0.15)
				)
				(justify left bottom)
			)
		)
		(pad "1" smd rect
			(at -1.051 -0.65 90)
			(size 0.6 0.6)
			(layers "F.Cu" "F.Mask" "F.Paste")
			(net 702 "HOT_SWAP_RED")
			(pinfunction "G")
			(pintype "passive")
		)
		(pad "2" smd rect
			(at -1.051 0.65 90)
			(size 0.6 0.6)
			(layers "F.Cu" "F.Mask" "F.Paste")
			(net 1 "GND")
			(pinfunction "S")
			(pintype "passive")
		)
		(pad "3" smd rect
			(at 1.05 0 90)
			(size 0.6 0.6)
			(layers "F.Cu" "F.Mask" "F.Paste")
			(net 283 "Net-(Q11-D)")
			(pinfunction "D")
			(pintype "passive")
		)
	)
	(footprint "antmicro-footprints:C_0402_1005Metric"
		(layer "F.Cu")
		(at 242.98 132.32 90)
		(descr "Capacitor SMD 0402")
		(tags "capacitor SMD 0402")
		(property "Reference" "C165"
			(at -1.78 1.62 90)
			(layer "F.SilkS")
			(effects
				(font
					(size 0.7 0.7)
					(thickness 0.15)
				)
				(justify left bottom)
			)
		)
		(property "Value" "C_100n_0402"
			(at -1.022927 2.155213 90)
			(layer "F.Fab")
			(effects
				(font
					(size 0.7 0.7)
					(thickness 0.15)
				)
				(justify left bottom)
			)
		)
		(property "Datasheet" "https://www.murata.com/products/productdetail?partno=GRM155R61H104KE14%23"
			(at 0 0 90)
			(layer "F.Fab")
			(hide yes)
			(effects
				(font
					(size 1.27 1.27)
					(thickness 0.15)
				)
			)
		)
		(property "Manufacturer" "Murata"
			(at 0 0 90)
			(unlocked yes)
			(layer "F.Fab")
			(hide yes)
			(effects
				(font
					(size 1 1)
					(thickness 0.15)
				)
			)
		)
		(property "MPN" "GRM155R61H104KE14D"
			(at 0 0 90)
			(unlocked yes)
			(layer "F.Fab")
			(hide yes)
			(effects
				(font
					(size 1 1)
					(thickness 0.15)
				)
			)
		)
		(property "Val" "100n"
			(at 0 0 90)
			(unlocked yes)
			(layer "F.Fab")
			(hide yes)
			(effects
				(font
					(size 1 1)
					(thickness 0.15)
				)
			)
		)
		(property "License" "Apache-2.0"
			(at 0 0 90)
			(unlocked yes)
			(layer "F.Fab")
			(hide yes)
			(effects
				(font
					(size 1 1)
					(thickness 0.15)
				)
			)
		)
		(property "Author" "Antmicro"
			(at 0 0 90)
			(unlocked yes)
			(layer "F.Fab")
			(hide yes)
			(effects
				(font
					(size 1 1)
					(thickness 0.15)
				)
			)
		)
		(property "Voltage" "50V"
			(at 0 0 90)
			(unlocked yes)
			(layer "F.Fab")
			(hide yes)
			(effects
				(font
					(size 1 1)
					(thickness 0.15)
				)
			)
		)
		(property "Dielectric" "X5R"
			(at 0 0 90)
			(unlocked yes)
			(layer "F.Fab")
			(hide yes)
			(effects
				(font
					(size 1 1)
					(thickness 0.15)
				)
			)
		)
		(sheetname "/I^{2}C + I3C/")
		(sheetfile "i2c.kicad_sch")
		(attr smd)
		(fp_rect
			(start -0.925 -0.47)
			(end 0.925 0.47)
			(stroke
				(width 0.05)
				(type default)
			)
			(fill no)
			(layer "F.CrtYd")
		)
		(fp_line
			(start 0.504 -0.25)
			(end 0.504 0.248)
			(stroke
				(width 0.15)
				(type solid)
			)
			(layer "F.Fab")
		)
		(fp_line
			(start -0.494 -0.25)
			(end 0.504 -0.25)
			(stroke
				(width 0.15)
				(type solid)
			)
			(layer "F.Fab")
		)
		(fp_line
			(start 0.504 0.248)
			(end -0.494 0.248)
			(stroke
				(width 0.15)
				(type solid)
			)
			(layer "F.Fab")
		)
		(fp_line
			(start -0.494 0.248)
			(end -0.494 -0.25)
			(stroke
				(width 0.15)
				(type solid)
			)
			(layer "F.Fab")
		)
		(fp_text user "License: Apache-2.0"
			(at -0.939 5.799 90)
			(layer "F.Fab")
			(effects
				(font
					(size 0.7 0.7)
					(thickness 0.15)
				)
				(justify left bottom)
			)
		)
		(fp_text user "Author: Antmicro"
			(at -0.939 3.399 90)
			(layer "F.Fab")
			(effects
				(font
					(size 0.7 0.7)
					(thickness 0.15)
				)
				(justify left bottom)
			)
		)
		(fp_text user "${REFERENCE}"
			(at -0.939 4.599 90)
			(layer "F.Fab")
			(effects
				(font
					(size 0.7 0.7)
					(thickness 0.15)
				)
				(justify left bottom)
			)
		)
		(pad "1" smd roundrect
			(at -0.48 0 90)
			(size 0.59 0.64)
			(layers "F.Cu" "F.Mask" "F.Paste")
			(roundrect_rratio 0.25)
			(net 151 "+3V3")
			(pintype "passive")
		)
		(pad "2" smd roundrect
			(at 0.48 0 90)
			(size 0.59 0.64)
			(layers "F.Cu" "F.Mask" "F.Paste")
			(roundrect_rratio 0.25)
			(net 1 "GND")
			(pintype "passive")
		)
	)
	(footprint "antmicro-footprints:USON-10_2.5x1mm_P0.5mm"
		(layer "F.Cu")
		(at 252.2 185.699)
		(descr "USON-10 2.5x1mm_ Pitch 0.5mm")
		(tags "USON-10 2.5x1mm Pitch 0.5mm")
		(property "Reference" "U33"
			(at -0.975 2.525 0)
			(layer "F.SilkS")
			(effects
				(font
					(size 0.7 0.7)
					(thickness 0.15)
				)
				(justify left bottom)
			)
		)
		(property "Value" "TPD4E05U06QDQARQ1"
			(at 0.018 2.499 0)
			(layer "F.Fab")
			(effects
				(font
					(size 0.7 0.7)
					(thickness 0.15)
				)
				(justify left bottom)
			)
		)
		(property "Datasheet" "https://www.ti.com/lit/ds/symlink/tpd4e05u06-q1.pdf?HQS=dis-mous-null-mousermode-dsf-pf-null-wwe&ts=1663591265741&ref_url=https%253A%252F%252Fwww.mouser.com%252F"
			(at 0 0 0)
			(layer "F.Fab")
			(hide yes)
			(effects
				(font
					(size 1.27 1.27)
					(thickness 0.15)
				)
			)
		)
		(property "Manufacturer" "Texas Instruments"
			(at 0 0 0)
			(unlocked yes)
			(layer "F.Fab")
			(hide yes)
			(effects
				(font
					(size 1 1)
					(thickness 0.15)
				)
			)
		)
		(property "MPN" "TPD4E05U06QDQARQ1"
			(at 0 0 0)
			(unlocked yes)
			(layer "F.Fab")
			(hide yes)
			(effects
				(font
					(size 1 1)
					(thickness 0.15)
				)
			)
		)
		(property "Author" "Antmicro"
			(at 0 0 0)
			(unlocked yes)
			(layer "F.Fab")
			(hide yes)
			(effects
				(font
					(size 1 1)
					(thickness 0.15)
				)
			)
		)
		(property "License" "Apache-2.0"
			(at 0 0 0)
			(unlocked yes)
			(layer "F.Fab")
			(hide yes)
			(effects
				(font
					(size 1 1)
					(thickness 0.15)
				)
			)
		)
		(sheetname "/I^{2}C + I3C/")
		(sheetfile "i2c.kicad_sch")
		(attr smd)
		(fp_line
			(start 0.498 -1.401)
			(end -0.5 -1.401)
			(stroke
				(width 0.15)
				(type solid)
			)
			(layer "F.SilkS")
		)
		(fp_line
			(start 0.498 1.398)
			(end -0.5 1.398)
			(stroke
				(width 0.15)
				(type solid)
			)
			(layer "F.SilkS")
		)
		(fp_circle
			(center -0.68 -1.27)
			(end -0.63 -1.27)
			(stroke
				(width 0.15)
				(type solid)
			)
			(fill yes)
			(layer "F.SilkS")
		)
		(fp_rect
			(start -0.8 -1.5)
			(end 0.8 1.499)
			(stroke
				(width 0.05)
				(type solid)
			)
			(fill no)
			(layer "F.CrtYd")
		)
		(fp_line
			(start -0.5 -1)
			(end -0.5 1.249)
			(stroke
				(width 0.15)
				(type solid)
			)
			(layer "F.Fab")
		)
		(fp_line
			(start -0.5 1.249)
			(end 0.498 1.249)
			(stroke
				(width 0.15)
				(type solid)
			)
			(layer "F.Fab")
		)
		(fp_line
			(start -0.25 -1.25)
			(end -0.5 -1)
			(stroke
				(width 0.15)
				(type solid)
			)
			(layer "F.Fab")
		)
		(fp_line
			(start 0.498 -1.25)
			(end -0.25 -1.25)
			(stroke
				(width 0.15)
				(type solid)
			)
			(layer "F.Fab")
		)
		(fp_line
			(start 0.498 -1.25)
			(end 0.498 1.249)
			(stroke
				(width 0.15)
				(type solid)
			)
			(layer "F.Fab")
		)
		(fp_text user "License: Apache-2.0"
			(at -0.802 6.9 0)
			(layer "F.Fab")
			(effects
				(font
					(size 0.7 0.7)
					(thickness 0.15)
				)
				(justify left bottom)
			)
		)
		(fp_text user "${REFERENCE}"
			(at -0.802 4.498 0)
			(layer "F.Fab")
			(effects
				(font
					(size 0.7 0.7)
					(thickness 0.15)
				)
				(justify left bottom)
			)
		)
		(fp_text user "Author: Antmicro"
			(at -0.802 5.7 0)
			(layer "F.Fab")
			(effects
				(font
					(size 0.7 0.7)
					(thickness 0.15)
				)
				(justify left bottom)
			)
		)
		(pad "1" smd roundrect
			(at -0.387 -1 270)
			(size 0.25 0.55)
			(layers "F.Cu" "F.Mask" "F.Paste")
			(roundrect_rratio 0.25)
			(net 151 "+3V3")
			(pintype "passive")
		)
		(pad "2" smd roundrect
			(at -0.387 -0.5 270)
			(size 0.25 0.55)
			(layers "F.Cu" "F.Mask" "F.Paste")
			(roundrect_rratio 0.25)
			(net 368 "/I^{2}C + I3C/I3C_EXT.SDA")
			(pintype "passive")
		)
		(pad "3" smd roundrect
			(at -0.387 0 270)
			(size 0.4 0.55)
			(layers "F.Cu" "F.Mask" "F.Paste")
			(roundrect_rratio 0.25)
			(net 1 "GND")
			(pintype "power_in")
		)
		(pad "4" smd roundrect
			(at -0.387 0.498 270)
			(size 0.25 0.55)
			(layers "F.Cu" "F.Mask" "F.Paste")
			(roundrect_rratio 0.25)
			(net 369 "/I^{2}C + I3C/I3C_EXT.SCL")
			(pintype "passive")
		)
		(pad "5" smd roundrect
			(at -0.387 0.998 270)
			(size 0.25 0.55)
			(layers "F.Cu" "F.Mask" "F.Paste")
			(roundrect_rratio 0.25)
			(net 817 "unconnected-(U33-Pad5)_1")
			(pintype "passive+no_connect")
		)
		(pad "6" smd roundrect
			(at 0.385 0.998 270)
			(size 0.25 0.55)
			(layers "F.Cu" "F.Mask" "F.Paste")
			(roundrect_rratio 0.25)
			(net 795 "unconnected-(U33-Pad5)")
			(pintype "passive+no_connect")
		)
		(pad "7" smd roundrect
			(at 0.385 0.498 270)
			(size 0.25 0.55)
			(layers "F.Cu" "F.Mask" "F.Paste")
			(roundrect_rratio 0.25)
			(net 369 "/I^{2}C + I3C/I3C_EXT.SCL")
			(pintype "passive")
		)
		(pad "8" smd roundrect
			(at 0.385 0 270)
			(size 0.4 0.55)
			(layers "F.Cu" "F.Mask" "F.Paste")
			(roundrect_rratio 0.25)
			(net 1 "GND")
			(pintype "passive")
		)
		(pad "9" smd roundrect
			(at 0.385 -0.5 270)
			(size 0.25 0.55)
			(layers "F.Cu" "F.Mask" "F.Paste")
			(roundrect_rratio 0.25)
			(net 368 "/I^{2}C + I3C/I3C_EXT.SDA")
			(pintype "passive")
		)
		(pad "10" smd roundrect
			(at 0.385 -1 270)
			(size 0.25 0.55)
			(layers "F.Cu" "F.Mask" "F.Paste")
			(roundrect_rratio 0.25)
			(net 151 "+3V3")
			(pintype "passive")
		)
	)
	(footprint "antmicro-footprints:LED_0402_1005Metric_G"
		(layer "F.Cu")
		(at 109.73 114.725 180)
		(property "Reference" "D1"
			(at 0.805 -1.525 0)
			(unlocked yes)
			(layer "F.SilkS")
			(hide yes)
			(effects
				(font
					(size 0.7 0.7)
					(thickness 0.15)
				)
				(justify left bottom)
			)
		)
		(property "Value" "LED_G_0402_VLMTG1500-GS08"
			(at 0 1.5 180)
			(unlocked yes)
			(layer "F.Fab")
			(effects
				(font
					(size 0.7 0.7)
					(thickness 0.15)
				)
				(justify left bottom)
			)
		)
		(property "Datasheet" "https://www.vishay.com/docs/82554/vlmo1500.pdf"
			(at 0 0 180)
			(layer "F.Fab")
			(hide yes)
			(effects
				(font
					(size 1.27 1.27)
					(thickness 0.15)
				)
			)
		)
		(property "MPN" "VLMTG1500-GS08"
			(at 0 0 180)
			(unlocked yes)
			(layer "F.Fab")
			(hide yes)
			(effects
				(font
					(size 1 1)
					(thickness 0.15)
				)
			)
		)
		(property "Manufacturer" "Vishay"
			(at 0 0 180)
			(unlocked yes)
			(layer "F.Fab")
			(hide yes)
			(effects
				(font
					(size 1 1)
					(thickness 0.15)
				)
			)
		)
		(property "Color" "Green"
			(at 0 0 180)
			(unlocked yes)
			(layer "F.Fab")
			(hide yes)
			(effects
				(font
					(size 1 1)
					(thickness 0.15)
				)
			)
		)
		(property "Author" "Antmicro"
			(at 0 0 180)
			(unlocked yes)
			(layer "F.Fab")
			(hide yes)
			(effects
				(font
					(size 1 1)
					(thickness 0.15)
				)
			)
		)
		(property "License" "Apache-2.0"
			(at 0 0 180)
			(unlocked yes)
			(layer "F.Fab")
			(hide yes)
			(effects
				(font
					(size 1 1)
					(thickness 0.15)
				)
			)
		)
		(sheetname "/FPGA Config/")
		(sheetfile "fpga-config.kicad_sch")
		(attr smd)
		(fp_line
			(start -0.175 0.4)
			(end 0.175 0.4)
			(stroke
				(width 0.15)
				(type solid)
			)
			(layer "F.SilkS")
		)
		(fp_line
			(start -0.175 -0.4)
			(end 0.175 -0.4)
			(stroke
				(width 0.15)
				(type solid)
			)
			(layer "F.SilkS")
		)
		(fp_line
			(start -0.9 -0.4)
			(end -0.9 0.4)
			(stroke
				(width 0.15)
				(type solid)
			)
			(layer "F.SilkS")
		)
		(fp_rect
			(start -0.925 -0.47)
			(end 0.925 0.47)
			(stroke
				(width 0.05)
				(type default)
			)
			(fill no)
			(layer "F.CrtYd")
		)
		(fp_line
			(start 0.501 0.26)
			(end 0.501 -0.248)
			(stroke
				(width 0.15)
				(type solid)
			)
			(layer "F.Fab")
		)
		(fp_line
			(start 0.501 0.26)
			(end 0.501 -0.248)
			(stroke
				(width 0.15)
				(type solid)
			)
			(layer "F.Fab")
		)
		(fp_line
			(start 0.501 -0.248)
			(end 0.172 -0.248)
			(stroke
				(width 0.15)
				(type solid)
			)
			(layer "F.Fab")
		)
		(fp_line
			(start 0.501 -0.248)
			(end -0.489 -0.248)
			(stroke
				(width 0.15)
				(type solid)
			)
			(layer "F.Fab")
		)
		(fp_line
			(start 0.228 0.202)
			(end 0.228 0)
			(stroke
				(width 0.15)
				(type solid)
			)
			(layer "F.Fab")
		)
		(fp_line
			(start 0.228 0)
			(end 0.228 -0.202)
			(stroke
				(width 0.15)
				(type solid)
			)
			(layer "F.Fab")
		)
		(fp_line
			(start 0.228 -0.202)
			(end -0.074 0)
			(stroke
				(width 0.15)
				(type solid)
			)
			(layer "F.Fab")
		)
		(fp_line
			(start 0.172 0.26)
			(end 0.501 0.26)
			(stroke
				(width 0.15)
				(type solid)
			)
			(layer "F.Fab")
		)
		(fp_line
			(start 0.172 -0.248)
			(end 0.172 0.26)
			(stroke
				(width 0.15)
				(type solid)
			)
			(layer "F.Fab")
		)
		(fp_line
			(start -0.074 0)
			(end 0.228 0.202)
			(stroke
				(width 0.15)
				(type solid)
			)
			(layer "F.Fab")
		)
		(fp_line
			(start -0.158 0.26)
			(end -0.158 -0.248)
			(stroke
				(width 0.15)
				(type solid)
			)
			(layer "F.Fab")
		)
		(fp_line
			(start -0.158 -0.248)
			(end -0.489 -0.248)
			(stroke
				(width 0.15)
				(type solid)
			)
			(layer "F.Fab")
		)
		(fp_line
			(start -0.173 0.202)
			(end -0.173 0.102)
			(stroke
				(width 0.15)
				(type solid)
			)
			(layer "F.Fab")
		)
		(fp_line
			(start -0.173 -0.202)
			(end -0.173 0.102)
			(stroke
				(width 0.15)
				(type solid)
			)
			(layer "F.Fab")
		)
		(fp_line
			(start -0.489 0.26)
			(end 0.501 0.26)
			(stroke
				(width 0.15)
				(type solid)
			)
			(layer "F.Fab")
		)
		(fp_line
			(start -0.489 0.26)
			(end -0.158 0.26)
			(stroke
				(width 0.15)
				(type solid)
			)
			(layer "F.Fab")
		)
		(fp_line
			(start -0.489 -0.248)
			(end -0.489 0.26)
			(stroke
				(width 0.15)
				(type solid)
			)
			(layer "F.Fab")
		)
		(fp_line
			(start -0.489 -0.248)
			(end -0.489 0.26)
			(stroke
				(width 0.15)
				(type solid)
			)
			(layer "F.Fab")
		)
		(fp_text user "${REFERENCE}"
			(at 0 2.95 180)
			(unlocked yes)
			(layer "F.Fab")
			(effects
				(font
					(size 0.7 0.7)
					(thickness 0.15)
				)
				(justify left bottom)
			)
		)
		(fp_text user "License: Apache-2.0"
			(at 0 5.35 180)
			(layer "F.Fab")
			(effects
				(font
					(size 0.7 0.7)
					(thickness 0.15)
				)
				(justify left bottom)
			)
		)
		(fp_text user "Author: Antmicro"
			(at 0 4.15 180)
			(layer "F.Fab")
			(effects
				(font
					(size 0.7 0.7)
					(thickness 0.15)
				)
				(justify left bottom)
			)
		)
		(pad "1" smd roundrect
			(at -0.48 0 180)
			(size 0.59 0.64)
			(layers "F.Cu" "F.Mask" "F.Paste")
			(roundrect_rratio 0.25)
			(net 783 "Net-(D1-C)")
			(pinfunction "C")
			(pintype "passive")
		)
		(pad "2" smd roundrect
			(at 0.48 0 180)
			(size 0.59 0.64)
			(layers "F.Cu" "F.Mask" "F.Paste")
			(roundrect_rratio 0.25)
			(net 151 "+3V3")
			(pinfunction "A")
			(pintype "passive")
		)
	)
	(footprint "antmicro-footprints:C_0402_1005Metric"
		(layer "F.Cu")
		(at 244.25 186.349 -90)
		(descr "Capacitor SMD 0402")
		(tags "capacitor SMD 0402")
		(property "Reference" "C320"
			(at 0.226 -1.35 90)
			(layer "F.SilkS")
			(effects
				(font
					(size 0.7 0.7)
					(thickness 0.15)
				)
				(justify right bottom)
			)
		)
		(property "Value" "C_100n_0402"
			(at -1.022927 2.155213 90)
			(layer "F.Fab")
			(effects
				(font
					(size 0.7 0.7)
					(thickness 0.15)
				)
				(justify right bottom)
			)
		)
		(property "Datasheet" "https://www.murata.com/products/productdetail?partno=GRM155R61H104KE14%23"
			(at 0 0 270)
			(layer "F.Fab")
			(hide yes)
			(effects
				(font
					(size 1.27 1.27)
					(thickness 0.15)
				)
			)
		)
		(property "Manufacturer" "Murata"
			(at 0 0 270)
			(unlocked yes)
			(layer "F.Fab")
			(hide yes)
			(effects
				(font
					(size 1 1)
					(thickness 0.15)
				)
			)
		)
		(property "MPN" "GRM155R61H104KE14D"
			(at 0 0 270)
			(unlocked yes)
			(layer "F.Fab")
			(hide yes)
			(effects
				(font
					(size 1 1)
					(thickness 0.15)
				)
			)
		)
		(property "Val" "100n"
			(at 0 0 270)
			(unlocked yes)
			(layer "F.Fab")
			(hide yes)
			(effects
				(font
					(size 1 1)
					(thickness 0.15)
				)
			)
		)
		(property "License" "Apache-2.0"
			(at 0 0 270)
			(unlocked yes)
			(layer "F.Fab")
			(hide yes)
			(effects
				(font
					(size 1 1)
					(thickness 0.15)
				)
			)
		)
		(property "Author" "Antmicro"
			(at 0 0 270)
			(unlocked yes)
			(layer "F.Fab")
			(hide yes)
			(effects
				(font
					(size 1 1)
					(thickness 0.15)
				)
			)
		)
		(property "Voltage" "50V"
			(at 0 0 270)
			(unlocked yes)
			(layer "F.Fab")
			(hide yes)
			(effects
				(font
					(size 1 1)
					(thickness 0.15)
				)
			)
		)
		(property "Dielectric" "X5R"
			(at 0 0 270)
			(unlocked yes)
			(layer "F.Fab")
			(hide yes)
			(effects
				(font
					(size 1 1)
					(thickness 0.15)
				)
			)
		)
		(sheetname "/I^{2}C + I3C/")
		(sheetfile "i2c.kicad_sch")
		(attr smd)
		(fp_rect
			(start -0.925 -0.47)
			(end 0.925 0.47)
			(stroke
				(width 0.05)
				(type default)
			)
			(fill no)
			(layer "F.CrtYd")
		)
		(fp_line
			(start -0.494 0.248)
			(end -0.494 -0.25)
			(stroke
				(width 0.15)
				(type solid)
			)
			(layer "F.Fab")
		)
		(fp_line
			(start 0.504 0.248)
			(end -0.494 0.248)
			(stroke
				(width 0.15)
				(type solid)
			)
			(layer "F.Fab")
		)
		(fp_line
			(start -0.494 -0.25)
			(end 0.504 -0.25)
			(stroke
				(width 0.15)
				(type solid)
			)
			(layer "F.Fab")
		)
		(fp_line
			(start 0.504 -0.25)
			(end 0.504 0.248)
			(stroke
				(width 0.15)
				(type solid)
			)
			(layer "F.Fab")
		)
		(fp_text user "License: Apache-2.0"
			(at -0.939 5.799 270)
			(layer "F.Fab")
			(effects
				(font
					(size 0.7 0.7)
					(thickness 0.15)
				)
				(justify left bottom)
			)
		)
		(fp_text user "Author: Antmicro"
			(at -0.939 3.399 270)
			(layer "F.Fab")
			(effects
				(font
					(size 0.7 0.7)
					(thickness 0.15)
				)
				(justify left bottom)
			)
		)
		(fp_text user "${REFERENCE}"
			(at -0.939 4.599 270)
			(layer "F.Fab")
			(effects
				(font
					(size 0.7 0.7)
					(thickness 0.15)
				)
				(justify left bottom)
			)
		)
		(pad "1" smd roundrect
			(at -0.48 0 270)
			(size 0.59 0.64)
			(layers "F.Cu" "F.Mask" "F.Paste")
			(roundrect_rratio 0.25)
			(net 774 "Net-(U49-EN)")
			(pintype "passive")
		)
		(pad "2" smd roundrect
			(at 0.48 0 270)
			(size 0.59 0.64)
			(layers "F.Cu" "F.Mask" "F.Paste")
			(roundrect_rratio 0.25)
			(net 1 "GND")
			(pintype "passive")
		)
	)
	(footprint "antmicro-footprints:Vishay_PowerPAK_1212-8_Single"
		(layer "F.Cu")
		(at 149.78 190.955 -90)
		(descr "PowerPAK 1212-8 Single")
		(tags "Vishay PowerPAK 1212-8 Single")
		(property "Reference" "Q13"
			(at -2.255 -1.57 180)
			(layer "F.SilkS")
			(effects
				(font
					(size 0.7 0.7)
					(thickness 0.15)
				)
				(justify right bottom)
			)
		)
		(property "Value" "SI7613DN-T1-GE3"
			(at 0 2.7 90)
			(layer "F.Fab")
			(hide yes)
			(effects
				(font
					(size 0.7 0.7)
					(thickness 0.15)
				)
				(justify right bottom)
			)
		)
		(property "Datasheet" "https://www.vishay.com/docs/64809/si7613dn.pdf"
			(at 0 0 270)
			(layer "F.Fab")
			(hide yes)
			(effects
				(font
					(size 1.27 1.27)
					(thickness 0.15)
				)
			)
		)
		(property "MPN" "SI7613DN-T1-GE3"
			(at 0 0 270)
			(unlocked yes)
			(layer "F.Fab")
			(hide yes)
			(effects
				(font
					(size 1 1)
					(thickness 0.15)
				)
			)
		)
		(property "Manufacturer" "Vishay"
			(at 0 0 270)
			(unlocked yes)
			(layer "F.Fab")
			(hide yes)
			(effects
				(font
					(size 1 1)
					(thickness 0.15)
				)
			)
		)
		(property "Author" "Antmicro"
			(at 0 0 270)
			(unlocked yes)
			(layer "F.Fab")
			(hide yes)
			(effects
				(font
					(size 1 1)
					(thickness 0.15)
				)
			)
		)
		(property "License" "Apache-2.0"
			(at 0 0 270)
			(unlocked yes)
			(layer "F.Fab")
			(hide yes)
			(effects
				(font
					(size 1 1)
					(thickness 0.15)
				)
			)
		)
		(sheetname "/Supply/")
		(sheetfile "supply.kicad_sch")
		(attr smd)
		(fp_line
			(start -1.635 1.634)
			(end 1.634 1.634)
			(stroke
				(width 0.15)
				(type solid)
			)
			(layer "F.SilkS")
		)
		(fp_line
			(start -1.635 1.3)
			(end -1.635 1.634)
			(stroke
				(width 0.15)
				(type solid)
			)
			(layer "F.SilkS")
		)
		(fp_line
			(start 1.634 1.3)
			(end 1.634 1.634)
			(stroke
				(width 0.15)
				(type solid)
			)
			(layer "F.SilkS")
		)
		(fp_line
			(start -1.651 -1.651)
			(end -1.651 -1.317)
			(stroke
				(width 0.15)
				(type solid)
			)
			(layer "F.SilkS")
		)
		(fp_line
			(start -1.651 -1.651)
			(end 1.648 -1.651)
			(stroke
				(width 0.15)
				(type solid)
			)
			(layer "F.SilkS")
		)
		(fp_line
			(start 1.648 -1.651)
			(end 1.648 -1.317)
			(stroke
				(width 0.15)
				(type solid)
			)
			(layer "F.SilkS")
		)
		(fp_circle
			(center -1.9 -1.4)
			(end -1.85 -1.4)
			(stroke
				(width 0.15)
				(type solid)
			)
			(fill yes)
			(layer "F.SilkS")
		)
		(fp_rect
			(start -2 -1.8)
			(end 2 1.798)
			(stroke
				(width 0.05)
				(type solid)
			)
			(fill no)
			(layer "F.CrtYd")
		)
		(fp_line
			(start -1.6425 -1.4175)
			(end -1.4175 -1.6425)
			(stroke
				(width 0.15)
				(type solid)
			)
			(layer "F.Fab")
		)
		(fp_rect
			(start -1.651 -1.651)
			(end 1.648 1.648)
			(stroke
				(width 0.15)
				(type solid)
			)
			(fill no)
			(layer "F.Fab")
		)
		(fp_text user "Author: Antmicro"
			(at -8 5.9 270)
			(layer "F.Fab")
			(effects
				(font
					(size 0.7 0.7)
					(thickness 0.15)
				)
				(justify left bottom)
			)
		)
		(fp_text user "${REFERENCE}"
			(at -8 4.7 270)
			(layer "F.Fab")
			(effects
				(font
					(size 0.7 0.7)
					(thickness 0.15)
				)
				(justify left bottom)
			)
		)
		(fp_text user "License: Apache-2.0"
			(at -8 7.1 270)
			(layer "F.Fab")
			(effects
				(font
					(size 0.7 0.7)
					(thickness 0.15)
				)
				(justify left bottom)
			)
		)
		(pad "1" smd rect
			(at -1.436 -0.99 270)
			(size 0.99 0.405)
			(layers "F.Cu" "F.Mask" "F.Paste")
			(net 35 "VDC")
			(pinfunction "S")
			(pintype "passive")
		)
		(pad "2" smd rect
			(at -1.436 -0.332 270)
			(size 0.99 0.405)
			(layers "F.Cu" "F.Mask" "F.Paste")
			(net 35 "VDC")
			(pinfunction "S")
			(pintype "passive")
		)
		(pad "3" smd rect
			(at -1.436 0.33 270)
			(size 0.99 0.405)
			(layers "F.Cu" "F.Mask" "F.Paste")
			(net 35 "VDC")
			(pinfunction "S")
			(pintype "passive")
		)
		(pad "4" smd rect
			(at -1.436 0.988 270)
			(size 0.99 0.405)
			(layers "F.Cu" "F.Mask" "F.Paste")
			(net 285 "Net-(Q13-G)")
			(pinfunction "G")
			(pintype "passive")
		)
		(pad "5" smd custom
			(at 0.557 0 270)
			(size 1.725 2.235)
			(layers "F.Cu" "F.Mask" "F.Paste")
			(net 324 "/Supply/12V_PCIE_fused")
			(pinfunction "D")
			(pintype "passive")
			(zone_connect 2)
			(options
				(clearance outline)
				(anchor rect)
			)
			(primitives
				(gr_poly
					(pts
						(xy 0.8625 0.1275) (xy 0.8625 -0.1275) (xy 1.3725 -0.1275) (xy 1.3725 -0.5325) (xy 0.8625 -0.5325)
						(xy 0.8625 -0.7875) (xy 1.3725 -0.7875) (xy 1.3725 -1.195) (xy 0.6125 -1.195) (xy 0.6125 1.195)
						(xy 1.3725 1.195) (xy 1.3725 0.7875) (xy 0.8625 0.7875) (xy 0.8625 0.5325) (xy 1.3725 0.5325)
						(xy 1.3725 0.1275)
					)
					(width 0)
					(fill yes)
				)
			)
		)
	)
	(footprint "antmicro-footprints:R_0402_1005Metric"
		(layer "F.Cu")
		(at 252.785 146.65 180)
		(descr "Resistor SMD 0402")
		(tags "resistor SMD 0402")
		(property "Reference" "R61"
			(at -1.122484 -1.35 0)
			(layer "F.SilkS")
			(effects
				(font
					(size 0.7 0.7)
					(thickness 0.15)
				)
				(justify right bottom)
			)
		)
		(property "Value" "R_330R_0402"
			(at -1.011843 1.772047 0)
			(layer "F.Fab")
			(effects
				(font
					(size 0.7 0.7)
					(thickness 0.15)
				)
				(justify right bottom)
			)
		)
		(property "Datasheet" "https://www.bourns.com/docs/product-datasheets/cr.pdf"
			(at 0 0 180)
			(layer "F.Fab")
			(hide yes)
			(effects
				(font
					(size 1.27 1.27)
					(thickness 0.15)
				)
			)
		)
		(property "Manufacturer" "Bourns"
			(at 0 0 180)
			(unlocked yes)
			(layer "F.Fab")
			(hide yes)
			(effects
				(font
					(size 1 1)
					(thickness 0.15)
				)
			)
		)
		(property "MPN" "CR0402-FX-3300GLF"
			(at 0 0 180)
			(unlocked yes)
			(layer "F.Fab")
			(hide yes)
			(effects
				(font
					(size 1 1)
					(thickness 0.15)
				)
			)
		)
		(property "Val" "330R"
			(at 0 0 180)
			(unlocked yes)
			(layer "F.Fab")
			(hide yes)
			(effects
				(font
					(size 1 1)
					(thickness 0.15)
				)
			)
		)
		(property "License" "Apache-2.0"
			(at 0 0 180)
			(unlocked yes)
			(layer "F.Fab")
			(hide yes)
			(effects
				(font
					(size 1 1)
					(thickness 0.15)
				)
			)
		)
		(property "Author" "Antmicro"
			(at 0 0 180)
			(unlocked yes)
			(layer "F.Fab")
			(hide yes)
			(effects
				(font
					(size 1 1)
					(thickness 0.15)
				)
			)
		)
		(property "Tolerance" "1%"
			(at 0 0 180)
			(unlocked yes)
			(layer "F.Fab")
			(hide yes)
			(effects
				(font
					(size 1 1)
					(thickness 0.15)
				)
			)
		)
		(sheetname "/DDR5 RDIMM/")
		(sheetfile "ddr5-rdimm.kicad_sch")
		(attr smd)
		(fp_rect
			(start -0.925 -0.47)
			(end 0.925 0.47)
			(stroke
				(width 0.05)
				(type default)
			)
			(fill no)
			(layer "F.CrtYd")
		)
		(fp_rect
			(start -0.5 -0.25)
			(end 0.5 0.25)
			(stroke
				(width 0.15)
				(type solid)
			)
			(fill no)
			(layer "F.Fab")
		)
		(fp_text user "${REFERENCE}"
			(at -0.95 3.168 180)
			(layer "F.Fab")
			(effects
				(font
					(size 0.7 0.7)
					(thickness 0.15)
				)
				(justify left bottom)
			)
		)
		(fp_text user "License: Apache-2.0"
			(at -0.95 5.169 180)
			(layer "F.Fab")
			(effects
				(font
					(size 0.7 0.7)
					(thickness 0.15)
				)
				(justify left bottom)
			)
		)
		(fp_text user "Author: Antmicro"
			(at -0.95 4.169 180)
			(layer "F.Fab")
			(effects
				(font
					(size 0.7 0.7)
					(thickness 0.15)
				)
				(justify left bottom)
			)
		)
		(pad "1" smd roundrect
			(at -0.48 0 180)
			(size 0.59 0.64)
			(layers "F.Cu" "F.Mask" "F.Paste")
			(roundrect_rratio 0.25)
			(net 237 "Net-(D20-C_{Y})")
			(pintype "passive")
		)
		(pad "2" smd roundrect
			(at 0.48 0 180)
			(size 0.59 0.64)
			(layers "F.Cu" "F.Mask" "F.Paste")
			(roundrect_rratio 0.25)
			(net 277 "Net-(Q9-D)")
			(pintype "passive")
		)
	)
	(footprint "antmicro-footprints:NetTie-2_SMD_Pad0.127mm"
		(layer "F.Cu")
		(at 257.727 162.423998)
		(descr "Net tie, 2 pin, 0.127mm  SMD pads")
		(tags "net tie")
		(property "Reference" "NT8"
			(at -0.128 -1.345 0)
			(layer "F.SilkS")
			(hide yes)
			(effects
				(font
					(size 0.7 0.7)
					(thickness 0.15)
				)
				(justify left bottom)
			)
		)
		(property "Value" "Net-Tie_P0.127mm"
			(at 0 1.199 0)
			(layer "F.Fab")
			(effects
				(font
					(size 0.7 0.7)
					(thickness 0.15)
				)
				(justify left bottom)
			)
		)
		(property "MPN" ""
			(at 0 0 0)
			(unlocked yes)
			(layer "F.Fab")
			(hide yes)
			(effects
				(font
					(size 1 1)
					(thickness 0.15)
				)
			)
		)
		(property "Manufacturer" ""
			(at 0 0 0)
			(unlocked yes)
			(layer "F.Fab")
			(hide yes)
			(effects
				(font
					(size 1 1)
					(thickness 0.15)
				)
			)
		)
		(property "Author" "Antmicro"
			(at 0 0 0)
			(unlocked yes)
			(layer "F.Fab")
			(hide yes)
			(effects
				(font
					(size 1 1)
					(thickness 0.15)
				)
			)
		)
		(property "License" "Apache-2.0"
			(at 0 0 0)
			(unlocked yes)
			(layer "F.Fab")
			(hide yes)
			(effects
				(font
					(size 1 1)
					(thickness 0.15)
				)
			)
		)
		(property ki_fp_filters "Net*Tie*")
		(sheetname "/Supply/DC-DC IO/")
		(sheetfile "dc-dc-io.kicad_sch")
		(attr through_hole exclude_from_pos_files exclude_from_bom)
		(net_tie_pad_groups "1, 2")
		(fp_poly
			(pts
				(xy -0.0635 -0.0635) (xy 0.0625 -0.0635) (xy 0.0625 0.0635) (xy -0.0635 0.0635)
			)
			(stroke
				(width 0)
				(type solid)
			)
			(fill yes)
			(layer "F.Cu")
		)
		(fp_poly
			(pts
				(xy 0.2 -0.16) (xy 0.29 -0.07) (xy 0.29 0.07) (xy 0.2 0.16) (xy -0.2 0.16) (xy -0.29 0.07) (xy -0.29 -0.06)
				(xy -0.19 -0.16)
			)
			(stroke
				(width 0.05)
				(type solid)
			)
			(fill no)
			(layer "F.CrtYd")
		)
		(fp_text user "Author: Antmicro"
			(at -0.128 4.4 0)
			(layer "F.Fab")
			(effects
				(font
					(size 0.7 0.7)
					(thickness 0.15)
				)
				(justify left bottom)
			)
		)
		(fp_text user "${REFERENCE}"
			(at -0.128 3.2 0)
			(layer "F.Fab")
			(effects
				(font
					(size 0.7 0.7)
					(thickness 0.15)
				)
				(justify left bottom)
			)
		)
		(fp_text user "License: Apache-2.0"
			(at -0.128 5.6 0)
			(layer "F.Fab")
			(effects
				(font
					(size 0.7 0.7)
					(thickness 0.15)
				)
				(justify left bottom)
			)
		)
		(pad "1" smd roundrect
			(at -0.127 0 180)
			(size 0.127 0.127)
			(layers "F.Cu")
			(roundrect_rratio 0.5)
			(chamfer_ratio 0)
			(chamfer top_left bottom_left)
			(net 688 "/Supply/DC-DC IO/1V2_SEN_+")
			(pinfunction "1")
			(pintype "passive")
		)
		(pad "2" smd roundrect
			(at 0.126 0)
			(size 0.127 0.127)
			(layers "F.Cu")
			(roundrect_rratio 0.5)
			(chamfer_ratio 0)
			(chamfer top_left bottom_left)
			(net 159 "/Supply/DC-DC IO/1V2_local")
			(pinfunction "2")
			(pintype "passive")
		)
	)
	(footprint "antmicro-footprints:DHVQFN-14-1EP_2.5x3mm"
		(layer "F.Cu")
		(at 147.775499 170.134 -90)
		(property "Reference" "U13"
			(at 1.915 4.151 0)
			(layer "F.SilkS")
			(effects
				(font
					(size 0.7 0.7)
					(thickness 0.15)
				)
				(justify left bottom)
			)
		)
		(property "Value" "TXU0304BQAR"
			(at 0 2.898 90)
			(layer "F.Fab")
			(effects
				(font
					(size 0.7 0.7)
					(thickness 0.15)
				)
				(justify right bottom)
			)
		)
		(property "Datasheet" "https://www.ti.com/lit/ds/symlink/txu0304.pdf?ts=1637748643258&ref_url=https%253A%252F%252Fwww.ti.com%252Fproduct%252FTXU0304"
			(at 0 0 270)
			(layer "F.Fab")
			(hide yes)
			(effects
				(font
					(size 1.27 1.27)
					(thickness 0.15)
				)
			)
		)
		(property "MPN" "TXU0304BQAR"
			(at 0 0 270)
			(unlocked yes)
			(layer "F.Fab")
			(hide yes)
			(effects
				(font
					(size 1 1)
					(thickness 0.15)
				)
			)
		)
		(property "Manufacturer" "Texas Instruments"
			(at 0 0 270)
			(unlocked yes)
			(layer "F.Fab")
			(hide yes)
			(effects
				(font
					(size 1 1)
					(thickness 0.15)
				)
			)
		)
		(property "Author" "Antmicro"
			(at 0 0 270)
			(unlocked yes)
			(layer "F.Fab")
			(hide yes)
			(effects
				(font
					(size 1 1)
					(thickness 0.15)
				)
			)
		)
		(property "License" "Apache-2.0"
			(at 0 0 270)
			(unlocked yes)
			(layer "F.Fab")
			(hide yes)
			(effects
				(font
					(size 1 1)
					(thickness 0.15)
				)
			)
		)
		(sheetname "/Debug FTDI + VNA/")
		(sheetfile "debug-ftdi.kicad_sch")
		(attr smd)
		(fp_line
			(start -1.35 1.6)
			(end -0.5 1.6)
			(stroke
				(width 0.15)
				(type solid)
			)
			(layer "F.SilkS")
		)
		(fp_line
			(start -1.35 1.6)
			(end -1.35 1.25)
			(stroke
				(width 0.15)
				(type solid)
			)
			(layer "F.SilkS")
		)
		(fp_line
			(start 0.5 1.6)
			(end 1.35 1.6)
			(stroke
				(width 0.15)
				(type solid)
			)
			(layer "F.SilkS")
		)
		(fp_line
			(start 1.35 1.6)
			(end 1.35 1.25)
			(stroke
				(width 0.15)
				(type solid)
			)
			(layer "F.SilkS")
		)
		(fp_line
			(start -1.35 -1.6)
			(end -1.35 -1.25)
			(stroke
				(width 0.15)
				(type solid)
			)
			(layer "F.SilkS")
		)
		(fp_line
			(start -1.35 -1.6)
			(end -0.5 -1.6)
			(stroke
				(width 0.15)
				(type solid)
			)
			(layer "F.SilkS")
		)
		(fp_line
			(start 1.35 -1.6)
			(end 1.35 -1.25)
			(stroke
				(width 0.15)
				(type solid)
			)
			(layer "F.SilkS")
		)
		(fp_line
			(start 1.35 -1.6)
			(end 0.5 -1.6)
			(stroke
				(width 0.15)
				(type solid)
			)
			(layer "F.SilkS")
		)
		(fp_circle
			(center -0.7 -1.85)
			(end -0.65 -1.85)
			(stroke
				(width 0.15)
				(type solid)
			)
			(fill yes)
			(layer "F.SilkS")
		)
		(fp_rect
			(start -1.8 -2)
			(end 1.8 2)
			(stroke
				(width 0.05)
				(type solid)
			)
			(fill no)
			(layer "F.CrtYd")
		)
		(fp_line
			(start -1.25 1.499)
			(end -1.25 -1.25)
			(stroke
				(width 0.15)
				(type solid)
			)
			(layer "F.Fab")
		)
		(fp_line
			(start 1.249 1.499)
			(end -1.25 1.499)
			(stroke
				(width 0.15)
				(type solid)
			)
			(layer "F.Fab")
		)
		(fp_line
			(start -1.25 -1.25)
			(end -1 -1.5)
			(stroke
				(width 0.15)
				(type solid)
			)
			(layer "F.Fab")
		)
		(fp_line
			(start -1 -1.5)
			(end 1.249 -1.5)
			(stroke
				(width 0.15)
				(type solid)
			)
			(layer "F.Fab")
		)
		(fp_line
			(start 1.249 -1.5)
			(end 1.249 1.499)
			(stroke
				(width 0.15)
				(type solid)
			)
			(layer "F.Fab")
		)
		(fp_text user "License: Apache-2.0"
			(at -1.841 6.097 270)
			(layer "F.Fab")
			(effects
				(font
					(size 0.7 0.7)
					(thickness 0.15)
				)
				(justify left bottom)
			)
		)
		(fp_text user "Author: Antmicro"
			(at -1.841 7.296 270)
			(layer "F.Fab")
			(effects
				(font
					(size 0.7 0.7)
					(thickness 0.15)
				)
				(justify left bottom)
			)
		)
		(fp_text user "${REFERENCE}"
			(at -1.841 4.897 270)
			(layer "F.Fab")
			(effects
				(font
					(size 0.7 0.7)
					(thickness 0.15)
				)
				(justify left bottom)
			)
		)
		(pad "1" smd oval
			(at -0.25 -1.5 270)
			(size 0.3 0.8)
			(layers "F.Cu" "F.Mask" "F.Paste")
			(net 6 "/Debug FTDI + VNA/FTDI_3V3")
			(pinfunction "VCCA")
			(pintype "power_in")
		)
		(pad "2" smd oval
			(at -1.25 -1)
			(size 0.3 0.8)
			(layers "F.Cu" "F.Mask" "F.Paste")
			(net 379 "/Debug FTDI + VNA/BDBUS0")
			(pinfunction "A1")
			(pintype "input")
		)
		(pad "3" smd oval
			(at -1.25 -0.5)
			(size 0.3 0.8)
			(layers "F.Cu" "F.Mask" "F.Paste")
			(net 1 "GND")
			(pinfunction "A2")
			(pintype "input")
		)
		(pad "4" smd oval
			(at -1.25 0)
			(size 0.3 0.8)
			(layers "F.Cu" "F.Mask" "F.Paste")
			(net 390 "/Debug FTDI + VNA/BDBUS1")
			(pinfunction "A3")
			(pintype "input")
		)
		(pad "5" smd oval
			(at -1.25 0.5)
			(size 0.3 0.8)
			(layers "F.Cu" "F.Mask" "F.Paste")
			(net 392 "/Debug FTDI + VNA/BDBUS2")
			(pinfunction "A4Y")
			(pintype "output")
		)
		(pad "6" smd oval
			(at -1.25 1)
			(size 0.3 0.8)
			(layers "F.Cu" "F.Mask" "F.Paste")
			(net 422 "unconnected-(U13-NC-Pad6)")
			(pinfunction "NC")
			(pintype "no_connect")
		)
		(pad "7" smd oval
			(at -0.25 1.5 270)
			(size 0.3 0.8)
			(layers "F.Cu" "F.Mask" "F.Paste")
			(net 1 "GND")
			(pinfunction "GND")
			(pintype "passive")
		)
		(pad "8" smd oval
			(at 0.25 1.5 270)
			(size 0.3 0.8)
			(layers "F.Cu" "F.Mask" "F.Paste")
			(net 301 "Net-(U13-OE)")
			(pinfunction "OE")
			(pintype "tri_state")
		)
		(pad "9" smd oval
			(at 1.25 1)
			(size 0.3 0.8)
			(layers "F.Cu" "F.Mask" "F.Paste")
			(net 423 "unconnected-(U13-NC-Pad9)")
			(pinfunction "NC")
			(pintype "no_connect")
		)
		(pad "10" smd oval
			(at 1.25 0.5)
			(size 0.3 0.8)
			(layers "F.Cu" "F.Mask" "F.Paste")
			(net 139 "/Debug FTDI + VNA/FTDI_SDA_IN")
			(pinfunction "B4")
			(pintype "input")
		)
		(pad "11" smd oval
			(at 1.25 0)
			(size 0.3 0.8)
			(layers "F.Cu" "F.Mask" "F.Paste")
			(net 44 "/Debug FTDI + VNA/FTDI_SDA_OUT")
			(pinfunction "B3Y")
			(pintype "output")
		)
		(pad "12" smd oval
			(at 1.25 -0.5)
			(size 0.3 0.8)
			(layers "F.Cu" "F.Mask" "F.Paste")
			(net 424 "unconnected-(U13-B2Y-Pad12)")
			(pinfunction "B2Y")
			(pintype "output+no_connect")
		)
		(pad "13" smd oval
			(at 1.25 -1)
			(size 0.3 0.8)
			(layers "F.Cu" "F.Mask" "F.Paste")
			(net 447 "/Debug FTDI + VNA/FTDI_SCL")
			(pinfunction "B1Y")
			(pintype "output")
		)
		(pad "14" smd oval
			(at 0.25 -1.5 270)
			(size 0.3 0.8)
			(layers "F.Cu" "F.Mask" "F.Paste")
			(net 38 "+3V3_AON")
			(pinfunction "VCCB")
			(pintype "power_in")
		)
		(pad "15" smd rect
			(at 0 0 270)
			(size 1 1.5)
			(layers "F.Cu" "F.Mask" "F.Paste")
			(net 1 "GND")
			(pinfunction "GND")
			(pintype "power_in")
		)
	)
	(footprint "antmicro-footprints:DFN-10-1EP_3x3mm"
		(layer "F.Cu")
		(at 239.274499 175.75)
		(property "Reference" "U3"
			(at -1.049499 3.025 0)
			(layer "F.SilkS")
			(effects
				(font
					(size 0.7 0.7)
					(thickness 0.15)
				)
				(justify left bottom)
			)
		)
		(property "Value" "PAC1720-1"
			(at 0 2.8 0)
			(layer "F.Fab")
			(effects
				(font
					(size 0.7 0.7)
					(thickness 0.15)
				)
				(justify left bottom)
			)
		)
		(property "Datasheet" "https://ww1.microchip.com/downloads/aemDocuments/documents/MSLD/ProductDocuments/DataSheets/PAC1710-PAC1720-Data-Sheet-DS20005386.pdf"
			(at 0 0 0)
			(layer "F.Fab")
			(hide yes)
			(effects
				(font
					(size 1.27 1.27)
					(thickness 0.15)
				)
			)
		)
		(property "MPN" "PAC1720-1-AIA-TR"
			(at 0 0 0)
			(unlocked yes)
			(layer "F.Fab")
			(hide yes)
			(effects
				(font
					(size 1 1)
					(thickness 0.15)
				)
			)
		)
		(property "Manufacturer" "Microchip Technology"
			(at 0 0 0)
			(unlocked yes)
			(layer "F.Fab")
			(hide yes)
			(effects
				(font
					(size 1 1)
					(thickness 0.15)
				)
			)
		)
		(property "Author" "Antmicro"
			(at 0 0 0)
			(unlocked yes)
			(layer "F.Fab")
			(hide yes)
			(effects
				(font
					(size 1 1)
					(thickness 0.15)
				)
			)
		)
		(property "License" "Apache-2.0"
			(at 0 0 0)
			(unlocked yes)
			(layer "F.Fab")
			(hide yes)
			(effects
				(font
					(size 1 1)
					(thickness 0.15)
				)
			)
		)
		(property ki_fp_filters "UQFN*1EP*4x4mm*P0.65mm*")
		(sheetname "/Supply/DC-DC AUX, MGT/")
		(sheetfile "dc-dc-aux-mgt.kicad_sch")
		(attr smd)
		(fp_line
			(start -1.624 -1.226)
			(end -1.773 -1.226)
			(stroke
				(width 0.15)
				(type solid)
			)
			(layer "F.SilkS")
		)
		(fp_line
			(start -1.6 1.6)
			(end -1.6 1.35)
			(stroke
				(width 0.15)
				(type solid)
			)
			(layer "F.SilkS")
		)
		(fp_line
			(start -1.6 1.6)
			(end -1.35 1.6)
			(stroke
				(width 0.15)
				(type solid)
			)
			(layer "F.SilkS")
		)
		(fp_line
			(start -1.249 -1.601)
			(end -1.624 -1.226)
			(stroke
				(width 0.15)
				(type solid)
			)
			(layer "F.SilkS")
		)
		(fp_line
			(start -1.249 -1.601)
			(end -0.824 -1.601)
			(stroke
				(width 0.15)
				(type solid)
			)
			(layer "F.SilkS")
		)
		(fp_line
			(start 1.601 -1.601)
			(end 1.351 -1.601)
			(stroke
				(width 0.15)
				(type solid)
			)
			(layer "F.SilkS")
		)
		(fp_line
			(start 1.601 -1.601)
			(end 1.601 -1.401)
			(stroke
				(width 0.15)
				(type solid)
			)
			(layer "F.SilkS")
		)
		(fp_line
			(start 1.601 1.6)
			(end 1.401 1.6)
			(stroke
				(width 0.15)
				(type solid)
			)
			(layer "F.SilkS")
		)
		(fp_line
			(start 1.601 1.6)
			(end 1.601 1.35)
			(stroke
				(width 0.15)
				(type solid)
			)
			(layer "F.SilkS")
		)
		(fp_circle
			(center -1.8 -1.6)
			(end -1.8 -1.551)
			(stroke
				(width 0.15)
				(type solid)
			)
			(fill yes)
			(layer "F.SilkS")
		)
		(fp_line
			(start -1.91 -1.73)
			(end 1.89 -1.73)
			(stroke
				(width 0.05)
				(type solid)
			)
			(layer "F.CrtYd")
		)
		(fp_line
			(start -1.91 1.75)
			(end -1.91 -1.73)
			(stroke
				(width 0.05)
				(type solid)
			)
			(layer "F.CrtYd")
		)
		(fp_line
			(start 1.89 1.75)
			(end -1.91 1.75)
			(stroke
				(width 0.05)
				(type solid)
			)
			(layer "F.CrtYd")
		)
		(fp_line
			(start 1.89 1.75)
			(end 1.89 -1.73)
			(stroke
				(width 0.05)
				(type solid)
			)
			(layer "F.CrtYd")
		)
		(fp_line
			(start -1.499 -1.18)
			(end -1.179 -1.5)
			(stroke
				(width 0.15)
				(type solid)
			)
			(layer "F.Fab")
		)
		(fp_line
			(start -1.499 1.499)
			(end -1.499 -1.176)
			(stroke
				(width 0.15)
				(type solid)
			)
			(layer "F.Fab")
		)
		(fp_line
			(start 1.5 -1.5)
			(end -1.175 -1.5)
			(stroke
				(width 0.15)
				(type solid)
			)
			(layer "F.Fab")
		)
		(fp_line
			(start 1.5 -1.5)
			(end 1.5 1.499)
			(stroke
				(width 0.15)
				(type solid)
			)
			(layer "F.Fab")
		)
		(fp_line
			(start 1.5 1.499)
			(end -1.499 1.499)
			(stroke
				(width 0.15)
				(type solid)
			)
			(layer "F.Fab")
		)
		(fp_text user "Author: Antmicro"
			(at -1.75 7.2 0)
			(layer "F.Fab")
			(effects
				(font
					(size 0.7 0.7)
					(thickness 0.15)
				)
				(justify left bottom)
			)
		)
		(fp_text user "${REFERENCE}"
			(at -1.75 5.999 0)
			(layer "F.Fab")
			(effects
				(font
					(size 0.7 0.7)
					(thickness 0.15)
				)
				(justify left bottom)
			)
		)
		(fp_text user "License: Apache-2.0"
			(at -1.75 8.4 0)
			(layer "F.Fab")
			(effects
				(font
					(size 0.7 0.7)
					(thickness 0.15)
				)
				(justify left bottom)
			)
		)
		(pad "1" smd roundrect
			(at -1.425 -1 270)
			(size 0.25 0.7)
			(layers "F.Cu" "F.Mask" "F.Paste")
			(roundrect_rratio 0.25)
			(net 681 "/Supply/DC-DC AUX, MGT/1V8_SEN_+")
			(pinfunction "IN1+")
			(pintype "input")
		)
		(pad "2" smd roundrect
			(at -1.425 -0.5 270)
			(size 0.25 0.7)
			(layers "F.Cu" "F.Mask" "F.Paste")
			(roundrect_rratio 0.25)
			(net 689 "/Supply/DC-DC AUX, MGT/1V8_SEN_-")
			(pinfunction "IN1-")
			(pintype "input")
		)
		(pad "3" smd roundrect
			(at -1.425 0 270)
			(size 0.25 0.7)
			(layers "F.Cu" "F.Mask" "F.Paste")
			(roundrect_rratio 0.25)
			(net 684 "/Supply/DC-DC AUX, MGT/MGTAVCCAUX_SEN_+")
			(pinfunction "IN2+")
			(pintype "input")
		)
		(pad "4" smd roundrect
			(at -1.425 0.498 270)
			(size 0.25 0.7)
			(layers "F.Cu" "F.Mask" "F.Paste")
			(roundrect_rratio 0.25)
			(net 692 "/Supply/DC-DC AUX, MGT/MGTAVCCAUX_SEN_-")
			(pinfunction "IN2-")
			(pintype "input")
		)
		(pad "5" smd roundrect
			(at -1.425 0.998 270)
			(size 0.25 0.7)
			(layers "F.Cu" "F.Mask" "F.Paste")
			(roundrect_rratio 0.25)
			(net 1 "GND")
			(pinfunction "GND")
			(pintype "power_in")
		)
		(pad "6" smd roundrect
			(at 1.426 0.998 270)
			(size 0.25 0.7)
			(layers "F.Cu" "F.Mask" "F.Paste")
			(roundrect_rratio 0.25)
			(net 729 "Net-(U3-ADDRSEL)")
			(pinfunction "ADDRSEL")
			(pintype "bidirectional")
		)
		(pad "7" smd roundrect
			(at 1.426 0.498 270)
			(size 0.25 0.7)
			(layers "F.Cu" "F.Mask" "F.Paste")
			(roundrect_rratio 0.25)
			(net 711 "Net-(U3-~{ALERT})")
			(pinfunction "~{ALERT}")
			(pintype "bidirectional")
		)
		(pad "8" smd roundrect
			(at 1.426 0 270)
			(size 0.25 0.7)
			(layers "F.Cu" "F.Mask" "F.Paste")
			(roundrect_rratio 0.25)
			(net 533 "/I^{2}C + I3C/PWR.SDA")
			(pinfunction "SDA")
			(pintype "bidirectional")
		)
		(pad "9" smd roundrect
			(at 1.426 -0.5 270)
			(size 0.25 0.7)
			(layers "F.Cu" "F.Mask" "F.Paste")
			(roundrect_rratio 0.25)
			(net 749 "/I^{2}C + I3C/PWR.SCL")
			(pinfunction "SCL")
			(pintype "input")
		)
		(pad "10" smd roundrect
			(at 1.426 -1 270)
			(size 0.25 0.7)
			(layers "F.Cu" "F.Mask" "F.Paste")
			(roundrect_rratio 0.25)
			(net 38 "+3V3_AON")
			(pinfunction "VDD")
			(pintype "power_in")
		)
		(pad "11" smd roundrect
			(at 0 0 270)
			(size 2.38 1.65)
			(layers "F.Cu" "F.Mask" "F.Paste")
			(roundrect_rratio 0.05)
			(net 1 "GND")
			(pinfunction "EP")
			(pintype "passive")
		)
	)
	(footprint "antmicro-footprints:C_0603_1608Metric"
		(layer "F.Cu")
		(at 221.955 170.109999 180)
		(descr "Capacitor SMD 0603")
		(tags "capacitor 0603")
		(property "Reference" "C220"
			(at -3.42 -3.015001 0)
			(layer "F.SilkS")
			(effects
				(font
					(size 0.7 0.7)
					(thickness 0.15)
				)
				(justify right bottom)
			)
		)
		(property "Value" "C_22u_0603"
			(at -1.42757 1.770288 0)
			(layer "F.Fab")
			(effects
				(font
					(size 0.7 0.7)
					(thickness 0.15)
				)
				(justify right bottom)
			)
		)
		(property "Datasheet" "https://www.murata.com/products/productdetail?partno=GRM188R60J226MEA0%23"
			(at 0 0 180)
			(layer "F.Fab")
			(hide yes)
			(effects
				(font
					(size 1.27 1.27)
					(thickness 0.15)
				)
			)
		)
		(property "Manufacturer" "Murata"
			(at 0 0 180)
			(unlocked yes)
			(layer "F.Fab")
			(hide yes)
			(effects
				(font
					(size 1 1)
					(thickness 0.15)
				)
			)
		)
		(property "MPN" "GRM188R60J226MEA0D"
			(at 0 0 180)
			(unlocked yes)
			(layer "F.Fab")
			(hide yes)
			(effects
				(font
					(size 1 1)
					(thickness 0.15)
				)
			)
		)
		(property "Val" "22u"
			(at 0 0 180)
			(unlocked yes)
			(layer "F.Fab")
			(hide yes)
			(effects
				(font
					(size 1 1)
					(thickness 0.15)
				)
			)
		)
		(property "License" "Apache-2.0"
			(at 0 0 180)
			(unlocked yes)
			(layer "F.Fab")
			(hide yes)
			(effects
				(font
					(size 1 1)
					(thickness 0.15)
				)
			)
		)
		(property "Author" "Antmicro"
			(at 0 0 180)
			(unlocked yes)
			(layer "F.Fab")
			(hide yes)
			(effects
				(font
					(size 1 1)
					(thickness 0.15)
				)
			)
		)
		(property "Voltage" ""
			(at 0 0 180)
			(unlocked yes)
			(layer "F.Fab")
			(hide yes)
			(effects
				(font
					(size 1 1)
					(thickness 0.15)
				)
			)
		)
		(property "Dielectric" ""
			(at 0 0 180)
			(unlocked yes)
			(layer "F.Fab")
			(hide yes)
			(effects
				(font
					(size 1 1)
					(thickness 0.15)
				)
			)
		)
		(sheetname "/Supply/DC-DC VCCINT/")
		(sheetfile "dc-dc-vccint.kicad_sch")
		(attr smd)
		(fp_line
			(start -0.15 0.4)
			(end 0.15 0.4)
			(stroke
				(width 0.15)
				(type solid)
			)
			(layer "F.SilkS")
		)
		(fp_line
			(start -0.15 -0.4)
			(end 0.15 -0.4)
			(stroke
				(width 0.15)
				(type solid)
			)
			(layer "F.SilkS")
		)
		(fp_rect
			(start -1.25 -0.65)
			(end 1.25 0.65)
			(stroke
				(width 0.05)
				(type solid)
			)
			(fill no)
			(layer "F.CrtYd")
		)
		(fp_rect
			(start -0.8 -0.4)
			(end 0.8 0.4)
			(stroke
				(width 0.15)
				(type solid)
			)
			(fill no)
			(layer "F.Fab")
		)
		(fp_text user "Author: Antmicro"
			(at -1.682 4.894 180)
			(layer "F.Fab")
			(effects
				(font
					(size 0.7 0.7)
					(thickness 0.15)
				)
				(justify left bottom)
			)
		)
		(fp_text user "License: Apache-2.0"
			(at -1.682 5.895 180)
			(layer "F.Fab")
			(effects
				(font
					(size 0.7 0.7)
					(thickness 0.15)
				)
				(justify left bottom)
			)
		)
		(fp_text user "${REFERENCE}"
			(at -1.682 3.895 180)
			(layer "F.Fab")
			(effects
				(font
					(size 0.7 0.7)
					(thickness 0.15)
				)
				(justify left bottom)
			)
		)
		(pad "1" smd roundrect
			(at -0.7 0 180)
			(size 0.8 1)
			(layers "F.Cu" "F.Mask" "F.Paste")
			(roundrect_rratio 0.2)
			(net 1 "GND")
			(pintype "passive")
		)
		(pad "2" smd roundrect
			(at 0.7 0 180)
			(size 0.8 1)
			(layers "F.Cu" "F.Mask" "F.Paste")
			(roundrect_rratio 0.2)
			(net 223 "/Supply/DC-DC VCCINT/0V85_REG0")
			(pintype "passive")
		)
	)
	(footprint "antmicro-footprints:LED_RGY_1.6x1.6mm_APTF1616"
		(layer "F.Cu")
		(at 254.1 145.05)
		(descr "1.6 x 1.6 mm Full-Color Surface Mount LED")
		(tags "LED")
		(property "Reference" "D20"
			(at -0.3 1.95 180)
			(layer "F.SilkS")
			(effects
				(font
					(size 0.7 0.7)
					(thickness 0.15)
				)
				(justify left bottom)
			)
		)
		(property "Value" "LED_RGY_0606_APTF1616SURKCGKSYKC"
			(at 0 2 0)
			(layer "F.Fab")
			(effects
				(font
					(size 0.7 0.7)
					(thickness 0.15)
				)
				(justify left bottom)
			)
		)
		(property "Datasheet" "https://www.kingbrightusa.com/images/catalog/SPEC/APTF1616SURKCGKSYKC.pdf"
			(at 0 0 0)
			(layer "F.Fab")
			(hide yes)
			(effects
				(font
					(size 1.27 1.27)
					(thickness 0.15)
				)
			)
		)
		(property "MPN" "APTF1616SURKCGKSYKC"
			(at 0 0 0)
			(unlocked yes)
			(layer "F.Fab")
			(hide yes)
			(effects
				(font
					(size 1 1)
					(thickness 0.15)
				)
			)
		)
		(property "Manufacturer" "Kingbright"
			(at 0 0 0)
			(unlocked yes)
			(layer "F.Fab")
			(hide yes)
			(effects
				(font
					(size 1 1)
					(thickness 0.15)
				)
			)
		)
		(property "Color" "R, G, Y"
			(at 0 0 0)
			(unlocked yes)
			(layer "F.Fab")
			(hide yes)
			(effects
				(font
					(size 1 1)
					(thickness 0.15)
				)
			)
		)
		(property "Author" "Antmicro"
			(at 0 0 0)
			(unlocked yes)
			(layer "F.Fab")
			(hide yes)
			(effects
				(font
					(size 1 1)
					(thickness 0.15)
				)
			)
		)
		(property "License" "Apache-2.0"
			(at 0 0 0)
			(unlocked yes)
			(layer "F.Fab")
			(hide yes)
			(effects
				(font
					(size 1 1)
					(thickness 0.15)
				)
			)
		)
		(sheetname "/DDR5 RDIMM/")
		(sheetfile "ddr5-rdimm.kicad_sch")
		(attr smd)
		(fp_line
			(start -0.8 -0.15)
			(end -0.801 0.15)
			(stroke
				(width 0.15)
				(type solid)
			)
			(layer "F.SilkS")
		)
		(fp_line
			(start -0.35 0.8)
			(end 0.35 0.8)
			(stroke
				(width 0.15)
				(type solid)
			)
			(layer "F.SilkS")
		)
		(fp_line
			(start 0.35 -0.802)
			(end -0.35 -0.802)
			(stroke
				(width 0.15)
				(type solid)
			)
			(layer "F.SilkS")
		)
		(fp_line
			(start 0.8 0.148)
			(end 0.8 -0.102)
			(stroke
				(width 0.15)
				(type solid)
			)
			(layer "F.SilkS")
		)
		(fp_circle
			(center -1.05 -0.95)
			(end -1.101 -0.999)
			(stroke
				(width 0.15)
				(type solid)
			)
			(fill yes)
			(layer "F.SilkS")
		)
		(fp_rect
			(start 1.3 1.1)
			(end -1.3 -1.1)
			(stroke
				(width 0.05)
				(type solid)
			)
			(fill no)
			(layer "F.CrtYd")
		)
		(fp_rect
			(start -0.801 -0.802)
			(end 0.8 0.801)
			(stroke
				(width 0.15)
				(type solid)
			)
			(fill no)
			(layer "F.Fab")
		)
		(fp_text user "Author: Antmicro"
			(at -1.3 4.496 0)
			(layer "F.Fab")
			(effects
				(font
					(size 0.7 0.7)
					(thickness 0.15)
				)
				(justify left bottom)
			)
		)
		(fp_text user "License: Apache-2.0"
			(at -1.3 5.698 0)
			(layer "F.Fab")
			(effects
				(font
					(size 0.7 0.7)
					(thickness 0.15)
				)
				(justify left bottom)
			)
		)
		(fp_text user "${REFERENCE}"
			(at -1.3 3.297 0)
			(layer "F.Fab")
			(effects
				(font
					(size 0.7 0.7)
					(thickness 0.15)
				)
				(justify left bottom)
			)
		)
		(pad "1" smd rect
			(at -0.874 -0.499 270)
			(size 0.5 0.85)
			(layers "F.Cu" "F.Mask" "F.Paste")
			(net 151 "+3V3")
			(pinfunction "A")
			(pintype "passive")
		)
		(pad "2" smd rect
			(at 0.874 -0.499 270)
			(size 0.5 0.85)
			(layers "F.Cu" "F.Mask" "F.Paste")
			(net 221 "Net-(D20-C_{R})")
			(pinfunction "C_{R}")
			(pintype "passive")
		)
		(pad "3" smd rect
			(at 0.874 0.498 270)
			(size 0.5 0.85)
			(layers "F.Cu" "F.Mask" "F.Paste")
			(net 236 "Net-(D20-C_{G})")
			(pinfunction "C_{G}")
			(pintype "passive")
		)
		(pad "4" smd rect
			(at -0.874 0.498 270)
			(size 0.5 0.85)
			(layers "F.Cu" "F.Mask" "F.Paste")
			(net 237 "Net-(D20-C_{Y})")
			(pinfunction "C_{Y}")
			(pintype "passive")
		)
	)
	(footprint "antmicro-footprints:R_1206_3216Metric"
		(layer "F.Cu")
		(at 246.299499 160.149 180)
		(property "Reference" "R145"
			(at -2.400501 -2.201 0)
			(layer "F.SilkS")
			(effects
				(font
					(size 0.7 0.7)
					(thickness 0.15)
				)
				(justify right bottom)
			)
		)
		(property "Value" "R_0R01_1206"
			(at -2.422356 2.103591 0)
			(layer "F.Fab")
			(effects
				(font
					(size 0.7 0.7)
					(thickness 0.15)
				)
				(justify right bottom)
			)
		)
		(property "Datasheet" "https://www.yageo.com/upload/media/product/productsearch/datasheet/rchip/PYu-RL_Group_521_RoHS_L_2.pdf"
			(at 0 0 180)
			(layer "F.Fab")
			(hide yes)
			(effects
				(font
					(size 1.27 1.27)
					(thickness 0.15)
				)
			)
		)
		(property "Manufacturer" "YAGEO"
			(at 0 0 180)
			(unlocked yes)
			(layer "F.Fab")
			(hide yes)
			(effects
				(font
					(size 1 1)
					(thickness 0.15)
				)
			)
		)
		(property "MPN" "RL1206FR-7W0R01L"
			(at 0 0 180)
			(unlocked yes)
			(layer "F.Fab")
			(hide yes)
			(effects
				(font
					(size 1 1)
					(thickness 0.15)
				)
			)
		)
		(property "Val" "0R01"
			(at 0 0 180)
			(unlocked yes)
			(layer "F.Fab")
			(hide yes)
			(effects
				(font
					(size 1 1)
					(thickness 0.15)
				)
			)
		)
		(property "License" "Apache-2.0"
			(at 0 0 180)
			(unlocked yes)
			(layer "F.Fab")
			(hide yes)
			(effects
				(font
					(size 1 1)
					(thickness 0.15)
				)
			)
		)
		(property "Author" "Antmicro"
			(at 0 0 180)
			(unlocked yes)
			(layer "F.Fab")
			(hide yes)
			(effects
				(font
					(size 1 1)
					(thickness 0.15)
				)
			)
		)
		(property "Tolerance" "1%"
			(at 0 0 180)
			(unlocked yes)
			(layer "F.Fab")
			(hide yes)
			(effects
				(font
					(size 1 1)
					(thickness 0.15)
				)
			)
		)
		(sheetname "/Supply/DC-DC IO/")
		(sheetfile "dc-dc-io.kicad_sch")
		(attr smd)
		(fp_line
			(start 0.8 0.901)
			(end -0.8 0.901)
			(stroke
				(width 0.15)
				(type solid)
			)
			(layer "F.SilkS")
		)
		(fp_line
			(start 0.8 -0.899)
			(end -0.8 -0.899)
			(stroke
				(width 0.15)
				(type solid)
			)
			(layer "F.SilkS")
		)
		(fp_rect
			(start -2.325 -1.15)
			(end 2.325 1.15)
			(stroke
				(width 0.05)
				(type default)
			)
			(fill no)
			(layer "F.CrtYd")
		)
		(fp_line
			(start 1.6 -0.802)
			(end 1.6 0.8)
			(stroke
				(width 0.15)
				(type solid)
			)
			(layer "F.Fab")
		)
		(fp_line
			(start -1.601 0.8)
			(end 1.6 0.8)
			(stroke
				(width 0.15)
				(type solid)
			)
			(layer "F.Fab")
		)
		(fp_line
			(start -1.601 -0.802)
			(end 1.6 -0.802)
			(stroke
				(width 0.15)
				(type solid)
			)
			(layer "F.Fab")
		)
		(fp_line
			(start -1.601 -0.802)
			(end -1.601 0.8)
			(stroke
				(width 0.15)
				(type solid)
			)
			(layer "F.Fab")
		)
		(fp_text user "${REFERENCE}"
			(at -2.401 3.5 180)
			(layer "F.Fab")
			(effects
				(font
					(size 0.7 0.7)
					(thickness 0.15)
				)
				(justify left bottom)
			)
		)
		(fp_text user "License: Apache-2.0"
			(at -2.401 6.3 180)
			(layer "F.Fab")
			(effects
				(font
					(size 0.7 0.7)
					(thickness 0.15)
				)
				(justify left bottom)
			)
		)
		(fp_text user "Author: Antmicro"
			(at -2.401 4.899 180)
			(layer "F.Fab")
			(effects
				(font
					(size 0.7 0.7)
					(thickness 0.15)
				)
				(justify left bottom)
			)
		)
		(pad "1" smd roundrect
			(at -1.5 0.001 180)
			(size 1.15 1.8)
			(layers "F.Cu" "F.Mask" "F.Paste")
			(roundrect_rratio 0.25)
			(net 45 "/Supply/DC-DC IO/3V3_local")
			(pintype "passive")
		)
		(pad "2" smd roundrect
			(at 1.5 0.001 180)
			(size 1.15 1.8)
			(layers "F.Cu" "F.Mask" "F.Paste")
			(roundrect_rratio 0.25)
			(net 151 "+3V3")
			(pintype "passive")
		)
	)
	(footprint "antmicro-footprints:C_0402_1005Metric"
		(layer "F.Cu")
		(at 164.45 164.034999)
		(descr "Capacitor SMD 0402")
		(tags "capacitor SMD 0402")
		(property "Reference" "C309"
			(at 0.82 0.44 0)
			(layer "F.SilkS")
			(effects
				(font
					(size 0.7 0.7)
					(thickness 0.15)
				)
				(justify left bottom)
			)
		)
		(property "Value" "C_100n_0402"
			(at -1.022927 2.155213 0)
			(layer "F.Fab")
			(effects
				(font
					(size 0.7 0.7)
					(thickness 0.15)
				)
				(justify left bottom)
			)
		)
		(property "Datasheet" "https://www.murata.com/products/productdetail?partno=GRM155R61H104KE14%23"
			(at 0 0 0)
			(layer "F.Fab")
			(hide yes)
			(effects
				(font
					(size 1.27 1.27)
					(thickness 0.15)
				)
			)
		)
		(property "Manufacturer" "Murata"
			(at 0 0 0)
			(unlocked yes)
			(layer "F.Fab")
			(hide yes)
			(effects
				(font
					(size 1 1)
					(thickness 0.15)
				)
			)
		)
		(property "MPN" "GRM155R61H104KE14D"
			(at 0 0 0)
			(unlocked yes)
			(layer "F.Fab")
			(hide yes)
			(effects
				(font
					(size 1 1)
					(thickness 0.15)
				)
			)
		)
		(property "Val" "100n"
			(at 0 0 0)
			(unlocked yes)
			(layer "F.Fab")
			(hide yes)
			(effects
				(font
					(size 1 1)
					(thickness 0.15)
				)
			)
		)
		(property "License" "Apache-2.0"
			(at 0 0 0)
			(unlocked yes)
			(layer "F.Fab")
			(hide yes)
			(effects
				(font
					(size 1 1)
					(thickness 0.15)
				)
			)
		)
		(property "Author" "Antmicro"
			(at 0 0 0)
			(unlocked yes)
			(layer "F.Fab")
			(hide yes)
			(effects
				(font
					(size 1 1)
					(thickness 0.15)
				)
			)
		)
		(property "Voltage" "50V"
			(at 0 0 0)
			(unlocked yes)
			(layer "F.Fab")
			(hide yes)
			(effects
				(font
					(size 1 1)
					(thickness 0.15)
				)
			)
		)
		(property "Dielectric" "X5R"
			(at 0 0 0)
			(unlocked yes)
			(layer "F.Fab")
			(hide yes)
			(effects
				(font
					(size 1 1)
					(thickness 0.15)
				)
			)
		)
		(sheetname "/FPGA MGT Interface/")
		(sheetfile "fpga-mgt.kicad_sch")
		(attr smd)
		(fp_rect
			(start -0.925 -0.47)
			(end 0.925 0.47)
			(stroke
				(width 0.05)
				(type default)
			)
			(fill no)
			(layer "F.CrtYd")
		)
		(fp_line
			(start -0.494 -0.25)
			(end 0.504 -0.25)
			(stroke
				(width 0.15)
				(type solid)
			)
			(layer "F.Fab")
		)
		(fp_line
			(start -0.494 0.248)
			(end -0.494 -0.25)
			(stroke
				(width 0.15)
				(type solid)
			)
			(layer "F.Fab")
		)
		(fp_line
			(start 0.504 -0.25)
			(end 0.504 0.248)
			(stroke
				(width 0.15)
				(type solid)
			)
			(layer "F.Fab")
		)
		(fp_line
			(start 0.504 0.248)
			(end -0.494 0.248)
			(stroke
				(width 0.15)
				(type solid)
			)
			(layer "F.Fab")
		)
		(fp_text user "Author: Antmicro"
			(at -0.939 3.399 0)
			(layer "F.Fab")
			(effects
				(font
					(size 0.7 0.7)
					(thickness 0.15)
				)
				(justify left bottom)
			)
		)
		(fp_text user "${REFERENCE}"
			(at -0.939 4.599 0)
			(layer "F.Fab")
			(effects
				(font
					(size 0.7 0.7)
					(thickness 0.15)
				)
				(justify left bottom)
			)
		)
		(fp_text user "License: Apache-2.0"
			(at -0.939 5.799 0)
			(layer "F.Fab")
			(effects
				(font
					(size 0.7 0.7)
					(thickness 0.15)
				)
				(justify left bottom)
			)
		)
		(pad "1" smd roundrect
			(at -0.48 0)
			(size 0.59 0.64)
			(layers "F.Cu" "F.Mask" "F.Paste")
			(roundrect_rratio 0.25)
			(net 389 "/FPGA MGT Interface/HDMI_SI5319_C_CLK_P")
			(pintype "passive")
		)
		(pad "2" smd roundrect
			(at 0.48 0)
			(size 0.59 0.64)
			(layers "F.Cu" "F.Mask" "F.Paste")
			(roundrect_rratio 0.25)
			(net 402 "/FPGA MGT Interface/HDMI_SI5319_CLK_P")
			(pintype "passive")
		)
	)
	(footprint "antmicro-footprints:TP_SMD_0.75mm"
		(layer "F.Cu")
		(at 155.43 160.789999)
		(property "Reference" "TP5"
			(at -2.6 0.5 0)
			(layer "F.SilkS")
			(effects
				(font
					(size 0.7 0.7)
					(thickness 0.15)
				)
				(justify left bottom)
			)
		)
		(property "Value" "TP_0.75mm_SMD"
			(at 0 1.2 0)
			(layer "F.Fab")
			(effects
				(font
					(size 0.7 0.7)
					(thickness 0.15)
				)
				(justify left bottom)
			)
		)
		(property "MPN" ""
			(at 0 0 0)
			(unlocked yes)
			(layer "F.Fab")
			(hide yes)
			(effects
				(font
					(size 1 1)
					(thickness 0.15)
				)
			)
		)
		(property "Manufacturer" ""
			(at 0 0 0)
			(unlocked yes)
			(layer "F.Fab")
			(hide yes)
			(effects
				(font
					(size 1 1)
					(thickness 0.15)
				)
			)
		)
		(property "Author" "Antmicro"
			(at 0 0 0)
			(unlocked yes)
			(layer "F.Fab")
			(hide yes)
			(effects
				(font
					(size 1 1)
					(thickness 0.15)
				)
			)
		)
		(property "License" "Apache-2.0"
			(at 0 0 0)
			(unlocked yes)
			(layer "F.Fab")
			(hide yes)
			(effects
				(font
					(size 1 1)
					(thickness 0.15)
				)
			)
		)
		(sheetname "/FPGA MGT Interface/")
		(sheetfile "fpga-mgt.kicad_sch")
		(attr exclude_from_pos_files exclude_from_bom)
		(fp_circle
			(center 0 0)
			(end 0.475 0)
			(stroke
				(width 0.05)
				(type default)
			)
			(fill no)
			(layer "F.CrtYd")
		)
		(fp_text user "${REFERENCE}"
			(at -0.4 2.7 0)
			(layer "F.Fab")
			(effects
				(font
					(size 0.7 0.7)
					(thickness 0.15)
				)
				(justify left bottom)
			)
		)
		(fp_text user "Author: Antmicro"
			(at -0.4 3.901 0)
			(layer "F.Fab")
			(effects
				(font
					(size 0.7 0.7)
					(thickness 0.15)
				)
				(justify left bottom)
			)
		)
		(fp_text user "License: Apache-2.0"
			(at -0.4 5.101 0)
			(layer "F.Fab")
			(effects
				(font
					(size 0.7 0.7)
					(thickness 0.15)
				)
				(justify left bottom)
			)
		)
		(pad "1" smd circle
			(at 0 0)
			(size 0.75 0.75)
			(layers "F.Cu" "F.Mask")
			(net 534 "Net-(U39-RATE0)")
			(pinfunction "1")
			(pintype "passive")
		)
	)
	(footprint "antmicro-footprints:C_0402_1005Metric"
		(layer "F.Cu")
		(at 124.756 186.5875 -90)
		(descr "Capacitor SMD 0402")
		(tags "capacitor SMD 0402")
		(property "Reference" "C274"
			(at -0.9375 -1.469 90)
			(layer "F.SilkS")
			(effects
				(font
					(size 0.7 0.7)
					(thickness 0.15)
				)
				(justify right bottom)
			)
		)
		(property "Value" "C_100n_0402"
			(at -1.022927 2.155213 90)
			(layer "F.Fab")
			(effects
				(font
					(size 0.7 0.7)
					(thickness 0.15)
				)
				(justify right bottom)
			)
		)
		(property "Datasheet" "https://www.murata.com/products/productdetail?partno=GRM155R61H104KE14%23"
			(at 0 0 270)
			(layer "F.Fab")
			(hide yes)
			(effects
				(font
					(size 1.27 1.27)
					(thickness 0.15)
				)
			)
		)
		(property "MPN" "GRM155R61H104KE14D"
			(at 0 0 270)
			(unlocked yes)
			(layer "F.Fab")
			(hide yes)
			(effects
				(font
					(size 1 1)
					(thickness 0.15)
				)
			)
		)
		(property "Manufacturer" "Murata"
			(at 0 0 270)
			(unlocked yes)
			(layer "F.Fab")
			(hide yes)
			(effects
				(font
					(size 1 1)
					(thickness 0.15)
				)
			)
		)
		(property "License" "Apache-2.0"
			(at 0 0 270)
			(unlocked yes)
			(layer "F.Fab")
			(hide yes)
			(effects
				(font
					(size 1 1)
					(thickness 0.15)
				)
			)
		)
		(property "Author" "Antmicro"
			(at 0 0 270)
			(unlocked yes)
			(layer "F.Fab")
			(hide yes)
			(effects
				(font
					(size 1 1)
					(thickness 0.15)
				)
			)
		)
		(property "Val" "100n"
			(at 0 0 270)
			(unlocked yes)
			(layer "F.Fab")
			(hide yes)
			(effects
				(font
					(size 1 1)
					(thickness 0.15)
				)
			)
		)
		(property "Voltage" "50V"
			(at 0 0 270)
			(unlocked yes)
			(layer "F.Fab")
			(hide yes)
			(effects
				(font
					(size 1 1)
					(thickness 0.15)
				)
			)
		)
		(property "Dielectric" "X5R"
			(at 0 0 270)
			(unlocked yes)
			(layer "F.Fab")
			(hide yes)
			(effects
				(font
					(size 1 1)
					(thickness 0.15)
				)
			)
		)
		(property "Public" ""
			(at 0 0 270)
			(unlocked yes)
			(layer "F.Fab")
			(hide yes)
			(effects
				(font
					(size 1 1)
					(thickness 0.15)
				)
			)
		)
		(sheetname "/HDMI + SD Card/")
		(sheetfile "hdmi-sd-card.kicad_sch")
		(attr smd)
		(fp_rect
			(start -0.925 -0.47)
			(end 0.925 0.47)
			(stroke
				(width 0.05)
				(type default)
			)
			(fill no)
			(layer "F.CrtYd")
		)
		(fp_line
			(start -0.494 0.248)
			(end -0.494 -0.25)
			(stroke
				(width 0.15)
				(type solid)
			)
			(layer "F.Fab")
		)
		(fp_line
			(start 0.504 0.248)
			(end -0.494 0.248)
			(stroke
				(width 0.15)
				(type solid)
			)
			(layer "F.Fab")
		)
		(fp_line
			(start -0.494 -0.25)
			(end 0.504 -0.25)
			(stroke
				(width 0.15)
				(type solid)
			)
			(layer "F.Fab")
		)
		(fp_line
			(start 0.504 -0.25)
			(end 0.504 0.248)
			(stroke
				(width 0.15)
				(type solid)
			)
			(layer "F.Fab")
		)
		(fp_text user "License: Apache-2.0"
			(at -0.939 5.799 270)
			(layer "F.Fab")
			(effects
				(font
					(size 0.7 0.7)
					(thickness 0.15)
				)
				(justify left bottom)
			)
		)
		(fp_text user "Author: Antmicro"
			(at -0.939 3.399 270)
			(layer "F.Fab")
			(effects
				(font
					(size 0.7 0.7)
					(thickness 0.15)
				)
				(justify left bottom)
			)
		)
		(fp_text user "${REFERENCE}"
			(at -0.939 4.599 270)
			(layer "F.Fab")
			(effects
				(font
					(size 0.7 0.7)
					(thickness 0.15)
				)
				(justify left bottom)
			)
		)
		(pad "1" smd roundrect
			(at -0.48 0 270)
			(size 0.59 0.64)
			(layers "F.Cu" "F.Mask" "F.Paste")
			(roundrect_rratio 0.25)
			(net 151 "+3V3")
			(pintype "passive")
		)
		(pad "2" smd roundrect
			(at 0.48 0 270)
			(size 0.59 0.64)
			(layers "F.Cu" "F.Mask" "F.Paste")
			(roundrect_rratio 0.25)
			(net 1 "GND")
			(pintype "passive")
		)
	)
	(footprint "antmicro-footprints:R_0402_1005Metric"
		(layer "F.Cu")
		(at 123.056 174.9375 -90)
		(descr "Resistor SMD 0402")
		(tags "resistor SMD 0402")
		(property "Reference" "R76"
			(at -1.1625 -1.494 90)
			(layer "F.SilkS")
			(effects
				(font
					(size 0.7 0.7)
					(thickness 0.15)
				)
				(justify right bottom)
			)
		)
		(property "Value" "R_6k49_0402"
			(at -1.011843 1.772047 90)
			(layer "F.Fab")
			(effects
				(font
					(size 0.7 0.7)
					(thickness 0.15)
				)
				(justify right bottom)
			)
		)
		(property "Datasheet" "https://www.farnell.com/datasheets/3795017.pdf"
			(at 0 0 270)
			(layer "F.Fab")
			(hide yes)
			(effects
				(font
					(size 1.27 1.27)
					(thickness 0.15)
				)
			)
		)
		(property "MPN" "RMCF0402FT6K49"
			(at 0 0 270)
			(unlocked yes)
			(layer "F.Fab")
			(hide yes)
			(effects
				(font
					(size 1 1)
					(thickness 0.15)
				)
			)
		)
		(property "Manufacturer" "Stackpole Electronics"
			(at 0 0 270)
			(unlocked yes)
			(layer "F.Fab")
			(hide yes)
			(effects
				(font
					(size 1 1)
					(thickness 0.15)
				)
			)
		)
		(property "License" "Apache-2.0"
			(at 0 0 270)
			(unlocked yes)
			(layer "F.Fab")
			(hide yes)
			(effects
				(font
					(size 1 1)
					(thickness 0.15)
				)
			)
		)
		(property "Author" "Antmicro"
			(at 0 0 270)
			(unlocked yes)
			(layer "F.Fab")
			(hide yes)
			(effects
				(font
					(size 1 1)
					(thickness 0.15)
				)
			)
		)
		(property "Val" "6k49"
			(at 0 0 270)
			(unlocked yes)
			(layer "F.Fab")
			(hide yes)
			(effects
				(font
					(size 1 1)
					(thickness 0.15)
				)
			)
		)
		(property "Tolerance" "1%"
			(at 0 0 270)
			(unlocked yes)
			(layer "F.Fab")
			(hide yes)
			(effects
				(font
					(size 1 1)
					(thickness 0.15)
				)
			)
		)
		(sheetname "/HDMI + SD Card/")
		(sheetfile "hdmi-sd-card.kicad_sch")
		(attr smd)
		(fp_rect
			(start -0.925 -0.47)
			(end 0.925 0.47)
			(stroke
				(width 0.05)
				(type default)
			)
			(fill no)
			(layer "F.CrtYd")
		)
		(fp_rect
			(start -0.5 -0.25)
			(end 0.5 0.25)
			(stroke
				(width 0.15)
				(type solid)
			)
			(fill no)
			(layer "F.Fab")
		)
		(fp_text user "License: Apache-2.0"
			(at -0.95 5.169 270)
			(layer "F.Fab")
			(effects
				(font
					(size 0.7 0.7)
					(thickness 0.15)
				)
				(justify left bottom)
			)
		)
		(fp_text user "Author: Antmicro"
			(at -0.95 4.169 270)
			(layer "F.Fab")
			(effects
				(font
					(size 0.7 0.7)
					(thickness 0.15)
				)
				(justify left bottom)
			)
		)
		(fp_text user "${REFERENCE}"
			(at -0.95 3.168 270)
			(layer "F.Fab")
			(effects
				(font
					(size 0.7 0.7)
					(thickness 0.15)
				)
				(justify left bottom)
			)
		)
		(pad "1" smd roundrect
			(at -0.48 0 270)
			(size 0.59 0.64)
			(layers "F.Cu" "F.Mask" "F.Paste")
			(roundrect_rratio 0.25)
			(net 1 "GND")
			(pintype "passive")
		)
		(pad "2" smd roundrect
			(at 0.48 0 270)
			(size 0.59 0.64)
			(layers "F.Cu" "F.Mask" "F.Paste")
			(roundrect_rratio 0.25)
			(net 709 "Net-(U38-VSADJ)")
			(pintype "passive")
		)
	)
	(footprint "antmicro-footprints:LED_0603_1608Metric_G"
		(layer "F.Cu")
		(at 113.405 102.225 90)
		(descr "LED SMD 0603 Green")
		(tags "LED SMD 0603 Green")
		(property "Reference" "D4"
			(at -2.575 -0.305 90)
			(layer "F.SilkS")
			(hide yes)
			(effects
				(font
					(size 0.7 0.7)
					(thickness 0.15)
				)
				(justify left bottom)
			)
		)
		(property "Value" "LED_G_0603_KP-1608CGCK"
			(at -0.001 1.599 90)
			(layer "F.Fab")
			(effects
				(font
					(size 0.7 0.7)
					(thickness 0.15)
				)
				(justify left bottom)
			)
		)
		(property "Datasheet" "http://www.kingbright.com/attachments/file/psearch//000/00/00/KP-1608CGCK(Ver.23B).pdf"
			(at 0 0 90)
			(layer "F.Fab")
			(hide yes)
			(effects
				(font
					(size 1.27 1.27)
					(thickness 0.15)
				)
			)
		)
		(property "MPN" "KP-1608CGCK"
			(at 0 0 90)
			(unlocked yes)
			(layer "F.Fab")
			(hide yes)
			(effects
				(font
					(size 1 1)
					(thickness 0.15)
				)
			)
		)
		(property "Manufacturer" "Kingbright"
			(at 0 0 90)
			(unlocked yes)
			(layer "F.Fab")
			(hide yes)
			(effects
				(font
					(size 1 1)
					(thickness 0.15)
				)
			)
		)
		(property "Author" "Antmicro"
			(at 0 0 90)
			(unlocked yes)
			(layer "F.Fab")
			(hide yes)
			(effects
				(font
					(size 1 1)
					(thickness 0.15)
				)
			)
		)
		(property "License" "Apache-2.0"
			(at 0 0 90)
			(unlocked yes)
			(layer "F.Fab")
			(hide yes)
			(effects
				(font
					(size 1 1)
					(thickness 0.15)
				)
			)
		)
		(property "Color" "Green"
			(at 0 0 90)
			(unlocked yes)
			(layer "F.Fab")
			(hide yes)
			(effects
				(font
					(size 1 1)
					(thickness 0.15)
				)
			)
		)
		(sheetname "/FPGA banks HD/")
		(sheetfile "fpga-hd-banks.kicad_sch")
		(attr smd)
		(fp_line
			(start 0.22 -0.35)
			(end -0.22 -0.35)
			(stroke
				(width 0.15)
				(type solid)
			)
			(layer "F.SilkS")
		)
		(fp_line
			(start -1.18 -0.319)
			(end -1.18 0.321)
			(stroke
				(width 0.15)
				(type solid)
			)
			(layer "F.SilkS")
		)
		(fp_line
			(start 0.105328 0.001008)
			(end 0.24 0.001)
			(stroke
				(width 0.1)
				(type solid)
			)
			(layer "F.SilkS")
		)
		(fp_line
			(start -0.094672 0.001008)
			(end 0.105328 -0.198992)
			(stroke
				(width 0.1)
				(type solid)
			)
			(layer "F.SilkS")
		)
		(fp_line
			(start -0.094672 0.001008)
			(end -0.24 0.001008)
			(stroke
				(width 0.1)
				(type solid)
			)
			(layer "F.SilkS")
		)
		(fp_line
			(start 0.105328 0.201008)
			(end 0.105328 -0.198992)
			(stroke
				(width 0.1)
				(type solid)
			)
			(layer "F.SilkS")
		)
		(fp_line
			(start 0.105328 0.201008)
			(end -0.094672 0.001008)
			(stroke
				(width 0.1)
				(type solid)
			)
			(layer "F.SilkS")
		)
		(fp_line
			(start -0.094672 0.201008)
			(end -0.094672 -0.198992)
			(stroke
				(width 0.1)
				(type solid)
			)
			(layer "F.SilkS")
		)
		(fp_line
			(start 0.22 0.35)
			(end -0.22 0.35)
			(stroke
				(width 0.15)
				(type solid)
			)
			(layer "F.SilkS")
		)
		(fp_rect
			(start 1.25 0.65)
			(end -1.25 -0.65)
			(stroke
				(width 0.05)
				(type solid)
			)
			(fill no)
			(layer "F.CrtYd")
		)
		(fp_line
			(start 0.201 -0.202)
			(end -0.101 0)
			(stroke
				(width 0.15)
				(type solid)
			)
			(layer "F.Fab")
		)
		(fp_line
			(start -0.199 -0.202)
			(end -0.199 0.1)
			(stroke
				(width 0.15)
				(type solid)
			)
			(layer "F.Fab")
		)
		(fp_line
			(start 0.599 0)
			(end 0.201 0)
			(stroke
				(width 0.15)
				(type solid)
			)
			(layer "F.Fab")
		)
		(fp_line
			(start 0.201 0)
			(end 0.201 -0.202)
			(stroke
				(width 0.15)
				(type solid)
			)
			(layer "F.Fab")
		)
		(fp_line
			(start -0.101 0)
			(end 0.201 0.2)
			(stroke
				(width 0.15)
				(type solid)
			)
			(layer "F.Fab")
		)
		(fp_line
			(start -0.199 0)
			(end -0.597 0)
			(stroke
				(width 0.15)
				(type solid)
			)
			(layer "F.Fab")
		)
		(fp_line
			(start 0.201 0.2)
			(end 0.201 0)
			(stroke
				(width 0.15)
				(type solid)
			)
			(layer "F.Fab")
		)
		(fp_line
			(start -0.199 0.2)
			(end -0.199 0.1)
			(stroke
				(width 0.15)
				(type solid)
			)
			(layer "F.Fab")
		)
		(fp_rect
			(start 0.848 0.4)
			(end -0.85 -0.402)
			(stroke
				(width 0.15)
				(type solid)
			)
			(fill no)
			(layer "F.Fab")
		)
		(fp_text user "Author: Antmicro"
			(at -1.4224 4.799 90)
			(layer "F.Fab")
			(effects
				(font
					(size 0.7 0.7)
					(thickness 0.15)
				)
				(justify left bottom)
			)
		)
		(fp_text user "License: Apache-2.0"
			(at -1.4224 3.599 90)
			(layer "F.Fab")
			(effects
				(font
					(size 0.7 0.7)
					(thickness 0.15)
				)
				(justify left bottom)
			)
		)
		(fp_text user "${REFERENCE}"
			(at -1.4224 5.999 90)
			(layer "F.Fab")
			(effects
				(font
					(size 0.7 0.7)
					(thickness 0.15)
				)
				(justify left bottom)
			)
		)
		(pad "1" smd roundrect
			(at -0.7 0 270)
			(size 0.8 1)
			(layers "F.Cu" "F.Mask" "F.Paste")
			(roundrect_rratio 0.2)
			(net 151 "+3V3")
			(pinfunction "C")
			(pintype "passive")
		)
		(pad "2" smd roundrect
			(at 0.7 0 270)
			(size 0.8 1)
			(layers "F.Cu" "F.Mask" "F.Paste")
			(roundrect_rratio 0.2)
			(net 32 "Net-(D4-A)")
			(pinfunction "A")
			(pintype "passive")
		)
	)
	(footprint "antmicro-footprints:Vishay_PowerPAK_1212-8_Single"
		(layer "F.Cu")
		(at 247.1255 126.55 90)
		(descr "PowerPAK 1212-8 Single")
		(tags "Vishay PowerPAK 1212-8 Single")
		(property "Reference" "Q12"
			(at -2.95 -0.2255 180)
			(layer "F.SilkS")
			(effects
				(font
					(size 0.7 0.7)
					(thickness 0.15)
				)
				(justify left bottom)
			)
		)
		(property "Value" "SI7613DN-T1-GE3"
			(at 0 2.7 90)
			(layer "F.Fab")
			(effects
				(font
					(size 0.7 0.7)
					(thickness 0.15)
				)
				(justify left bottom)
			)
		)
		(property "Datasheet" "https://www.vishay.com/docs/64809/si7613dn.pdf"
			(at 0 0 90)
			(layer "F.Fab")
			(hide yes)
			(effects
				(font
					(size 1.27 1.27)
					(thickness 0.15)
				)
			)
		)
		(property "MPN" "SI7613DN-T1-GE3"
			(at 0 0 90)
			(unlocked yes)
			(layer "F.Fab")
			(hide yes)
			(effects
				(font
					(size 1 1)
					(thickness 0.15)
				)
			)
		)
		(property "Manufacturer" "Vishay"
			(at 0 0 90)
			(unlocked yes)
			(layer "F.Fab")
			(hide yes)
			(effects
				(font
					(size 1 1)
					(thickness 0.15)
				)
			)
		)
		(property "Author" "Antmicro"
			(at 0 0 90)
			(unlocked yes)
			(layer "F.Fab")
			(hide yes)
			(effects
				(font
					(size 1 1)
					(thickness 0.15)
				)
			)
		)
		(property "License" "Apache-2.0"
			(at 0 0 90)
			(unlocked yes)
			(layer "F.Fab")
			(hide yes)
			(effects
				(font
					(size 1 1)
					(thickness 0.15)
				)
			)
		)
		(sheetname "/Supply/")
		(sheetfile "supply.kicad_sch")
		(attr smd)
		(fp_line
			(start 1.648 -1.651)
			(end 1.648 -1.317)
			(stroke
				(width 0.15)
				(type solid)
			)
			(layer "F.SilkS")
		)
		(fp_line
			(start -1.651 -1.651)
			(end 1.648 -1.651)
			(stroke
				(width 0.15)
				(type solid)
			)
			(layer "F.SilkS")
		)
		(fp_line
			(start -1.651 -1.651)
			(end -1.651 -1.317)
			(stroke
				(width 0.15)
				(type solid)
			)
			(layer "F.SilkS")
		)
		(fp_line
			(start 1.634 1.3)
			(end 1.634 1.634)
			(stroke
				(width 0.15)
				(type solid)
			)
			(layer "F.SilkS")
		)
		(fp_line
			(start -1.635 1.3)
			(end -1.635 1.634)
			(stroke
				(width 0.15)
				(type solid)
			)
			(layer "F.SilkS")
		)
		(fp_line
			(start -1.635 1.634)
			(end 1.634 1.634)
			(stroke
				(width 0.15)
				(type solid)
			)
			(layer "F.SilkS")
		)
		(fp_circle
			(center -1.9 -1.4)
			(end -1.85 -1.4)
			(stroke
				(width 0.15)
				(type solid)
			)
			(fill yes)
			(layer "F.SilkS")
		)
		(fp_rect
			(start -2 -1.8)
			(end 2 1.798)
			(stroke
				(width 0.05)
				(type solid)
			)
			(fill no)
			(layer "F.CrtYd")
		)
		(fp_line
			(start -1.6425 -1.4175)
			(end -1.4175 -1.6425)
			(stroke
				(width 0.15)
				(type solid)
			)
			(layer "F.Fab")
		)
		(fp_rect
			(start -1.651 -1.651)
			(end 1.648 1.648)
			(stroke
				(width 0.15)
				(type solid)
			)
			(fill no)
			(layer "F.Fab")
		)
		(fp_text user "Author: Antmicro"
			(at -8 5.9 90)
			(layer "F.Fab")
			(effects
				(font
					(size 0.7 0.7)
					(thickness 0.15)
				)
				(justify left bottom)
			)
		)
		(fp_text user "${REFERENCE}"
			(at -8 4.7 90)
			(layer "F.Fab")
			(effects
				(font
					(size 0.7 0.7)
					(thickness 0.15)
				)
				(justify left bottom)
			)
		)
		(fp_text user "License: Apache-2.0"
			(at -8 7.1 90)
			(layer "F.Fab")
			(effects
				(font
					(size 0.7 0.7)
					(thickness 0.15)
				)
				(justify left bottom)
			)
		)
		(pad "1" smd rect
			(at -1.436 -0.99 90)
			(size 0.99 0.405)
			(layers "F.Cu" "F.Mask" "F.Paste")
			(net 35 "VDC")
			(pinfunction "S")
			(pintype "passive")
		)
		(pad "2" smd rect
			(at -1.436 -0.332 90)
			(size 0.99 0.405)
			(layers "F.Cu" "F.Mask" "F.Paste")
			(net 35 "VDC")
			(pinfunction "S")
			(pintype "passive")
		)
		(pad "3" smd rect
			(at -1.436 0.33 90)
			(size 0.99 0.405)
			(layers "F.Cu" "F.Mask" "F.Paste")
			(net 35 "VDC")
			(pinfunction "S")
			(pintype "passive")
		)
		(pad "4" smd rect
			(at -1.436 0.988 90)
			(size 0.99 0.405)
			(layers "F.Cu" "F.Mask" "F.Paste")
			(net 284 "Net-(Q12-G)")
			(pinfunction "G")
			(pintype "passive")
		)
		(pad "5" smd custom
			(at 0.557 0 90)
			(size 1.725 2.235)
			(layers "F.Cu" "F.Mask" "F.Paste")
			(net 323 "/Supply/12V_aux_fused")
			(pinfunction "D")
			(pintype "passive")
			(zone_connect 2)
			(options
				(clearance outline)
				(anchor rect)
			)
			(primitives
				(gr_poly
					(pts
						(xy 0.8625 0.1275) (xy 0.8625 -0.1275) (xy 1.3725 -0.1275) (xy 1.3725 -0.5325) (xy 0.8625 -0.5325)
						(xy 0.8625 -0.7875) (xy 1.3725 -0.7875) (xy 1.3725 -1.195) (xy 0.6125 -1.195) (xy 0.6125 1.195)
						(xy 1.3725 1.195) (xy 1.3725 0.7875) (xy 0.8625 0.7875) (xy 0.8625 0.5325) (xy 1.3725 0.5325)
						(xy 1.3725 0.1275)
					)
					(width 0)
					(fill yes)
				)
			)
		)
	)
	(footprint "antmicro-footprints:C_0402_1005Metric"
		(layer "F.Cu")
		(at 120.941 186.1375 180)
		(descr "Capacitor SMD 0402")
		(tags "capacitor SMD 0402")
		(property "Reference" "C282"
			(at -1.039 -1.4425 0)
			(layer "F.SilkS")
			(effects
				(font
					(size 0.7 0.7)
					(thickness 0.15)
				)
				(justify right bottom)
			)
		)
		(property "Value" "C_100n_0402"
			(at -1.022927 2.155213 0)
			(layer "F.Fab")
			(effects
				(font
					(size 0.7 0.7)
					(thickness 0.15)
				)
				(justify right bottom)
			)
		)
		(property "Datasheet" "https://www.murata.com/products/productdetail?partno=GRM155R61H104KE14%23"
			(at 0 0 180)
			(layer "F.Fab")
			(hide yes)
			(effects
				(font
					(size 1.27 1.27)
					(thickness 0.15)
				)
			)
		)
		(property "MPN" "GRM155R61H104KE14D"
			(at 0 0 180)
			(unlocked yes)
			(layer "F.Fab")
			(hide yes)
			(effects
				(font
					(size 1 1)
					(thickness 0.15)
				)
			)
		)
		(property "Manufacturer" "Murata"
			(at 0 0 180)
			(unlocked yes)
			(layer "F.Fab")
			(hide yes)
			(effects
				(font
					(size 1 1)
					(thickness 0.15)
				)
			)
		)
		(property "License" "Apache-2.0"
			(at 0 0 180)
			(unlocked yes)
			(layer "F.Fab")
			(hide yes)
			(effects
				(font
					(size 1 1)
					(thickness 0.15)
				)
			)
		)
		(property "Author" "Antmicro"
			(at 0 0 180)
			(unlocked yes)
			(layer "F.Fab")
			(hide yes)
			(effects
				(font
					(size 1 1)
					(thickness 0.15)
				)
			)
		)
		(property "Val" "100n"
			(at 0 0 180)
			(unlocked yes)
			(layer "F.Fab")
			(hide yes)
			(effects
				(font
					(size 1 1)
					(thickness 0.15)
				)
			)
		)
		(property "Voltage" "50V"
			(at 0 0 180)
			(unlocked yes)
			(layer "F.Fab")
			(hide yes)
			(effects
				(font
					(size 1 1)
					(thickness 0.15)
				)
			)
		)
		(property "Dielectric" "X5R"
			(at 0 0 180)
			(unlocked yes)
			(layer "F.Fab")
			(hide yes)
			(effects
				(font
					(size 1 1)
					(thickness 0.15)
				)
			)
		)
		(property "Public" ""
			(at 0 0 180)
			(unlocked yes)
			(layer "F.Fab")
			(hide yes)
			(effects
				(font
					(size 1 1)
					(thickness 0.15)
				)
			)
		)
		(sheetname "/HDMI + SD Card/")
		(sheetfile "hdmi-sd-card.kicad_sch")
		(attr smd)
		(fp_rect
			(start -0.925 -0.47)
			(end 0.925 0.47)
			(stroke
				(width 0.05)
				(type default)
			)
			(fill no)
			(layer "F.CrtYd")
		)
		(fp_line
			(start 0.504 0.248)
			(end -0.494 0.248)
			(stroke
				(width 0.15)
				(type solid)
			)
			(layer "F.Fab")
		)
		(fp_line
			(start 0.504 -0.25)
			(end 0.504 0.248)
			(stroke
				(width 0.15)
				(type solid)
			)
			(layer "F.Fab")
		)
		(fp_line
			(start -0.494 0.248)
			(end -0.494 -0.25)
			(stroke
				(width 0.15)
				(type solid)
			)
			(layer "F.Fab")
		)
		(fp_line
			(start -0.494 -0.25)
			(end 0.504 -0.25)
			(stroke
				(width 0.15)
				(type solid)
			)
			(layer "F.Fab")
		)
		(fp_text user "License: Apache-2.0"
			(at -0.939 5.799 180)
			(layer "F.Fab")
			(effects
				(font
					(size 0.7 0.7)
					(thickness 0.15)
				)
				(justify left bottom)
			)
		)
		(fp_text user "${REFERENCE}"
			(at -0.939 4.599 180)
			(layer "F.Fab")
			(effects
				(font
					(size 0.7 0.7)
					(thickness 0.15)
				)
				(justify left bottom)
			)
		)
		(fp_text user "Author: Antmicro"
			(at -0.939 3.399 180)
			(layer "F.Fab")
			(effects
				(font
					(size 0.7 0.7)
					(thickness 0.15)
				)
				(justify left bottom)
			)
		)
		(pad "1" smd roundrect
			(at -0.48 0 180)
			(size 0.59 0.64)
			(layers "F.Cu" "F.Mask" "F.Paste")
			(roundrect_rratio 0.25)
			(net 810 "/HDMI + SD Card/HDMI_VDD")
			(pintype "passive")
		)
		(pad "2" smd roundrect
			(at 0.48 0 180)
			(size 0.59 0.64)
			(layers "F.Cu" "F.Mask" "F.Paste")
			(roundrect_rratio 0.25)
			(net 1 "GND")
			(pintype "passive")
		)
	)
	(footprint "antmicro-footprints:C_0402_1005Metric"
		(layer "F.Cu")
		(at 222.98 180.74 90)
		(descr "Capacitor SMD 0402")
		(tags "capacitor SMD 0402")
		(property "Reference" "C208"
			(at -6.62 0.97 90)
			(layer "F.SilkS")
			(effects
				(font
					(size 0.7 0.7)
					(thickness 0.15)
				)
				(justify left bottom)
			)
		)
		(property "Value" "C_4u7_25V_0402"
			(at -1.022927 2.155213 90)
			(layer "F.Fab")
			(effects
				(font
					(size 0.7 0.7)
					(thickness 0.15)
				)
				(justify left bottom)
			)
		)
		(property "Datasheet" "https://www.murata.com/products/productdetail?partno=GRM155C61E475ME15%23"
			(at 0 0 90)
			(layer "F.Fab")
			(hide yes)
			(effects
				(font
					(size 1.27 1.27)
					(thickness 0.15)
				)
			)
		)
		(property "MPN" "GRM155C61E475ME15J"
			(at 0 0 90)
			(unlocked yes)
			(layer "F.Fab")
			(hide yes)
			(effects
				(font
					(size 1 1)
					(thickness 0.15)
				)
			)
		)
		(property "Manufacturer" "Murata"
			(at 0 0 90)
			(unlocked yes)
			(layer "F.Fab")
			(hide yes)
			(effects
				(font
					(size 1 1)
					(thickness 0.15)
				)
			)
		)
		(property "License" "Apache-2.0"
			(at 0 0 90)
			(unlocked yes)
			(layer "F.Fab")
			(hide yes)
			(effects
				(font
					(size 1 1)
					(thickness 0.15)
				)
			)
		)
		(property "Author" "Antmicro"
			(at 0 0 90)
			(unlocked yes)
			(layer "F.Fab")
			(hide yes)
			(effects
				(font
					(size 1 1)
					(thickness 0.15)
				)
			)
		)
		(property "Val" "4u7"
			(at 0 0 90)
			(unlocked yes)
			(layer "F.Fab")
			(hide yes)
			(effects
				(font
					(size 1 1)
					(thickness 0.15)
				)
			)
		)
		(property "Voltage" "25V"
			(at 0 0 90)
			(unlocked yes)
			(layer "F.Fab")
			(hide yes)
			(effects
				(font
					(size 1 1)
					(thickness 0.15)
				)
			)
		)
		(property "Dielectric" "X5S"
			(at 0 0 90)
			(unlocked yes)
			(layer "F.Fab")
			(hide yes)
			(effects
				(font
					(size 1 1)
					(thickness 0.15)
				)
			)
		)
		(sheetname "/Supply/DC-DC VCCINT/")
		(sheetfile "dc-dc-vccint.kicad_sch")
		(attr smd)
		(fp_rect
			(start -0.925 -0.47)
			(end 0.925 0.47)
			(stroke
				(width 0.05)
				(type default)
			)
			(fill no)
			(layer "F.CrtYd")
		)
		(fp_line
			(start 0.504 -0.25)
			(end 0.504 0.248)
			(stroke
				(width 0.15)
				(type solid)
			)
			(layer "F.Fab")
		)
		(fp_line
			(start -0.494 -0.25)
			(end 0.504 -0.25)
			(stroke
				(width 0.15)
				(type solid)
			)
			(layer "F.Fab")
		)
		(fp_line
			(start 0.504 0.248)
			(end -0.494 0.248)
			(stroke
				(width 0.15)
				(type solid)
			)
			(layer "F.Fab")
		)
		(fp_line
			(start -0.494 0.248)
			(end -0.494 -0.25)
			(stroke
				(width 0.15)
				(type solid)
			)
			(layer "F.Fab")
		)
		(fp_text user "License: Apache-2.0"
			(at -0.939 5.799 90)
			(layer "F.Fab")
			(effects
				(font
					(size 0.7 0.7)
					(thickness 0.15)
				)
				(justify left bottom)
			)
		)
		(fp_text user "${REFERENCE}"
			(at -0.939 4.599 90)
			(layer "F.Fab")
			(effects
				(font
					(size 0.7 0.7)
					(thickness 0.15)
				)
				(justify left bottom)
			)
		)
		(fp_text user "Author: Antmicro"
			(at -0.939 3.399 90)
			(layer "F.Fab")
			(effects
				(font
					(size 0.7 0.7)
					(thickness 0.15)
				)
				(justify left bottom)
			)
		)
		(pad "1" smd roundrect
			(at -0.48 0 90)
			(size 0.59 0.64)
			(layers "F.Cu" "F.Mask" "F.Paste")
			(roundrect_rratio 0.25)
			(net 1 "GND")
			(pintype "passive")
		)
		(pad "2" smd roundrect
			(at 0.48 0 90)
			(size 0.59 0.64)
			(layers "F.Cu" "F.Mask" "F.Paste")
			(roundrect_rratio 0.25)
			(net 163 "/Supply/DC-DC VCCINT/V_{CC}")
			(pintype "passive")
		)
	)
	(footprint "antmicro-footprints:R_0402_1005Metric"
		(layer "F.Cu")
		(at 126.681 168.3125 90)
		(descr "Resistor SMD 0402")
		(tags "resistor SMD 0402")
		(property "Reference" "R71"
			(at -3.15 0.619 90)
			(layer "F.SilkS")
			(effects
				(font
					(size 0.7 0.7)
					(thickness 0.15)
				)
				(justify left bottom)
			)
		)
		(property "Value" "R_64k9_0402"
			(at -1.011843 1.772047 90)
			(layer "F.Fab")
			(effects
				(font
					(size 0.7 0.7)
					(thickness 0.15)
				)
				(justify left bottom)
			)
		)
		(property "Datasheet" "https://www.bourns.com/docs/product-datasheets/cr.pdf"
			(at 0 0 90)
			(layer "F.Fab")
			(hide yes)
			(effects
				(font
					(size 1.27 1.27)
					(thickness 0.15)
				)
			)
		)
		(property "MPN" "CR0402-FX-6492GLF"
			(at 0 0 90)
			(unlocked yes)
			(layer "F.Fab")
			(hide yes)
			(effects
				(font
					(size 1 1)
					(thickness 0.15)
				)
			)
		)
		(property "Manufacturer" "Bourns"
			(at 0 0 90)
			(unlocked yes)
			(layer "F.Fab")
			(hide yes)
			(effects
				(font
					(size 1 1)
					(thickness 0.15)
				)
			)
		)
		(property "License" "Apache-2.0"
			(at 0 0 90)
			(unlocked yes)
			(layer "F.Fab")
			(hide yes)
			(effects
				(font
					(size 1 1)
					(thickness 0.15)
				)
			)
		)
		(property "Author" "Antmicro"
			(at 0 0 90)
			(unlocked yes)
			(layer "F.Fab")
			(hide yes)
			(effects
				(font
					(size 1 1)
					(thickness 0.15)
				)
			)
		)
		(property "Val" "64k9"
			(at 0 0 90)
			(unlocked yes)
			(layer "F.Fab")
			(hide yes)
			(effects
				(font
					(size 1 1)
					(thickness 0.15)
				)
			)
		)
		(property "Tolerance" "1%"
			(at 0 0 90)
			(unlocked yes)
			(layer "F.Fab")
			(hide yes)
			(effects
				(font
					(size 1 1)
					(thickness 0.15)
				)
			)
		)
		(sheetname "/HDMI + SD Card/")
		(sheetfile "hdmi-sd-card.kicad_sch")
		(attr smd exclude_from_bom dnp)
		(fp_rect
			(start -0.925 -0.47)
			(end 0.925 0.47)
			(stroke
				(width 0.05)
				(type default)
			)
			(fill no)
			(layer "F.CrtYd")
		)
		(fp_rect
			(start -0.5 -0.25)
			(end 0.5 0.25)
			(stroke
				(width 0.15)
				(type solid)
			)
			(fill no)
			(layer "F.Fab")
		)
		(fp_text user "${REFERENCE}"
			(at -0.95 3.168 90)
			(layer "F.Fab")
			(effects
				(font
					(size 0.7 0.7)
					(thickness 0.15)
				)
				(justify left bottom)
			)
		)
		(fp_text user "Author: Antmicro"
			(at -0.95 4.169 90)
			(layer "F.Fab")
			(effects
				(font
					(size 0.7 0.7)
					(thickness 0.15)
				)
				(justify left bottom)
			)
		)
		(fp_text user "License: Apache-2.0"
			(at -0.95 5.169 90)
			(layer "F.Fab")
			(effects
				(font
					(size 0.7 0.7)
					(thickness 0.15)
				)
				(justify left bottom)
			)
		)
		(pad "1" smd roundrect
			(at -0.48 0 90)
			(size 0.59 0.64)
			(layers "F.Cu" "F.Mask" "F.Paste")
			(roundrect_rratio 0.25)
			(net 1 "GND")
			(pintype "passive")
		)
		(pad "2" smd roundrect
			(at 0.48 0 90)
			(size 0.59 0.64)
			(layers "F.Cu" "F.Mask" "F.Paste")
			(roundrect_rratio 0.25)
			(net 707 "/HDMI + SD Card/SWAP{slash}POL")
			(pintype "passive")
		)
	)
	(footprint "antmicro-footprints:C_0402_1005Metric"
		(layer "F.Cu")
		(at 241.774499 174.27 90)
		(descr "Capacitor SMD 0402")
		(tags "capacitor SMD 0402")
		(property "Reference" "C199"
			(at -3.63 0.775501 90)
			(layer "F.SilkS")
			(effects
				(font
					(size 0.7 0.7)
					(thickness 0.15)
				)
				(justify left bottom)
			)
		)
		(property "Value" "C_100n_0402"
			(at -1.022927 2.155213 90)
			(layer "F.Fab")
			(effects
				(font
					(size 0.7 0.7)
					(thickness 0.15)
				)
				(justify left bottom)
			)
		)
		(property "Datasheet" "https://www.murata.com/products/productdetail?partno=GRM155R61H104KE14%23"
			(at 0 0 90)
			(layer "F.Fab")
			(hide yes)
			(effects
				(font
					(size 1.27 1.27)
					(thickness 0.15)
				)
			)
		)
		(property "Manufacturer" "Murata"
			(at 0 0 90)
			(unlocked yes)
			(layer "F.Fab")
			(hide yes)
			(effects
				(font
					(size 1 1)
					(thickness 0.15)
				)
			)
		)
		(property "MPN" "GRM155R61H104KE14D"
			(at 0 0 90)
			(unlocked yes)
			(layer "F.Fab")
			(hide yes)
			(effects
				(font
					(size 1 1)
					(thickness 0.15)
				)
			)
		)
		(property "Val" "100n"
			(at 0 0 90)
			(unlocked yes)
			(layer "F.Fab")
			(hide yes)
			(effects
				(font
					(size 1 1)
					(thickness 0.15)
				)
			)
		)
		(property "License" "Apache-2.0"
			(at 0 0 90)
			(unlocked yes)
			(layer "F.Fab")
			(hide yes)
			(effects
				(font
					(size 1 1)
					(thickness 0.15)
				)
			)
		)
		(property "Author" "Antmicro"
			(at 0 0 90)
			(unlocked yes)
			(layer "F.Fab")
			(hide yes)
			(effects
				(font
					(size 1 1)
					(thickness 0.15)
				)
			)
		)
		(property "Voltage" "50V"
			(at 0 0 90)
			(unlocked yes)
			(layer "F.Fab")
			(hide yes)
			(effects
				(font
					(size 1 1)
					(thickness 0.15)
				)
			)
		)
		(property "Dielectric" "X5R"
			(at 0 0 90)
			(unlocked yes)
			(layer "F.Fab")
			(hide yes)
			(effects
				(font
					(size 1 1)
					(thickness 0.15)
				)
			)
		)
		(sheetname "/Supply/DC-DC AUX, MGT/")
		(sheetfile "dc-dc-aux-mgt.kicad_sch")
		(attr smd)
		(fp_rect
			(start -0.925 -0.47)
			(end 0.925 0.47)
			(stroke
				(width 0.05)
				(type default)
			)
			(fill no)
			(layer "F.CrtYd")
		)
		(fp_line
			(start 0.504 -0.25)
			(end 0.504 0.248)
			(stroke
				(width 0.15)
				(type solid)
			)
			(layer "F.Fab")
		)
		(fp_line
			(start -0.494 -0.25)
			(end 0.504 -0.25)
			(stroke
				(width 0.15)
				(type solid)
			)
			(layer "F.Fab")
		)
		(fp_line
			(start 0.504 0.248)
			(end -0.494 0.248)
			(stroke
				(width 0.15)
				(type solid)
			)
			(layer "F.Fab")
		)
		(fp_line
			(start -0.494 0.248)
			(end -0.494 -0.25)
			(stroke
				(width 0.15)
				(type solid)
			)
			(layer "F.Fab")
		)
		(fp_text user "License: Apache-2.0"
			(at -0.939 5.799 90)
			(layer "F.Fab")
			(effects
				(font
					(size 0.7 0.7)
					(thickness 0.15)
				)
				(justify left bottom)
			)
		)
		(fp_text user "Author: Antmicro"
			(at -0.939 3.399 90)
			(layer "F.Fab")
			(effects
				(font
					(size 0.7 0.7)
					(thickness 0.15)
				)
				(justify left bottom)
			)
		)
		(fp_text user "${REFERENCE}"
			(at -0.939 4.599 90)
			(layer "F.Fab")
			(effects
				(font
					(size 0.7 0.7)
					(thickness 0.15)
				)
				(justify left bottom)
			)
		)
		(pad "1" smd roundrect
			(at -0.48 0 90)
			(size 0.59 0.64)
			(layers "F.Cu" "F.Mask" "F.Paste")
			(roundrect_rratio 0.25)
			(net 38 "+3V3_AON")
			(pintype "passive")
		)
		(pad "2" smd roundrect
			(at 0.48 0 90)
			(size 0.59 0.64)
			(layers "F.Cu" "F.Mask" "F.Paste")
			(roundrect_rratio 0.25)
			(net 1 "GND")
			(pintype "passive")
		)
	)
	(footprint "antmicro-footprints:R_0402_1005Metric"
		(layer "F.Cu")
		(at 119.15 154.61 180)
		(descr "Resistor SMD 0402")
		(tags "resistor SMD 0402")
		(property "Reference" "R31"
			(at -5.11 -0.38 0)
			(layer "F.SilkS")
			(effects
				(font
					(size 0.7 0.7)
					(thickness 0.15)
				)
				(justify right bottom)
			)
		)
		(property "Value" "R_49k9_0402"
			(at -1.011843 1.772047 0)
			(layer "F.Fab")
			(effects
				(font
					(size 0.7 0.7)
					(thickness 0.15)
				)
				(justify right bottom)
			)
		)
		(property "Datasheet" "https://www.bourns.com/docs/product-datasheets/cr.pdf"
			(at 0 0 180)
			(layer "F.Fab")
			(hide yes)
			(effects
				(font
					(size 1.27 1.27)
					(thickness 0.15)
				)
			)
		)
		(property "MPN" "CR0402-FX-4992GLF"
			(at 0 0 180)
			(unlocked yes)
			(layer "F.Fab")
			(hide yes)
			(effects
				(font
					(size 1 1)
					(thickness 0.15)
				)
			)
		)
		(property "Manufacturer" "Bourns"
			(at 0 0 180)
			(unlocked yes)
			(layer "F.Fab")
			(hide yes)
			(effects
				(font
					(size 1 1)
					(thickness 0.15)
				)
			)
		)
		(property "License" "Apache-2.0"
			(at 0 0 180)
			(unlocked yes)
			(layer "F.Fab")
			(hide yes)
			(effects
				(font
					(size 1 1)
					(thickness 0.15)
				)
			)
		)
		(property "Author" "Antmicro"
			(at 0 0 180)
			(unlocked yes)
			(layer "F.Fab")
			(hide yes)
			(effects
				(font
					(size 1 1)
					(thickness 0.15)
				)
			)
		)
		(property "Val" "49k9"
			(at 0 0 180)
			(unlocked yes)
			(layer "F.Fab")
			(hide yes)
			(effects
				(font
					(size 1 1)
					(thickness 0.15)
				)
			)
		)
		(property "Tolerance" "1%"
			(at 0 0 180)
			(unlocked yes)
			(layer "F.Fab")
			(hide yes)
			(effects
				(font
					(size 1 1)
					(thickness 0.15)
				)
			)
		)
		(sheetname "/HDMI + SD Card/")
		(sheetfile "hdmi-sd-card.kicad_sch")
		(attr smd)
		(fp_rect
			(start -0.925 -0.47)
			(end 0.925 0.47)
			(stroke
				(width 0.05)
				(type default)
			)
			(fill no)
			(layer "F.CrtYd")
		)
		(fp_rect
			(start -0.5 -0.25)
			(end 0.5 0.25)
			(stroke
				(width 0.15)
				(type solid)
			)
			(fill no)
			(layer "F.Fab")
		)
		(fp_text user "License: Apache-2.0"
			(at -0.95 5.169 180)
			(layer "F.Fab")
			(effects
				(font
					(size 0.7 0.7)
					(thickness 0.15)
				)
				(justify left bottom)
			)
		)
		(fp_text user "Author: Antmicro"
			(at -0.95 4.169 180)
			(layer "F.Fab")
			(effects
				(font
					(size 0.7 0.7)
					(thickness 0.15)
				)
				(justify left bottom)
			)
		)
		(fp_text user "${REFERENCE}"
			(at -0.95 3.168 180)
			(layer "F.Fab")
			(effects
				(font
					(size 0.7 0.7)
					(thickness 0.15)
				)
				(justify left bottom)
			)
		)
		(pad "1" smd roundrect
			(at -0.48 0 180)
			(size 0.59 0.64)
			(layers "F.Cu" "F.Mask" "F.Paste")
			(roundrect_rratio 0.25)
			(net 677 "Net-(L7-Pad2)")
			(pintype "passive")
		)
		(pad "2" smd roundrect
			(at 0.48 0 180)
			(size 0.59 0.64)
			(layers "F.Cu" "F.Mask" "F.Paste")
			(roundrect_rratio 0.25)
			(net 322 "Net-(C300-Pad2)")
			(pintype "passive")
		)
	)
	(footprint "antmicro-footprints:C_0402_1005Metric"
		(layer "F.Cu")
		(at 121.086 176.032 90)
		(descr "Capacitor SMD 0402")
		(tags "capacitor SMD 0402")
		(property "Reference" "C278"
			(at 1.21 0.41 90)
			(layer "F.SilkS")
			(effects
				(font
					(size 0.7 0.7)
					(thickness 0.15)
				)
				(justify left bottom)
			)
		)
		(property "Value" "C_100n_0402"
			(at -1.022927 2.155213 90)
			(layer "F.Fab")
			(effects
				(font
					(size 0.7 0.7)
					(thickness 0.15)
				)
				(justify left bottom)
			)
		)
		(property "Datasheet" "https://www.murata.com/products/productdetail?partno=GRM155R61H104KE14%23"
			(at 0 0 90)
			(layer "F.Fab")
			(hide yes)
			(effects
				(font
					(size 1.27 1.27)
					(thickness 0.15)
				)
			)
		)
		(property "MPN" "GRM155R61H104KE14D"
			(at 0 0 90)
			(unlocked yes)
			(layer "F.Fab")
			(hide yes)
			(effects
				(font
					(size 1 1)
					(thickness 0.15)
				)
			)
		)
		(property "Manufacturer" "Murata"
			(at 0 0 90)
			(unlocked yes)
			(layer "F.Fab")
			(hide yes)
			(effects
				(font
					(size 1 1)
					(thickness 0.15)
				)
			)
		)
		(property "License" "Apache-2.0"
			(at 0 0 90)
			(unlocked yes)
			(layer "F.Fab")
			(hide yes)
			(effects
				(font
					(size 1 1)
					(thickness 0.15)
				)
			)
		)
		(property "Author" "Antmicro"
			(at 0 0 90)
			(unlocked yes)
			(layer "F.Fab")
			(hide yes)
			(effects
				(font
					(size 1 1)
					(thickness 0.15)
				)
			)
		)
		(property "Val" "100n"
			(at 0 0 90)
			(unlocked yes)
			(layer "F.Fab")
			(hide yes)
			(effects
				(font
					(size 1 1)
					(thickness 0.15)
				)
			)
		)
		(property "Voltage" "50V"
			(at 0 0 90)
			(unlocked yes)
			(layer "F.Fab")
			(hide yes)
			(effects
				(font
					(size 1 1)
					(thickness 0.15)
				)
			)
		)
		(property "Dielectric" "X5R"
			(at 0 0 90)
			(unlocked yes)
			(layer "F.Fab")
			(hide yes)
			(effects
				(font
					(size 1 1)
					(thickness 0.15)
				)
			)
		)
		(property "Public" ""
			(at 0 0 90)
			(unlocked yes)
			(layer "F.Fab")
			(hide yes)
			(effects
				(font
					(size 1 1)
					(thickness 0.15)
				)
			)
		)
		(sheetname "/HDMI + SD Card/")
		(sheetfile "hdmi-sd-card.kicad_sch")
		(attr smd)
		(fp_rect
			(start -0.925 -0.47)
			(end 0.925 0.47)
			(stroke
				(width 0.05)
				(type default)
			)
			(fill no)
			(layer "F.CrtYd")
		)
		(fp_line
			(start 0.504 -0.25)
			(end 0.504 0.248)
			(stroke
				(width 0.15)
				(type solid)
			)
			(layer "F.Fab")
		)
		(fp_line
			(start -0.494 -0.25)
			(end 0.504 -0.25)
			(stroke
				(width 0.15)
				(type solid)
			)
			(layer "F.Fab")
		)
		(fp_line
			(start 0.504 0.248)
			(end -0.494 0.248)
			(stroke
				(width 0.15)
				(type solid)
			)
			(layer "F.Fab")
		)
		(fp_line
			(start -0.494 0.248)
			(end -0.494 -0.25)
			(stroke
				(width 0.15)
				(type solid)
			)
			(layer "F.Fab")
		)
		(fp_text user "${REFERENCE}"
			(at -0.939 4.599 90)
			(layer "F.Fab")
			(effects
				(font
					(size 0.7 0.7)
					(thickness 0.15)
				)
				(justify left bottom)
			)
		)
		(fp_text user "Author: Antmicro"
			(at -0.939 3.399 90)
			(layer "F.Fab")
			(effects
				(font
					(size 0.7 0.7)
					(thickness 0.15)
				)
				(justify left bottom)
			)
		)
		(fp_text user "License: Apache-2.0"
			(at -0.939 5.799 90)
			(layer "F.Fab")
			(effects
				(font
					(size 0.7 0.7)
					(thickness 0.15)
				)
				(justify left bottom)
			)
		)
		(pad "1" smd roundrect
			(at -0.48 0 90)
			(size 0.59 0.64)
			(layers "F.Cu" "F.Mask" "F.Paste")
			(roundrect_rratio 0.25)
			(net 810 "/HDMI + SD Card/HDMI_VDD")
			(pintype "passive")
		)
		(pad "2" smd roundrect
			(at 0.48 0 90)
			(size 0.59 0.64)
			(layers "F.Cu" "F.Mask" "F.Paste")
			(roundrect_rratio 0.25)
			(net 1 "GND")
			(pintype "passive")
		)
	)
	(footprint "antmicro-footprints:C_0402_1005Metric"
		(layer "F.Cu")
		(at 139.674499 171.149 90)
		(descr "Capacitor SMD 0402")
		(tags "capacitor SMD 0402")
		(property "Reference" "C124"
			(at -3.801 0.525501 90)
			(layer "F.SilkS")
			(effects
				(font
					(size 0.7 0.7)
					(thickness 0.15)
				)
				(justify left bottom)
			)
		)
		(property "Value" "C_100n_0402"
			(at -1.022927 2.155213 90)
			(layer "F.Fab")
			(effects
				(font
					(size 0.7 0.7)
					(thickness 0.15)
				)
				(justify left bottom)
			)
		)
		(property "Datasheet" "https://www.murata.com/products/productdetail?partno=GRM155R61H104KE14%23"
			(at 0 0 90)
			(layer "F.Fab")
			(hide yes)
			(effects
				(font
					(size 1.27 1.27)
					(thickness 0.15)
				)
			)
		)
		(property "MPN" "GRM155R61H104KE14D"
			(at 0 0 90)
			(unlocked yes)
			(layer "F.Fab")
			(hide yes)
			(effects
				(font
					(size 1 1)
					(thickness 0.15)
				)
			)
		)
		(property "Manufacturer" "Murata"
			(at 0 0 90)
			(unlocked yes)
			(layer "F.Fab")
			(hide yes)
			(effects
				(font
					(size 1 1)
					(thickness 0.15)
				)
			)
		)
		(property "License" "Apache-2.0"
			(at 0 0 90)
			(unlocked yes)
			(layer "F.Fab")
			(hide yes)
			(effects
				(font
					(size 1 1)
					(thickness 0.15)
				)
			)
		)
		(property "Author" "Antmicro"
			(at 0 0 90)
			(unlocked yes)
			(layer "F.Fab")
			(hide yes)
			(effects
				(font
					(size 1 1)
					(thickness 0.15)
				)
			)
		)
		(property "Val" "100n"
			(at 0 0 90)
			(unlocked yes)
			(layer "F.Fab")
			(hide yes)
			(effects
				(font
					(size 1 1)
					(thickness 0.15)
				)
			)
		)
		(property "Voltage" "50V"
			(at 0 0 90)
			(unlocked yes)
			(layer "F.Fab")
			(hide yes)
			(effects
				(font
					(size 1 1)
					(thickness 0.15)
				)
			)
		)
		(property "Dielectric" "X5R"
			(at 0 0 90)
			(unlocked yes)
			(layer "F.Fab")
			(hide yes)
			(effects
				(font
					(size 1 1)
					(thickness 0.15)
				)
			)
		)
		(sheetname "/Debug FTDI + VNA/")
		(sheetfile "debug-ftdi.kicad_sch")
		(attr smd)
		(fp_rect
			(start -0.925 -0.47)
			(end 0.925 0.47)
			(stroke
				(width 0.05)
				(type default)
			)
			(fill no)
			(layer "F.CrtYd")
		)
		(fp_line
			(start 0.504 -0.25)
			(end 0.504 0.248)
			(stroke
				(width 0.15)
				(type solid)
			)
			(layer "F.Fab")
		)
		(fp_line
			(start -0.494 -0.25)
			(end 0.504 -0.25)
			(stroke
				(width 0.15)
				(type solid)
			)
			(layer "F.Fab")
		)
		(fp_line
			(start 0.504 0.248)
			(end -0.494 0.248)
			(stroke
				(width 0.15)
				(type solid)
			)
			(layer "F.Fab")
		)
		(fp_line
			(start -0.494 0.248)
			(end -0.494 -0.25)
			(stroke
				(width 0.15)
				(type solid)
			)
			(layer "F.Fab")
		)
		(fp_text user "Author: Antmicro"
			(at -0.939 3.399 90)
			(layer "F.Fab")
			(effects
				(font
					(size 0.7 0.7)
					(thickness 0.15)
				)
				(justify left bottom)
			)
		)
		(fp_text user "${REFERENCE}"
			(at -0.939 4.599 90)
			(layer "F.Fab")
			(effects
				(font
					(size 0.7 0.7)
					(thickness 0.15)
				)
				(justify left bottom)
			)
		)
		(fp_text user "License: Apache-2.0"
			(at -0.939 5.799 90)
			(layer "F.Fab")
			(effects
				(font
					(size 0.7 0.7)
					(thickness 0.15)
				)
				(justify left bottom)
			)
		)
		(pad "1" smd roundrect
			(at -0.48 0 90)
			(size 0.59 0.64)
			(layers "F.Cu" "F.Mask" "F.Paste")
			(roundrect_rratio 0.25)
			(net 1 "GND")
			(pintype "passive")
		)
		(pad "2" smd roundrect
			(at 0.48 0 90)
			(size 0.59 0.64)
			(layers "F.Cu" "F.Mask" "F.Paste")
			(roundrect_rratio 0.25)
			(net 797 "+1V8")
			(pintype "passive")
		)
	)
	(footprint "antmicro-footprints:Vishay_PowerPAK_1212-8_Single"
		(layer "F.Cu")
		(at 254.9775 102.7675 180)
		(descr "PowerPAK 1212-8 Single")
		(tags "Vishay PowerPAK 1212-8 Single")
		(property "Reference" "Q27"
			(at 2.9275 2.2675 90)
			(layer "F.SilkS")
			(effects
				(font
					(size 0.7 0.7)
					(thickness 0.15)
				)
				(justify right top)
			)
		)
		(property "Value" "SI7613DN-T1-GE3"
			(at 0 2.7 0)
			(layer "F.Fab")
			(effects
				(font
					(size 0.7 0.7)
					(thickness 0.15)
				)
				(justify right top)
			)
		)
		(property "Datasheet" "https://www.vishay.com/docs/64809/si7613dn.pdf"
			(at 0 0 0)
			(layer "F.Fab")
			(hide yes)
			(effects
				(font
					(size 1.27 1.27)
					(thickness 0.15)
				)
			)
		)
		(property "MPN" "SI7613DN-T1-GE3"
			(at 0 0 180)
			(unlocked yes)
			(layer "F.Fab")
			(hide yes)
			(effects
				(font
					(size 1 1)
					(thickness 0.15)
				)
			)
		)
		(property "Manufacturer" "Vishay"
			(at 0 0 180)
			(unlocked yes)
			(layer "F.Fab")
			(hide yes)
			(effects
				(font
					(size 1 1)
					(thickness 0.15)
				)
			)
		)
		(property "Author" "Antmicro"
			(at 0 0 180)
			(unlocked yes)
			(layer "F.Fab")
			(hide yes)
			(effects
				(font
					(size 1 1)
					(thickness 0.15)
				)
			)
		)
		(property "License" "Apache-2.0"
			(at 0 0 180)
			(unlocked yes)
			(layer "F.Fab")
			(hide yes)
			(effects
				(font
					(size 1 1)
					(thickness 0.15)
				)
			)
		)
		(sheetname "/DDR5 RDIMM/")
		(sheetfile "ddr5-rdimm.kicad_sch")
		(attr smd)
		(fp_line
			(start 1.648 -1.651)
			(end 1.648 -1.317)
			(stroke
				(width 0.15)
				(type solid)
			)
			(layer "F.SilkS")
		)
		(fp_line
			(start 1.634 1.3)
			(end 1.634 1.634)
			(stroke
				(width 0.15)
				(type solid)
			)
			(layer "F.SilkS")
		)
		(fp_line
			(start -1.635 1.634)
			(end 1.634 1.634)
			(stroke
				(width 0.15)
				(type solid)
			)
			(layer "F.SilkS")
		)
		(fp_line
			(start -1.635 1.3)
			(end -1.635 1.634)
			(stroke
				(width 0.15)
				(type solid)
			)
			(layer "F.SilkS")
		)
		(fp_line
			(start -1.651 -1.651)
			(end 1.648 -1.651)
			(stroke
				(width 0.15)
				(type solid)
			)
			(layer "F.SilkS")
		)
		(fp_line
			(start -1.651 -1.651)
			(end -1.651 -1.317)
			(stroke
				(width 0.15)
				(type solid)
			)
			(layer "F.SilkS")
		)
		(fp_circle
			(center -1.9 -1.4)
			(end -1.85 -1.4)
			(stroke
				(width 0.15)
				(type solid)
			)
			(fill yes)
			(layer "F.SilkS")
		)
		(fp_rect
			(start -2 -1.8)
			(end 2 1.798)
			(stroke
				(width 0.05)
				(type solid)
			)
			(fill no)
			(layer "F.CrtYd")
		)
		(fp_line
			(start -1.6425 -1.4175)
			(end -1.4175 -1.6425)
			(stroke
				(width 0.15)
				(type solid)
			)
			(layer "F.Fab")
		)
		(fp_rect
			(start -1.651 -1.651)
			(end 1.648 1.648)
			(stroke
				(width 0.15)
				(type solid)
			)
			(fill no)
			(layer "F.Fab")
		)
		(fp_text user "License: Apache-2.0"
			(at -8 7.1 180)
			(layer "F.Fab")
			(effects
				(font
					(size 0.7 0.7)
					(thickness 0.15)
				)
				(justify left bottom)
			)
		)
		(fp_text user "${REFERENCE}"
			(at -8 4.7 180)
			(layer "F.Fab")
			(effects
				(font
					(size 0.7 0.7)
					(thickness 0.15)
				)
				(justify left bottom)
			)
		)
		(fp_text user "Author: Antmicro"
			(at -8 5.9 180)
			(layer "F.Fab")
			(effects
				(font
					(size 0.7 0.7)
					(thickness 0.15)
				)
				(justify left bottom)
			)
		)
		(pad "1" smd rect
			(at -1.436 -0.99 180)
			(size 0.99 0.405)
			(layers "F.Cu" "F.Mask" "F.Paste")
			(net 151 "+3V3")
			(pinfunction "S")
			(pintype "passive")
		)
		(pad "2" smd rect
			(at -1.436 -0.332 180)
			(size 0.99 0.405)
			(layers "F.Cu" "F.Mask" "F.Paste")
			(net 151 "+3V3")
			(pinfunction "S")
			(pintype "passive")
		)
		(pad "3" smd rect
			(at -1.436 0.33 180)
			(size 0.99 0.405)
			(layers "F.Cu" "F.Mask" "F.Paste")
			(net 151 "+3V3")
			(pinfunction "S")
			(pintype "passive")
		)
		(pad "4" smd rect
			(at -1.436 0.988 180)
			(size 0.99 0.405)
			(layers "F.Cu" "F.Mask" "F.Paste")
			(net 807 "Net-(Q26-D)")
			(pinfunction "G")
			(pintype "passive")
		)
		(pad "5" smd custom
			(at 0.557 0 180)
			(size 1.725 2.235)
			(layers "F.Cu" "F.Mask" "F.Paste")
			(net 803 "/DDR5 RDIMM/VIN_MGMT")
			(pinfunction "D")
			(pintype "passive")
			(zone_connect 2)
			(options
				(clearance outline)
				(anchor rect)
			)
			(primitives
				(gr_poly
					(pts
						(xy 0.8625 0.1275) (xy 0.8625 -0.1275) (xy 1.3725 -0.1275) (xy 1.3725 -0.5325) (xy 0.8625 -0.5325)
						(xy 0.8625 -0.7875) (xy 1.3725 -0.7875) (xy 1.3725 -1.195) (xy 0.6125 -1.195) (xy 0.6125 1.195)
						(xy 1.3725 1.195) (xy 1.3725 0.7875) (xy 0.8625 0.7875) (xy 0.8625 0.5325) (xy 1.3725 0.5325)
						(xy 1.3725 0.1275)
					)
					(width 0)
					(fill yes)
				)
			)
		)
	)
	(footprint "antmicro-footprints:R_1206_3216Metric"
		(layer "F.Cu")
		(at 246.324499 177.549 180)
		(property "Reference" "R141"
			(at 0.1 1.2 0)
			(layer "F.SilkS")
			(effects
				(font
					(size 0.7 0.7)
					(thickness 0.15)
				)
				(justify right bottom)
			)
		)
		(property "Value" "R_0R01_1206"
			(at -2.422356 2.103591 0)
			(layer "F.Fab")
			(effects
				(font
					(size 0.7 0.7)
					(thickness 0.15)
				)
				(justify right bottom)
			)
		)
		(property "Datasheet" "https://www.yageo.com/upload/media/product/productsearch/datasheet/rchip/PYu-RL_Group_521_RoHS_L_2.pdf"
			(at 0 0 180)
			(layer "F.Fab")
			(hide yes)
			(effects
				(font
					(size 1.27 1.27)
					(thickness 0.15)
				)
			)
		)
		(property "Manufacturer" "YAGEO"
			(at 0 0 180)
			(unlocked yes)
			(layer "F.Fab")
			(hide yes)
			(effects
				(font
					(size 1 1)
					(thickness 0.15)
				)
			)
		)
		(property "MPN" "RL1206FR-7W0R01L"
			(at 0 0 180)
			(unlocked yes)
			(layer "F.Fab")
			(hide yes)
			(effects
				(font
					(size 1 1)
					(thickness 0.15)
				)
			)
		)
		(property "Val" "0R01"
			(at 0 0 180)
			(unlocked yes)
			(layer "F.Fab")
			(hide yes)
			(effects
				(font
					(size 1 1)
					(thickness 0.15)
				)
			)
		)
		(property "License" "Apache-2.0"
			(at 0 0 180)
			(unlocked yes)
			(layer "F.Fab")
			(hide yes)
			(effects
				(font
					(size 1 1)
					(thickness 0.15)
				)
			)
		)
		(property "Author" "Antmicro"
			(at 0 0 180)
			(unlocked yes)
			(layer "F.Fab")
			(hide yes)
			(effects
				(font
					(size 1 1)
					(thickness 0.15)
				)
			)
		)
		(property "Tolerance" "1%"
			(at 0 0 180)
			(unlocked yes)
			(layer "F.Fab")
			(hide yes)
			(effects
				(font
					(size 1 1)
					(thickness 0.15)
				)
			)
		)
		(sheetname "/Supply/DC-DC AUX, MGT/")
		(sheetfile "dc-dc-aux-mgt.kicad_sch")
		(attr smd)
		(fp_line
			(start 0.8 0.901)
			(end -0.8 0.901)
			(stroke
				(width 0.15)
				(type solid)
			)
			(layer "F.SilkS")
		)
		(fp_line
			(start 0.8 -0.899)
			(end -0.8 -0.899)
			(stroke
				(width 0.15)
				(type solid)
			)
			(layer "F.SilkS")
		)
		(fp_rect
			(start -2.325 -1.15)
			(end 2.325 1.15)
			(stroke
				(width 0.05)
				(type default)
			)
			(fill no)
			(layer "F.CrtYd")
		)
		(fp_line
			(start 1.6 -0.802)
			(end 1.6 0.8)
			(stroke
				(width 0.15)
				(type solid)
			)
			(layer "F.Fab")
		)
		(fp_line
			(start -1.601 0.8)
			(end 1.6 0.8)
			(stroke
				(width 0.15)
				(type solid)
			)
			(layer "F.Fab")
		)
		(fp_line
			(start -1.601 -0.802)
			(end 1.6 -0.802)
			(stroke
				(width 0.15)
				(type solid)
			)
			(layer "F.Fab")
		)
		(fp_line
			(start -1.601 -0.802)
			(end -1.601 0.8)
			(stroke
				(width 0.15)
				(type solid)
			)
			(layer "F.Fab")
		)
		(fp_text user "${REFERENCE}"
			(at -2.401 3.5 180)
			(layer "F.Fab")
			(effects
				(font
					(size 0.7 0.7)
					(thickness 0.15)
				)
				(justify left bottom)
			)
		)
		(fp_text user "Author: Antmicro"
			(at -2.401 4.899 180)
			(layer "F.Fab")
			(effects
				(font
					(size 0.7 0.7)
					(thickness 0.15)
				)
				(justify left bottom)
			)
		)
		(fp_text user "License: Apache-2.0"
			(at -2.401 6.3 180)
			(layer "F.Fab")
			(effects
				(font
					(size 0.7 0.7)
					(thickness 0.15)
				)
				(justify left bottom)
			)
		)
		(pad "1" smd roundrect
			(at -1.5 0.001 180)
			(size 1.15 1.8)
			(layers "F.Cu" "F.Mask" "F.Paste")
			(roundrect_rratio 0.25)
			(net 37 "/Supply/DC-DC AUX, MGT/1V8_local")
			(pintype "passive")
		)
		(pad "2" smd roundrect
			(at 1.5 0.001 180)
			(size 1.15 1.8)
			(layers "F.Cu" "F.Mask" "F.Paste")
			(roundrect_rratio 0.25)
			(net 797 "+1V8")
			(pintype "passive")
		)
	)
	(footprint "antmicro-footprints:R_0402_1005Metric"
		(layer "F.Cu")
		(at 119.15 148.61 180)
		(descr "Resistor SMD 0402")
		(tags "resistor SMD 0402")
		(property "Reference" "R28"
			(at -5.12 -0.405 0)
			(layer "F.SilkS")
			(effects
				(font
					(size 0.7 0.7)
					(thickness 0.15)
				)
				(justify right bottom)
			)
		)
		(property "Value" "R_49k9_0402"
			(at -1.011843 1.772047 0)
			(layer "F.Fab")
			(effects
				(font
					(size 0.7 0.7)
					(thickness 0.15)
				)
				(justify right bottom)
			)
		)
		(property "Datasheet" "https://www.bourns.com/docs/product-datasheets/cr.pdf"
			(at 0 0 180)
			(layer "F.Fab")
			(hide yes)
			(effects
				(font
					(size 1.27 1.27)
					(thickness 0.15)
				)
			)
		)
		(property "MPN" "CR0402-FX-4992GLF"
			(at 0 0 180)
			(unlocked yes)
			(layer "F.Fab")
			(hide yes)
			(effects
				(font
					(size 1 1)
					(thickness 0.15)
				)
			)
		)
		(property "Manufacturer" "Bourns"
			(at 0 0 180)
			(unlocked yes)
			(layer "F.Fab")
			(hide yes)
			(effects
				(font
					(size 1 1)
					(thickness 0.15)
				)
			)
		)
		(property "License" "Apache-2.0"
			(at 0 0 180)
			(unlocked yes)
			(layer "F.Fab")
			(hide yes)
			(effects
				(font
					(size 1 1)
					(thickness 0.15)
				)
			)
		)
		(property "Author" "Antmicro"
			(at 0 0 180)
			(unlocked yes)
			(layer "F.Fab")
			(hide yes)
			(effects
				(font
					(size 1 1)
					(thickness 0.15)
				)
			)
		)
		(property "Val" "49k9"
			(at 0 0 180)
			(unlocked yes)
			(layer "F.Fab")
			(hide yes)
			(effects
				(font
					(size 1 1)
					(thickness 0.15)
				)
			)
		)
		(property "Tolerance" "1%"
			(at 0 0 180)
			(unlocked yes)
			(layer "F.Fab")
			(hide yes)
			(effects
				(font
					(size 1 1)
					(thickness 0.15)
				)
			)
		)
		(sheetname "/HDMI + SD Card/")
		(sheetfile "hdmi-sd-card.kicad_sch")
		(attr smd)
		(fp_rect
			(start -0.925 -0.47)
			(end 0.925 0.47)
			(stroke
				(width 0.05)
				(type default)
			)
			(fill no)
			(layer "F.CrtYd")
		)
		(fp_rect
			(start -0.5 -0.25)
			(end 0.5 0.25)
			(stroke
				(width 0.15)
				(type solid)
			)
			(fill no)
			(layer "F.Fab")
		)
		(fp_text user "${REFERENCE}"
			(at -0.95 3.168 180)
			(layer "F.Fab")
			(effects
				(font
					(size 0.7 0.7)
					(thickness 0.15)
				)
				(justify left bottom)
			)
		)
		(fp_text user "Author: Antmicro"
			(at -0.95 4.169 180)
			(layer "F.Fab")
			(effects
				(font
					(size 0.7 0.7)
					(thickness 0.15)
				)
				(justify left bottom)
			)
		)
		(fp_text user "License: Apache-2.0"
			(at -0.95 5.169 180)
			(layer "F.Fab")
			(effects
				(font
					(size 0.7 0.7)
					(thickness 0.15)
				)
				(justify left bottom)
			)
		)
		(pad "1" smd roundrect
			(at -0.48 0 180)
			(size 0.59 0.64)
			(layers "F.Cu" "F.Mask" "F.Paste")
			(roundrect_rratio 0.25)
			(net 674 "Net-(L4-Pad2)")
			(pintype "passive")
		)
		(pad "2" smd roundrect
			(at 0.48 0 180)
			(size 0.59 0.64)
			(layers "F.Cu" "F.Mask" "F.Paste")
			(roundrect_rratio 0.25)
			(net 322 "Net-(C300-Pad2)")
			(pintype "passive")
		)
	)
	(footprint "antmicro-footprints:LED_0603_1608Metric_G"
		(layer "F.Cu")
		(at 139.424499 185.549 90)
		(descr "LED SMD 0603 Green")
		(tags "LED SMD 0603 Green")
		(property "Reference" "D12"
			(at -0.001 -0.901 90)
			(layer "F.SilkS")
			(hide yes)
			(effects
				(font
					(size 0.7 0.7)
					(thickness 0.15)
				)
				(justify left bottom)
			)
		)
		(property "Value" "LED_G_0603_KP-1608CGCK"
			(at -0.001 1.599 90)
			(layer "F.Fab")
			(effects
				(font
					(size 0.7 0.7)
					(thickness 0.15)
				)
				(justify left bottom)
			)
		)
		(property "Datasheet" "http://www.kingbright.com/attachments/file/psearch//000/00/00/KP-1608CGCK(Ver.23B).pdf"
			(at 0 0 90)
			(layer "F.Fab")
			(hide yes)
			(effects
				(font
					(size 1.27 1.27)
					(thickness 0.15)
				)
			)
		)
		(property "MPN" "KP-1608CGCK"
			(at 0 0 90)
			(unlocked yes)
			(layer "F.Fab")
			(hide yes)
			(effects
				(font
					(size 1 1)
					(thickness 0.15)
				)
			)
		)
		(property "Manufacturer" "Kingbright"
			(at 0 0 90)
			(unlocked yes)
			(layer "F.Fab")
			(hide yes)
			(effects
				(font
					(size 1 1)
					(thickness 0.15)
				)
			)
		)
		(property "Color" "Green"
			(at 0 0 90)
			(unlocked yes)
			(layer "F.Fab")
			(hide yes)
			(effects
				(font
					(size 1 1)
					(thickness 0.15)
				)
			)
		)
		(property "Author" "Antmicro"
			(at 0 0 90)
			(unlocked yes)
			(layer "F.Fab")
			(hide yes)
			(effects
				(font
					(size 1 1)
					(thickness 0.15)
				)
			)
		)
		(property "License" "Apache-2.0"
			(at 0 0 90)
			(unlocked yes)
			(layer "F.Fab")
			(hide yes)
			(effects
				(font
					(size 1 1)
					(thickness 0.15)
				)
			)
		)
		(sheetname "/Debug FTDI + VNA/")
		(sheetfile "debug-ftdi.kicad_sch")
		(attr smd)
		(fp_line
			(start 0.22 -0.35)
			(end -0.22 -0.35)
			(stroke
				(width 0.15)
				(type solid)
			)
			(layer "F.SilkS")
		)
		(fp_line
			(start -1.18 -0.319)
			(end -1.18 0.321)
			(stroke
				(width 0.15)
				(type solid)
			)
			(layer "F.SilkS")
		)
		(fp_line
			(start 0.105328 0.001008)
			(end 0.24 0.001)
			(stroke
				(width 0.1)
				(type solid)
			)
			(layer "F.SilkS")
		)
		(fp_line
			(start -0.094672 0.001008)
			(end 0.105328 -0.198992)
			(stroke
				(width 0.1)
				(type solid)
			)
			(layer "F.SilkS")
		)
		(fp_line
			(start -0.094672 0.001008)
			(end -0.24 0.001008)
			(stroke
				(width 0.1)
				(type solid)
			)
			(layer "F.SilkS")
		)
		(fp_line
			(start 0.105328 0.201008)
			(end 0.105328 -0.198992)
			(stroke
				(width 0.1)
				(type solid)
			)
			(layer "F.SilkS")
		)
		(fp_line
			(start 0.105328 0.201008)
			(end -0.094672 0.001008)
			(stroke
				(width 0.1)
				(type solid)
			)
			(layer "F.SilkS")
		)
		(fp_line
			(start -0.094672 0.201008)
			(end -0.094672 -0.198992)
			(stroke
				(width 0.1)
				(type solid)
			)
			(layer "F.SilkS")
		)
		(fp_line
			(start 0.22 0.35)
			(end -0.22 0.35)
			(stroke
				(width 0.15)
				(type solid)
			)
			(layer "F.SilkS")
		)
		(fp_rect
			(start 1.25 0.65)
			(end -1.25 -0.65)
			(stroke
				(width 0.05)
				(type solid)
			)
			(fill no)
			(layer "F.CrtYd")
		)
		(fp_line
			(start 0.201 -0.202)
			(end -0.101 0)
			(stroke
				(width 0.15)
				(type solid)
			)
			(layer "F.Fab")
		)
		(fp_line
			(start -0.199 -0.202)
			(end -0.199 0.1)
			(stroke
				(width 0.15)
				(type solid)
			)
			(layer "F.Fab")
		)
		(fp_line
			(start 0.599 0)
			(end 0.201 0)
			(stroke
				(width 0.15)
				(type solid)
			)
			(layer "F.Fab")
		)
		(fp_line
			(start 0.201 0)
			(end 0.201 -0.202)
			(stroke
				(width 0.15)
				(type solid)
			)
			(layer "F.Fab")
		)
		(fp_line
			(start -0.101 0)
			(end 0.201 0.2)
			(stroke
				(width 0.15)
				(type solid)
			)
			(layer "F.Fab")
		)
		(fp_line
			(start -0.199 0)
			(end -0.597 0)
			(stroke
				(width 0.15)
				(type solid)
			)
			(layer "F.Fab")
		)
		(fp_line
			(start 0.201 0.2)
			(end 0.201 0)
			(stroke
				(width 0.15)
				(type solid)
			)
			(layer "F.Fab")
		)
		(fp_line
			(start -0.199 0.2)
			(end -0.199 0.1)
			(stroke
				(width 0.15)
				(type solid)
			)
			(layer "F.Fab")
		)
		(fp_rect
			(start 0.848 0.4)
			(end -0.85 -0.402)
			(stroke
				(width 0.15)
				(type solid)
			)
			(fill no)
			(layer "F.Fab")
		)
		(fp_text user "License: Apache-2.0"
			(at -1.4224 3.599 90)
			(layer "F.Fab")
			(effects
				(font
					(size 0.7 0.7)
					(thickness 0.15)
				)
				(justify left bottom)
			)
		)
		(fp_text user "${REFERENCE}"
			(at -1.4224 5.999 90)
			(layer "F.Fab")
			(effects
				(font
					(size 0.7 0.7)
					(thickness 0.15)
				)
				(justify left bottom)
			)
		)
		(fp_text user "Author: Antmicro"
			(at -1.4224 4.799 90)
			(layer "F.Fab")
			(effects
				(font
					(size 0.7 0.7)
					(thickness 0.15)
				)
				(justify left bottom)
			)
		)
		(pad "1" smd roundrect
			(at -0.7 0 270)
			(size 0.8 1)
			(layers "F.Cu" "F.Mask" "F.Paste")
			(roundrect_rratio 0.2)
			(net 1 "GND")
			(pinfunction "C")
			(pintype "passive")
		)
		(pad "2" smd roundrect
			(at 0.7 0 270)
			(size 0.8 1)
			(layers "F.Cu" "F.Mask" "F.Paste")
			(roundrect_rratio 0.2)
			(net 42 "Net-(D12-A)")
			(pinfunction "A")
			(pintype "passive")
		)
	)
	(footprint "antmicro-footprints:TP_SMD_0.75mm"
		(layer "F.Cu")
		(at 233.875 132.075)
		(property "Reference" "TP27"
			(at -2.25 1.525 0)
			(layer "F.SilkS")
			(effects
				(font
					(size 0.7 0.7)
					(thickness 0.15)
				)
				(justify left bottom)
			)
		)
		(property "Value" "TP_0.75mm_SMD"
			(at 0 1.2 0)
			(layer "F.Fab")
			(effects
				(font
					(size 0.7 0.7)
					(thickness 0.15)
				)
				(justify left bottom)
			)
		)
		(property "MPN" ""
			(at 0 0 0)
			(unlocked yes)
			(layer "F.Fab")
			(hide yes)
			(effects
				(font
					(size 1 1)
					(thickness 0.15)
				)
			)
		)
		(property "Manufacturer" ""
			(at 0 0 0)
			(unlocked yes)
			(layer "F.Fab")
			(hide yes)
			(effects
				(font
					(size 1 1)
					(thickness 0.15)
				)
			)
		)
		(property "Author" "Antmicro"
			(at 0 0 0)
			(unlocked yes)
			(layer "F.Fab")
			(hide yes)
			(effects
				(font
					(size 1 1)
					(thickness 0.15)
				)
			)
		)
		(property "License" "Apache-2.0"
			(at 0 0 0)
			(unlocked yes)
			(layer "F.Fab")
			(hide yes)
			(effects
				(font
					(size 1 1)
					(thickness 0.15)
				)
			)
		)
		(sheetname "/I^{2}C + I3C/")
		(sheetfile "i2c.kicad_sch")
		(attr exclude_from_pos_files exclude_from_bom)
		(fp_circle
			(center 0 0)
			(end 0.475 0)
			(stroke
				(width 0.05)
				(type default)
			)
			(fill no)
			(layer "F.CrtYd")
		)
		(fp_text user "License: Apache-2.0"
			(at -0.4 5.101 0)
			(layer "F.Fab")
			(effects
				(font
					(size 0.7 0.7)
					(thickness 0.15)
				)
				(justify left bottom)
			)
		)
		(fp_text user "Author: Antmicro"
			(at -0.4 3.901 0)
			(layer "F.Fab")
			(effects
				(font
					(size 0.7 0.7)
					(thickness 0.15)
				)
				(justify left bottom)
			)
		)
		(fp_text user "${REFERENCE}"
			(at -0.4 2.7 0)
			(layer "F.Fab")
			(effects
				(font
					(size 0.7 0.7)
					(thickness 0.15)
				)
				(justify left bottom)
			)
		)
		(pad "1" smd circle
			(at 0 0)
			(size 0.75 0.75)
			(layers "F.Cu" "F.Mask")
			(net 473 "Net-(R126-Pad1)")
			(pinfunction "1")
			(pintype "passive")
		)
	)
	(footprint "antmicro-footprints:C_0402_1005Metric"
		(layer "F.Cu")
		(at 118.19 146.61)
		(descr "Capacitor SMD 0402")
		(tags "capacitor SMD 0402")
		(property "Reference" "C301"
			(at -3.74 0.39 0)
			(layer "F.SilkS")
			(effects
				(font
					(size 0.7 0.7)
					(thickness 0.15)
				)
				(justify left bottom)
			)
		)
		(property "Value" "C_10u_6.3V_0402"
			(at -1.022927 2.155213 0)
			(layer "F.Fab")
			(effects
				(font
					(size 0.7 0.7)
					(thickness 0.15)
				)
				(justify left bottom)
			)
		)
		(property "Datasheet" "https://www.murata.com/products/productdetail?partno=GRM155R60J106ME15%23"
			(at 0 0 0)
			(layer "F.Fab")
			(hide yes)
			(effects
				(font
					(size 1.27 1.27)
					(thickness 0.15)
				)
			)
		)
		(property "MPN" "GRM155R60J106ME15D"
			(at 0 0 0)
			(unlocked yes)
			(layer "F.Fab")
			(hide yes)
			(effects
				(font
					(size 1 1)
					(thickness 0.15)
				)
			)
		)
		(property "Manufacturer" "Murata"
			(at 0 0 0)
			(unlocked yes)
			(layer "F.Fab")
			(hide yes)
			(effects
				(font
					(size 1 1)
					(thickness 0.15)
				)
			)
		)
		(property "License" "Apache-2.0"
			(at 0 0 0)
			(unlocked yes)
			(layer "F.Fab")
			(hide yes)
			(effects
				(font
					(size 1 1)
					(thickness 0.15)
				)
			)
		)
		(property "Author" "Antmicro"
			(at 0 0 0)
			(unlocked yes)
			(layer "F.Fab")
			(hide yes)
			(effects
				(font
					(size 1 1)
					(thickness 0.15)
				)
			)
		)
		(property "Val" "10u"
			(at 0 0 0)
			(unlocked yes)
			(layer "F.Fab")
			(hide yes)
			(effects
				(font
					(size 1 1)
					(thickness 0.15)
				)
			)
		)
		(property "Voltage" "6.3V"
			(at 0 0 0)
			(unlocked yes)
			(layer "F.Fab")
			(hide yes)
			(effects
				(font
					(size 1 1)
					(thickness 0.15)
				)
			)
		)
		(property "Dielectric" "X5R"
			(at 0 0 0)
			(unlocked yes)
			(layer "F.Fab")
			(hide yes)
			(effects
				(font
					(size 1 1)
					(thickness 0.15)
				)
			)
		)
		(sheetname "/HDMI + SD Card/")
		(sheetfile "hdmi-sd-card.kicad_sch")
		(attr smd)
		(fp_rect
			(start -0.925 -0.47)
			(end 0.925 0.47)
			(stroke
				(width 0.05)
				(type default)
			)
			(fill no)
			(layer "F.CrtYd")
		)
		(fp_line
			(start -0.494 -0.25)
			(end 0.504 -0.25)
			(stroke
				(width 0.15)
				(type solid)
			)
			(layer "F.Fab")
		)
		(fp_line
			(start -0.494 0.248)
			(end -0.494 -0.25)
			(stroke
				(width 0.15)
				(type solid)
			)
			(layer "F.Fab")
		)
		(fp_line
			(start 0.504 -0.25)
			(end 0.504 0.248)
			(stroke
				(width 0.15)
				(type solid)
			)
			(layer "F.Fab")
		)
		(fp_line
			(start 0.504 0.248)
			(end -0.494 0.248)
			(stroke
				(width 0.15)
				(type solid)
			)
			(layer "F.Fab")
		)
		(fp_text user "Author: Antmicro"
			(at -0.939 3.399 0)
			(layer "F.Fab")
			(effects
				(font
					(size 0.7 0.7)
					(thickness 0.15)
				)
				(justify left bottom)
			)
		)
		(fp_text user "${REFERENCE}"
			(at -0.939 4.599 0)
			(layer "F.Fab")
			(effects
				(font
					(size 0.7 0.7)
					(thickness 0.15)
				)
				(justify left bottom)
			)
		)
		(fp_text user "License: Apache-2.0"
			(at -0.939 5.799 0)
			(layer "F.Fab")
			(effects
				(font
					(size 0.7 0.7)
					(thickness 0.15)
				)
				(justify left bottom)
			)
		)
		(pad "1" smd roundrect
			(at -0.48 0)
			(size 0.59 0.64)
			(layers "F.Cu" "F.Mask" "F.Paste")
			(roundrect_rratio 0.25)
			(net 1 "GND")
			(pintype "passive")
		)
		(pad "2" smd roundrect
			(at 0.48 0)
			(size 0.59 0.64)
			(layers "F.Cu" "F.Mask" "F.Paste")
			(roundrect_rratio 0.25)
			(net 322 "Net-(C300-Pad2)")
			(pintype "passive")
		)
	)
	(footprint "antmicro-footprints:TP_SMD_0.75mm"
		(layer "F.Cu")
		(at 155.43 161.799999)
		(property "Reference" "TP6"
			(at -2.6 0.45 0)
			(layer "F.SilkS")
			(effects
				(font
					(size 0.7 0.7)
					(thickness 0.15)
				)
				(justify left bottom)
			)
		)
		(property "Value" "TP_0.75mm_SMD"
			(at 0 1.2 0)
			(layer "F.Fab")
			(effects
				(font
					(size 0.7 0.7)
					(thickness 0.15)
				)
				(justify left bottom)
			)
		)
		(property "MPN" ""
			(at 0 0 0)
			(unlocked yes)
			(layer "F.Fab")
			(hide yes)
			(effects
				(font
					(size 1 1)
					(thickness 0.15)
				)
			)
		)
		(property "Manufacturer" ""
			(at 0 0 0)
			(unlocked yes)
			(layer "F.Fab")
			(hide yes)
			(effects
				(font
					(size 1 1)
					(thickness 0.15)
				)
			)
		)
		(property "Author" "Antmicro"
			(at 0 0 0)
			(unlocked yes)
			(layer "F.Fab")
			(hide yes)
			(effects
				(font
					(size 1 1)
					(thickness 0.15)
				)
			)
		)
		(property "License" "Apache-2.0"
			(at 0 0 0)
			(unlocked yes)
			(layer "F.Fab")
			(hide yes)
			(effects
				(font
					(size 1 1)
					(thickness 0.15)
				)
			)
		)
		(sheetname "/FPGA MGT Interface/")
		(sheetfile "fpga-mgt.kicad_sch")
		(attr exclude_from_pos_files exclude_from_bom)
		(fp_circle
			(center 0 0)
			(end 0.475 0)
			(stroke
				(width 0.05)
				(type default)
			)
			(fill no)
			(layer "F.CrtYd")
		)
		(fp_text user "Author: Antmicro"
			(at -0.4 3.901 0)
			(layer "F.Fab")
			(effects
				(font
					(size 0.7 0.7)
					(thickness 0.15)
				)
				(justify left bottom)
			)
		)
		(fp_text user "${REFERENCE}"
			(at -0.4 2.7 0)
			(layer "F.Fab")
			(effects
				(font
					(size 0.7 0.7)
					(thickness 0.15)
				)
				(justify left bottom)
			)
		)
		(fp_text user "License: Apache-2.0"
			(at -0.4 5.101 0)
			(layer "F.Fab")
			(effects
				(font
					(size 0.7 0.7)
					(thickness 0.15)
				)
				(justify left bottom)
			)
		)
		(pad "1" smd circle
			(at 0 0)
			(size 0.75 0.75)
			(layers "F.Cu" "F.Mask")
			(net 542 "Net-(U39-RATE1)")
			(pinfunction "1")
			(pintype "passive")
		)
	)
	(footprint "antmicro-footprints:C_0402_1005Metric"
		(layer "F.Cu")
		(at 241.774499 164.4 90)
		(descr "Capacitor SMD 0402")
		(tags "capacitor SMD 0402")
		(property "Reference" "C207"
			(at 0.875 0.425501 90)
			(layer "F.SilkS")
			(effects
				(font
					(size 0.7 0.7)
					(thickness 0.15)
				)
				(justify left bottom)
			)
		)
		(property "Value" "C_100n_0402"
			(at -1.022927 2.155213 90)
			(layer "F.Fab")
			(effects
				(font
					(size 0.7 0.7)
					(thickness 0.15)
				)
				(justify left bottom)
			)
		)
		(property "Datasheet" "https://www.murata.com/products/productdetail?partno=GRM155R61H104KE14%23"
			(at 0 0 90)
			(layer "F.Fab")
			(hide yes)
			(effects
				(font
					(size 1.27 1.27)
					(thickness 0.15)
				)
			)
		)
		(property "Manufacturer" "Murata"
			(at 0 0 90)
			(unlocked yes)
			(layer "F.Fab")
			(hide yes)
			(effects
				(font
					(size 1 1)
					(thickness 0.15)
				)
			)
		)
		(property "MPN" "GRM155R61H104KE14D"
			(at 0 0 90)
			(unlocked yes)
			(layer "F.Fab")
			(hide yes)
			(effects
				(font
					(size 1 1)
					(thickness 0.15)
				)
			)
		)
		(property "Val" "100n"
			(at 0 0 90)
			(unlocked yes)
			(layer "F.Fab")
			(hide yes)
			(effects
				(font
					(size 1 1)
					(thickness 0.15)
				)
			)
		)
		(property "License" "Apache-2.0"
			(at 0 0 90)
			(unlocked yes)
			(layer "F.Fab")
			(hide yes)
			(effects
				(font
					(size 1 1)
					(thickness 0.15)
				)
			)
		)
		(property "Author" "Antmicro"
			(at 0 0 90)
			(unlocked yes)
			(layer "F.Fab")
			(hide yes)
			(effects
				(font
					(size 1 1)
					(thickness 0.15)
				)
			)
		)
		(property "Voltage" "50V"
			(at 0 0 90)
			(unlocked yes)
			(layer "F.Fab")
			(hide yes)
			(effects
				(font
					(size 1 1)
					(thickness 0.15)
				)
			)
		)
		(property "Dielectric" "X5R"
			(at 0 0 90)
			(unlocked yes)
			(layer "F.Fab")
			(hide yes)
			(effects
				(font
					(size 1 1)
					(thickness 0.15)
				)
			)
		)
		(sheetname "/Supply/")
		(sheetfile "supply.kicad_sch")
		(attr smd)
		(fp_rect
			(start -0.925 -0.47)
			(end 0.925 0.47)
			(stroke
				(width 0.05)
				(type default)
			)
			(fill no)
			(layer "F.CrtYd")
		)
		(fp_line
			(start 0.504 -0.25)
			(end 0.504 0.248)
			(stroke
				(width 0.15)
				(type solid)
			)
			(layer "F.Fab")
		)
		(fp_line
			(start -0.494 -0.25)
			(end 0.504 -0.25)
			(stroke
				(width 0.15)
				(type solid)
			)
			(layer "F.Fab")
		)
		(fp_line
			(start 0.504 0.248)
			(end -0.494 0.248)
			(stroke
				(width 0.15)
				(type solid)
			)
			(layer "F.Fab")
		)
		(fp_line
			(start -0.494 0.248)
			(end -0.494 -0.25)
			(stroke
				(width 0.15)
				(type solid)
			)
			(layer "F.Fab")
		)
		(fp_text user "License: Apache-2.0"
			(at -0.939 5.799 90)
			(layer "F.Fab")
			(effects
				(font
					(size 0.7 0.7)
					(thickness 0.15)
				)
				(justify left bottom)
			)
		)
		(fp_text user "${REFERENCE}"
			(at -0.939 4.599 90)
			(layer "F.Fab")
			(effects
				(font
					(size 0.7 0.7)
					(thickness 0.15)
				)
				(justify left bottom)
			)
		)
		(fp_text user "Author: Antmicro"
			(at -0.939 3.399 90)
			(layer "F.Fab")
			(effects
				(font
					(size 0.7 0.7)
					(thickness 0.15)
				)
				(justify left bottom)
			)
		)
		(pad "1" smd roundrect
			(at -0.48 0 90)
			(size 0.59 0.64)
			(layers "F.Cu" "F.Mask" "F.Paste")
			(roundrect_rratio 0.25)
			(net 38 "+3V3_AON")
			(pintype "passive")
		)
		(pad "2" smd roundrect
			(at 0.48 0 90)
			(size 0.59 0.64)
			(layers "F.Cu" "F.Mask" "F.Paste")
			(roundrect_rratio 0.25)
			(net 1 "GND")
			(pintype "passive")
		)
	)
	(footprint "antmicro-footprints:C_0402_1005Metric"
		(layer "F.Cu")
		(at 233.465001 180.725 90)
		(descr "Capacitor SMD 0402")
		(tags "capacitor SMD 0402")
		(property "Reference" "C210"
			(at -3.175 1.804999 90)
			(layer "F.SilkS")
			(effects
				(font
					(size 0.7 0.7)
					(thickness 0.15)
				)
				(justify left bottom)
			)
		)
		(property "Value" "C_4u7_25V_0402"
			(at -1.022927 2.155213 90)
			(layer "F.Fab")
			(effects
				(font
					(size 0.7 0.7)
					(thickness 0.15)
				)
				(justify left bottom)
			)
		)
		(property "Datasheet" "https://www.murata.com/products/productdetail?partno=GRM155C61E475ME15%23"
			(at 0 0 90)
			(layer "F.Fab")
			(hide yes)
			(effects
				(font
					(size 1.27 1.27)
					(thickness 0.15)
				)
			)
		)
		(property "MPN" "GRM155C61E475ME15J"
			(at 0 0 90)
			(unlocked yes)
			(layer "F.Fab")
			(hide yes)
			(effects
				(font
					(size 1 1)
					(thickness 0.15)
				)
			)
		)
		(property "Manufacturer" "Murata"
			(at 0 0 90)
			(unlocked yes)
			(layer "F.Fab")
			(hide yes)
			(effects
				(font
					(size 1 1)
					(thickness 0.15)
				)
			)
		)
		(property "License" "Apache-2.0"
			(at 0 0 90)
			(unlocked yes)
			(layer "F.Fab")
			(hide yes)
			(effects
				(font
					(size 1 1)
					(thickness 0.15)
				)
			)
		)
		(property "Author" "Antmicro"
			(at 0 0 90)
			(unlocked yes)
			(layer "F.Fab")
			(hide yes)
			(effects
				(font
					(size 1 1)
					(thickness 0.15)
				)
			)
		)
		(property "Val" "4u7"
			(at 0 0 90)
			(unlocked yes)
			(layer "F.Fab")
			(hide yes)
			(effects
				(font
					(size 1 1)
					(thickness 0.15)
				)
			)
		)
		(property "Voltage" "25V"
			(at 0 0 90)
			(unlocked yes)
			(layer "F.Fab")
			(hide yes)
			(effects
				(font
					(size 1 1)
					(thickness 0.15)
				)
			)
		)
		(property "Dielectric" "X5S"
			(at 0 0 90)
			(unlocked yes)
			(layer "F.Fab")
			(hide yes)
			(effects
				(font
					(size 1 1)
					(thickness 0.15)
				)
			)
		)
		(sheetname "/Supply/DC-DC VCCINT/")
		(sheetfile "dc-dc-vccint.kicad_sch")
		(attr smd)
		(fp_rect
			(start -0.925 -0.47)
			(end 0.925 0.47)
			(stroke
				(width 0.05)
				(type default)
			)
			(fill no)
			(layer "F.CrtYd")
		)
		(fp_line
			(start 0.504 -0.25)
			(end 0.504 0.248)
			(stroke
				(width 0.15)
				(type solid)
			)
			(layer "F.Fab")
		)
		(fp_line
			(start -0.494 -0.25)
			(end 0.504 -0.25)
			(stroke
				(width 0.15)
				(type solid)
			)
			(layer "F.Fab")
		)
		(fp_line
			(start 0.504 0.248)
			(end -0.494 0.248)
			(stroke
				(width 0.15)
				(type solid)
			)
			(layer "F.Fab")
		)
		(fp_line
			(start -0.494 0.248)
			(end -0.494 -0.25)
			(stroke
				(width 0.15)
				(type solid)
			)
			(layer "F.Fab")
		)
		(fp_text user "${REFERENCE}"
			(at -0.939 4.599 90)
			(layer "F.Fab")
			(effects
				(font
					(size 0.7 0.7)
					(thickness 0.15)
				)
				(justify left bottom)
			)
		)
		(fp_text user "Author: Antmicro"
			(at -0.939 3.399 90)
			(layer "F.Fab")
			(effects
				(font
					(size 0.7 0.7)
					(thickness 0.15)
				)
				(justify left bottom)
			)
		)
		(fp_text user "License: Apache-2.0"
			(at -0.939 5.799 90)
			(layer "F.Fab")
			(effects
				(font
					(size 0.7 0.7)
					(thickness 0.15)
				)
				(justify left bottom)
			)
		)
		(pad "1" smd roundrect
			(at -0.48 0 90)
			(size 0.59 0.64)
			(layers "F.Cu" "F.Mask" "F.Paste")
			(roundrect_rratio 0.25)
			(net 1 "GND")
			(pintype "passive")
		)
		(pad "2" smd roundrect
			(at 0.48 0 90)
			(size 0.59 0.64)
			(layers "F.Cu" "F.Mask" "F.Paste")
			(roundrect_rratio 0.25)
			(net 163 "/Supply/DC-DC VCCINT/V_{CC}")
			(pintype "passive")
		)
	)
	(footprint "antmicro-footprints:Vishay_PowerPAK_1212-8_Single"
		(layer "F.Cu")
		(at 247.1255 121.25 -90)
		(descr "PowerPAK 1212-8 Single")
		(tags "Vishay PowerPAK 1212-8 Single")
		(property "Reference" "Q29"
			(at 3.05 -1.9745 180)
			(layer "F.SilkS")
			(effects
				(font
					(size 0.7 0.7)
					(thickness 0.15)
				)
				(justify right bottom)
			)
		)
		(property "Value" "SI7613DN-T1-GE3"
			(at 0 2.7 90)
			(layer "F.Fab")
			(effects
				(font
					(size 0.7 0.7)
					(thickness 0.15)
				)
				(justify right bottom)
			)
		)
		(property "Datasheet" "https://www.vishay.com/docs/64809/si7613dn.pdf"
			(at 0 0 90)
			(layer "F.Fab")
			(hide yes)
			(effects
				(font
					(size 1.27 1.27)
					(thickness 0.15)
				)
			)
		)
		(property "MPN" "SI7613DN-T1-GE3"
			(at 0 0 270)
			(unlocked yes)
			(layer "F.Fab")
			(hide yes)
			(effects
				(font
					(size 1 1)
					(thickness 0.15)
				)
			)
		)
		(property "Manufacturer" "Vishay"
			(at 0 0 270)
			(unlocked yes)
			(layer "F.Fab")
			(hide yes)
			(effects
				(font
					(size 1 1)
					(thickness 0.15)
				)
			)
		)
		(property "Author" "Antmicro"
			(at 0 0 270)
			(unlocked yes)
			(layer "F.Fab")
			(hide yes)
			(effects
				(font
					(size 1 1)
					(thickness 0.15)
				)
			)
		)
		(property "License" "Apache-2.0"
			(at 0 0 270)
			(unlocked yes)
			(layer "F.Fab")
			(hide yes)
			(effects
				(font
					(size 1 1)
					(thickness 0.15)
				)
			)
		)
		(sheetname "/Supply/")
		(sheetfile "supply.kicad_sch")
		(attr smd)
		(fp_line
			(start -1.635 1.634)
			(end 1.634 1.634)
			(stroke
				(width 0.15)
				(type solid)
			)
			(layer "F.SilkS")
		)
		(fp_line
			(start -1.635 1.3)
			(end -1.635 1.634)
			(stroke
				(width 0.15)
				(type solid)
			)
			(layer "F.SilkS")
		)
		(fp_line
			(start 1.634 1.3)
			(end 1.634 1.634)
			(stroke
				(width 0.15)
				(type solid)
			)
			(layer "F.SilkS")
		)
		(fp_line
			(start -1.651 -1.651)
			(end -1.651 -1.317)
			(stroke
				(width 0.15)
				(type solid)
			)
			(layer "F.SilkS")
		)
		(fp_line
			(start -1.651 -1.651)
			(end 1.648 -1.651)
			(stroke
				(width 0.15)
				(type solid)
			)
			(layer "F.SilkS")
		)
		(fp_line
			(start 1.648 -1.651)
			(end 1.648 -1.317)
			(stroke
				(width 0.15)
				(type solid)
			)
			(layer "F.SilkS")
		)
		(fp_circle
			(center -1.9 -1.4)
			(end -1.85 -1.4)
			(stroke
				(width 0.15)
				(type solid)
			)
			(fill yes)
			(layer "F.SilkS")
		)
		(fp_rect
			(start -2 -1.8)
			(end 2 1.798)
			(stroke
				(width 0.05)
				(type solid)
			)
			(fill no)
			(layer "F.CrtYd")
		)
		(fp_line
			(start -1.6425 -1.4175)
			(end -1.4175 -1.6425)
			(stroke
				(width 0.15)
				(type solid)
			)
			(layer "F.Fab")
		)
		(fp_rect
			(start -1.651 -1.651)
			(end 1.648 1.648)
			(stroke
				(width 0.15)
				(type solid)
			)
			(fill no)
			(layer "F.Fab")
		)
		(fp_text user "License: Apache-2.0"
			(at -8 7.1 270)
			(layer "F.Fab")
			(effects
				(font
					(size 0.7 0.7)
					(thickness 0.15)
				)
				(justify left bottom)
			)
		)
		(fp_text user "${REFERENCE}"
			(at -8 4.7 270)
			(layer "F.Fab")
			(effects
				(font
					(size 0.7 0.7)
					(thickness 0.15)
				)
				(justify left bottom)
			)
		)
		(fp_text user "Author: Antmicro"
			(at -8 5.9 270)
			(layer "F.Fab")
			(effects
				(font
					(size 0.7 0.7)
					(thickness 0.15)
				)
				(justify left bottom)
			)
		)
		(pad "1" smd rect
			(at -1.436 -0.99 270)
			(size 0.99 0.405)
			(layers "F.Cu" "F.Mask" "F.Paste")
			(net 35 "VDC")
			(pinfunction "S")
			(pintype "passive")
		)
		(pad "2" smd rect
			(at -1.436 -0.332 270)
			(size 0.99 0.405)
			(layers "F.Cu" "F.Mask" "F.Paste")
			(net 35 "VDC")
			(pinfunction "S")
			(pintype "passive")
		)
		(pad "3" smd rect
			(at -1.436 0.33 270)
			(size 0.99 0.405)
			(layers "F.Cu" "F.Mask" "F.Paste")
			(net 35 "VDC")
			(pinfunction "S")
			(pintype "passive")
		)
		(pad "4" smd rect
			(at -1.436 0.988 270)
			(size 0.99 0.405)
			(layers "F.Cu" "F.Mask" "F.Paste")
			(net 813 "Net-(Q28-D)")
			(pinfunction "G")
			(pintype "passive")
		)
		(pad "5" smd custom
			(at 0.557 0 270)
			(size 1.725 2.235)
			(layers "F.Cu" "F.Mask" "F.Paste")
			(net 814 "Net-(Q29-D)")
			(pinfunction "D")
			(pintype "passive")
			(zone_connect 2)
			(options
				(clearance outline)
				(anchor rect)
			)
			(primitives
				(gr_poly
					(pts
						(xy 0.8625 0.1275) (xy 0.8625 -0.1275) (xy 1.3725 -0.1275) (xy 1.3725 -0.5325) (xy 0.8625 -0.5325)
						(xy 0.8625 -0.7875) (xy 1.3725 -0.7875) (xy 1.3725 -1.195) (xy 0.6125 -1.195) (xy 0.6125 1.195)
						(xy 1.3725 1.195) (xy 1.3725 0.7875) (xy 0.8625 0.7875) (xy 0.8625 0.5325) (xy 1.3725 0.5325)
						(xy 1.3725 0.1275)
					)
					(width 0)
					(fill yes)
				)
			)
		)
	)
	(footprint "antmicro-footprints:R_0402_1005Metric"
		(layer "F.Cu")
		(at 139.424499 183.279 90)
		(descr "Resistor SMD 0402")
		(tags "resistor SMD 0402")
		(property "Reference" "R66"
			(at -1.046 3.000501 90)
			(layer "F.SilkS")
			(effects
				(font
					(size 0.7 0.7)
					(thickness 0.15)
				)
				(justify left bottom)
			)
		)
		(property "Value" "R_330R_0402"
			(at -1.011843 1.772047 90)
			(layer "F.Fab")
			(effects
				(font
					(size 0.7 0.7)
					(thickness 0.15)
				)
				(justify left bottom)
			)
		)
		(property "Datasheet" "https://www.bourns.com/docs/product-datasheets/cr.pdf"
			(at 0 0 90)
			(layer "F.Fab")
			(hide yes)
			(effects
				(font
					(size 1.27 1.27)
					(thickness 0.15)
				)
			)
		)
		(property "Manufacturer" "Bourns"
			(at 0 0 90)
			(unlocked yes)
			(layer "F.Fab")
			(hide yes)
			(effects
				(font
					(size 1 1)
					(thickness 0.15)
				)
			)
		)
		(property "MPN" "CR0402-FX-3300GLF"
			(at 0 0 90)
			(unlocked yes)
			(layer "F.Fab")
			(hide yes)
			(effects
				(font
					(size 1 1)
					(thickness 0.15)
				)
			)
		)
		(property "Val" "330R"
			(at 0 0 90)
			(unlocked yes)
			(layer "F.Fab")
			(hide yes)
			(effects
				(font
					(size 1 1)
					(thickness 0.15)
				)
			)
		)
		(property "License" "Apache-2.0"
			(at 0 0 90)
			(unlocked yes)
			(layer "F.Fab")
			(hide yes)
			(effects
				(font
					(size 1 1)
					(thickness 0.15)
				)
			)
		)
		(property "Author" "Antmicro"
			(at 0 0 90)
			(unlocked yes)
			(layer "F.Fab")
			(hide yes)
			(effects
				(font
					(size 1 1)
					(thickness 0.15)
				)
			)
		)
		(property "Tolerance" "1%"
			(at 0 0 90)
			(unlocked yes)
			(layer "F.Fab")
			(hide yes)
			(effects
				(font
					(size 1 1)
					(thickness 0.15)
				)
			)
		)
		(sheetname "/Debug FTDI + VNA/")
		(sheetfile "debug-ftdi.kicad_sch")
		(attr smd)
		(fp_rect
			(start -0.925 -0.47)
			(end 0.925 0.47)
			(stroke
				(width 0.05)
				(type default)
			)
			(fill no)
			(layer "F.CrtYd")
		)
		(fp_rect
			(start -0.5 -0.25)
			(end 0.5 0.25)
			(stroke
				(width 0.15)
				(type solid)
			)
			(fill no)
			(layer "F.Fab")
		)
		(fp_text user "License: Apache-2.0"
			(at -0.95 5.169 90)
			(layer "F.Fab")
			(effects
				(font
					(size 0.7 0.7)
					(thickness 0.15)
				)
				(justify left bottom)
			)
		)
		(fp_text user "Author: Antmicro"
			(at -0.95 4.169 90)
			(layer "F.Fab")
			(effects
				(font
					(size 0.7 0.7)
					(thickness 0.15)
				)
				(justify left bottom)
			)
		)
		(fp_text user "${REFERENCE}"
			(at -0.95 3.168 90)
			(layer "F.Fab")
			(effects
				(font
					(size 0.7 0.7)
					(thickness 0.15)
				)
				(justify left bottom)
			)
		)
		(pad "1" smd roundrect
			(at -0.48 0 90)
			(size 0.59 0.64)
			(layers "F.Cu" "F.Mask" "F.Paste")
			(roundrect_rratio 0.25)
			(net 42 "Net-(D12-A)")
			(pintype "passive")
		)
		(pad "2" smd roundrect
			(at 0.48 0 90)
			(size 0.59 0.64)
			(layers "F.Cu" "F.Mask" "F.Paste")
			(roundrect_rratio 0.25)
			(net 445 "/Debug FTDI + VNA/LED_TX1")
			(pintype "passive")
		)
	)
	(footprint "antmicro-footprints:C_0402_1005Metric"
		(layer "F.Cu")
		(at 127.306 176.022 90)
		(descr "Capacitor SMD 0402")
		(tags "capacitor SMD 0402")
		(property "Reference" "C273"
			(at 1.2 0.49 90)
			(layer "F.SilkS")
			(effects
				(font
					(size 0.7 0.7)
					(thickness 0.15)
				)
				(justify left bottom)
			)
		)
		(property "Value" "C_100n_0402"
			(at -1.022927 2.155213 90)
			(layer "F.Fab")
			(effects
				(font
					(size 0.7 0.7)
					(thickness 0.15)
				)
				(justify left bottom)
			)
		)
		(property "Datasheet" "https://www.murata.com/products/productdetail?partno=GRM155R61H104KE14%23"
			(at 0 0 90)
			(layer "F.Fab")
			(hide yes)
			(effects
				(font
					(size 1.27 1.27)
					(thickness 0.15)
				)
			)
		)
		(property "MPN" "GRM155R61H104KE14D"
			(at 0 0 90)
			(unlocked yes)
			(layer "F.Fab")
			(hide yes)
			(effects
				(font
					(size 1 1)
					(thickness 0.15)
				)
			)
		)
		(property "Manufacturer" "Murata"
			(at 0 0 90)
			(unlocked yes)
			(layer "F.Fab")
			(hide yes)
			(effects
				(font
					(size 1 1)
					(thickness 0.15)
				)
			)
		)
		(property "License" "Apache-2.0"
			(at 0 0 90)
			(unlocked yes)
			(layer "F.Fab")
			(hide yes)
			(effects
				(font
					(size 1 1)
					(thickness 0.15)
				)
			)
		)
		(property "Author" "Antmicro"
			(at 0 0 90)
			(unlocked yes)
			(layer "F.Fab")
			(hide yes)
			(effects
				(font
					(size 1 1)
					(thickness 0.15)
				)
			)
		)
		(property "Val" "100n"
			(at 0 0 90)
			(unlocked yes)
			(layer "F.Fab")
			(hide yes)
			(effects
				(font
					(size 1 1)
					(thickness 0.15)
				)
			)
		)
		(property "Voltage" "50V"
			(at 0 0 90)
			(unlocked yes)
			(layer "F.Fab")
			(hide yes)
			(effects
				(font
					(size 1 1)
					(thickness 0.15)
				)
			)
		)
		(property "Dielectric" "X5R"
			(at 0 0 90)
			(unlocked yes)
			(layer "F.Fab")
			(hide yes)
			(effects
				(font
					(size 1 1)
					(thickness 0.15)
				)
			)
		)
		(property "Public" ""
			(at 0 0 90)
			(unlocked yes)
			(layer "F.Fab")
			(hide yes)
			(effects
				(font
					(size 1 1)
					(thickness 0.15)
				)
			)
		)
		(sheetname "/HDMI + SD Card/")
		(sheetfile "hdmi-sd-card.kicad_sch")
		(attr smd)
		(fp_rect
			(start -0.925 -0.47)
			(end 0.925 0.47)
			(stroke
				(width 0.05)
				(type default)
			)
			(fill no)
			(layer "F.CrtYd")
		)
		(fp_line
			(start 0.504 -0.25)
			(end 0.504 0.248)
			(stroke
				(width 0.15)
				(type solid)
			)
			(layer "F.Fab")
		)
		(fp_line
			(start -0.494 -0.25)
			(end 0.504 -0.25)
			(stroke
				(width 0.15)
				(type solid)
			)
			(layer "F.Fab")
		)
		(fp_line
			(start 0.504 0.248)
			(end -0.494 0.248)
			(stroke
				(width 0.15)
				(type solid)
			)
			(layer "F.Fab")
		)
		(fp_line
			(start -0.494 0.248)
			(end -0.494 -0.25)
			(stroke
				(width 0.15)
				(type solid)
			)
			(layer "F.Fab")
		)
		(fp_text user "${REFERENCE}"
			(at -0.939 4.599 90)
			(layer "F.Fab")
			(effects
				(font
					(size 0.7 0.7)
					(thickness 0.15)
				)
				(justify left bottom)
			)
		)
		(fp_text user "Author: Antmicro"
			(at -0.939 3.399 90)
			(layer "F.Fab")
			(effects
				(font
					(size 0.7 0.7)
					(thickness 0.15)
				)
				(justify left bottom)
			)
		)
		(fp_text user "License: Apache-2.0"
			(at -0.939 5.799 90)
			(layer "F.Fab")
			(effects
				(font
					(size 0.7 0.7)
					(thickness 0.15)
				)
				(justify left bottom)
			)
		)
		(pad "1" smd roundrect
			(at -0.48 0 90)
			(size 0.59 0.64)
			(layers "F.Cu" "F.Mask" "F.Paste")
			(roundrect_rratio 0.25)
			(net 151 "+3V3")
			(pintype "passive")
		)
		(pad "2" smd roundrect
			(at 0.48 0 90)
			(size 0.59 0.64)
			(layers "F.Cu" "F.Mask" "F.Paste")
			(roundrect_rratio 0.25)
			(net 1 "GND")
			(pintype "passive")
		)
	)
	(footprint "antmicro-footprints:R_0402_1005Metric"
		(layer "F.Cu")
		(at 252.4 183.549 180)
		(descr "Resistor SMD 0402")
		(tags "resistor SMD 0402")
		(property "Reference" "R222"
			(at 1 -0.375 0)
			(layer "F.SilkS")
			(effects
				(font
					(size 0.7 0.7)
					(thickness 0.15)
				)
				(justify right bottom)
			)
		)
		(property "Value" "R_0R_0402"
			(at -1.011843 1.772047 0)
			(layer "F.Fab")
			(effects
				(font
					(size 0.7 0.7)
					(thickness 0.15)
				)
				(justify right bottom)
			)
		)
		(property "Datasheet" "https://industrial.panasonic.com/cdbs/www-data/pdf/RDA0000/AOA0000C301.pdf"
			(at 0 0 180)
			(layer "F.Fab")
			(hide yes)
			(effects
				(font
					(size 1.27 1.27)
					(thickness 0.15)
				)
			)
		)
		(property "MPN" "ERJ2GE0R00X"
			(at 0 0 180)
			(unlocked yes)
			(layer "F.Fab")
			(hide yes)
			(effects
				(font
					(size 1 1)
					(thickness 0.15)
				)
			)
		)
		(property "Manufacturer" "Panasonic"
			(at 0 0 180)
			(unlocked yes)
			(layer "F.Fab")
			(hide yes)
			(effects
				(font
					(size 1 1)
					(thickness 0.15)
				)
			)
		)
		(property "License" "Apache-2.0"
			(at 0 0 180)
			(unlocked yes)
			(layer "F.Fab")
			(hide yes)
			(effects
				(font
					(size 1 1)
					(thickness 0.15)
				)
			)
		)
		(property "Author" "Antmicro"
			(at 0 0 180)
			(unlocked yes)
			(layer "F.Fab")
			(hide yes)
			(effects
				(font
					(size 1 1)
					(thickness 0.15)
				)
			)
		)
		(property "Val" "0R"
			(at 0 0 180)
			(unlocked yes)
			(layer "F.Fab")
			(hide yes)
			(effects
				(font
					(size 1 1)
					(thickness 0.15)
				)
			)
		)
		(property "Tolerance" "~"
			(at 0 0 180)
			(unlocked yes)
			(layer "F.Fab")
			(hide yes)
			(effects
				(font
					(size 1 1)
					(thickness 0.15)
				)
			)
		)
		(property "Current" "1A"
			(at 0 0 180)
			(unlocked yes)
			(layer "F.Fab")
			(hide yes)
			(effects
				(font
					(size 1 1)
					(thickness 0.15)
				)
			)
		)
		(sheetname "/I^{2}C + I3C/")
		(sheetfile "i2c.kicad_sch")
		(attr smd)
		(fp_rect
			(start -0.925 -0.47)
			(end 0.925 0.47)
			(stroke
				(width 0.05)
				(type default)
			)
			(fill no)
			(layer "F.CrtYd")
		)
		(fp_rect
			(start -0.5 -0.25)
			(end 0.5 0.25)
			(stroke
				(width 0.15)
				(type solid)
			)
			(fill no)
			(layer "F.Fab")
		)
		(fp_text user "${REFERENCE}"
			(at -0.95 3.168 180)
			(layer "F.Fab")
			(effects
				(font
					(size 0.7 0.7)
					(thickness 0.15)
				)
				(justify left bottom)
			)
		)
		(fp_text user "License: Apache-2.0"
			(at -0.95 5.169 180)
			(layer "F.Fab")
			(effects
				(font
					(size 0.7 0.7)
					(thickness 0.15)
				)
				(justify left bottom)
			)
		)
		(fp_text user "Author: Antmicro"
			(at -0.95 4.169 180)
			(layer "F.Fab")
			(effects
				(font
					(size 0.7 0.7)
					(thickness 0.15)
				)
				(justify left bottom)
			)
		)
		(pad "1" smd roundrect
			(at -0.48 0 180)
			(size 0.59 0.64)
			(layers "F.Cu" "F.Mask" "F.Paste")
			(roundrect_rratio 0.25)
			(net 664 "Net-(C325-Pad2)")
			(pintype "passive")
		)
		(pad "2" smd roundrect
			(at 0.48 0 180)
			(size 0.59 0.64)
			(layers "F.Cu" "F.Mask" "F.Paste")
			(roundrect_rratio 0.25)
			(net 151 "+3V3")
			(pintype "passive")
		)
	)
	(footprint "antmicro-footprints:SC70-3"
		(layer "F.Cu")
		(at 250.269499 132.394)
		(property "Reference" "Q14"
			(at 0.490501 1.096 90)
			(layer "F.SilkS")
			(effects
				(font
					(size 0.7 0.7)
					(thickness 0.15)
				)
				(justify left bottom)
			)
		)
		(property "Value" "BSS138PW"
			(at 0 2.3 0)
			(layer "F.Fab")
			(effects
				(font
					(size 0.7 0.7)
					(thickness 0.15)
				)
				(justify left bottom)
			)
		)
		(property "Datasheet" "https://assets.nexperia.com/documents/data-sheet/BSS138PW.pdf"
			(at 0 0 0)
			(layer "F.Fab")
			(hide yes)
			(effects
				(font
					(size 1.27 1.27)
					(thickness 0.15)
				)
			)
		)
		(property "MPN" "BSS138PW"
			(at 0 0 0)
			(unlocked yes)
			(layer "F.Fab")
			(hide yes)
			(effects
				(font
					(size 1 1)
					(thickness 0.15)
				)
			)
		)
		(property "Manufacturer" "Nexperia"
			(at 0 0 0)
			(unlocked yes)
			(layer "F.Fab")
			(hide yes)
			(effects
				(font
					(size 1 1)
					(thickness 0.15)
				)
			)
		)
		(property "Author" "Antmicro"
			(at 0 0 0)
			(unlocked yes)
			(layer "F.Fab")
			(hide yes)
			(effects
				(font
					(size 1 1)
					(thickness 0.15)
				)
			)
		)
		(property "License" "Apache-2.0"
			(at 0 0 0)
			(unlocked yes)
			(layer "F.Fab")
			(hide yes)
			(effects
				(font
					(size 1 1)
					(thickness 0.15)
				)
			)
		)
		(sheetname "/Supply/")
		(sheetfile "supply.kicad_sch")
		(attr smd)
		(fp_line
			(start -0.3 -1)
			(end 0.627 -0.999)
			(stroke
				(width 0.15)
				(type solid)
			)
			(layer "F.SilkS")
		)
		(fp_line
			(start -0.3 1)
			(end 0.627 1.001)
			(stroke
				(width 0.15)
				(type solid)
			)
			(layer "F.SilkS")
		)
		(fp_line
			(start 0.627 -0.6)
			(end 0.627 -0.999)
			(stroke
				(width 0.15)
				(type solid)
			)
			(layer "F.SilkS")
		)
		(fp_line
			(start 0.627 0.6)
			(end 0.627 1.001)
			(stroke
				(width 0.15)
				(type solid)
			)
			(layer "F.SilkS")
		)
		(fp_line
			(start -1.4 1)
			(end -1.4 -1)
			(stroke
				(width 0.05)
				(type solid)
			)
			(layer "F.CrtYd")
		)
		(fp_line
			(start -0.9 -1.3)
			(end -0.9 -1)
			(stroke
				(width 0.05)
				(type solid)
			)
			(layer "F.CrtYd")
		)
		(fp_line
			(start -0.9 -1.3)
			(end 0.9 -1.3)
			(stroke
				(width 0.05)
				(type solid)
			)
			(layer "F.CrtYd")
		)
		(fp_line
			(start -0.9 -1)
			(end -1.4 -1)
			(stroke
				(width 0.05)
				(type solid)
			)
			(layer "F.CrtYd")
		)
		(fp_line
			(start -0.9 1)
			(end -1.4 1)
			(stroke
				(width 0.05)
				(type solid)
			)
			(layer "F.CrtYd")
		)
		(fp_line
			(start -0.9 1.3)
			(end -0.9 1)
			(stroke
				(width 0.05)
				(type solid)
			)
			(layer "F.CrtYd")
		)
		(fp_line
			(start 0.9 -1.3)
			(end 0.9 -0.4)
			(stroke
				(width 0.05)
				(type solid)
			)
			(layer "F.CrtYd")
		)
		(fp_line
			(start 0.9 -0.4)
			(end 1.4 -0.4)
			(stroke
				(width 0.05)
				(type solid)
			)
			(layer "F.CrtYd")
		)
		(fp_line
			(start 0.9 0.4)
			(end 0.9 1.3)
			(stroke
				(width 0.05)
				(type solid)
			)
			(layer "F.CrtYd")
		)
		(fp_line
			(start 0.9 1.3)
			(end -0.9 1.3)
			(stroke
				(width 0.05)
				(type solid)
			)
			(layer "F.CrtYd")
		)
		(fp_line
			(start 1.4 -0.4)
			(end 1.4 0.4)
			(stroke
				(width 0.05)
				(type solid)
			)
			(layer "F.CrtYd")
		)
		(fp_line
			(start 1.4 0.4)
			(end 0.9 0.4)
			(stroke
				(width 0.05)
				(type solid)
			)
			(layer "F.CrtYd")
		)
		(fp_rect
			(start -0.623 -0.999)
			(end 0.627 1.001)
			(stroke
				(width 0.15)
				(type solid)
			)
			(fill no)
			(layer "F.Fab")
		)
		(fp_text user "License: Apache-2.0"
			(at -1.45 6.782 0)
			(layer "F.Fab")
			(effects
				(font
					(size 0.7 0.7)
					(thickness 0.15)
				)
				(justify left bottom)
			)
		)
		(fp_text user "${REFERENCE}"
			(at -1.45 4.783 0)
			(layer "F.Fab")
			(effects
				(font
					(size 0.7 0.7)
					(thickness 0.15)
				)
				(justify left bottom)
			)
		)
		(fp_text user "Author: Antmicro"
			(at -1.45 5.782 0)
			(layer "F.Fab")
			(effects
				(font
					(size 0.7 0.7)
					(thickness 0.15)
				)
				(justify left bottom)
			)
		)
		(pad "1" smd rect
			(at -1.051 -0.65 90)
			(size 0.6 0.6)
			(layers "F.Cu" "F.Mask" "F.Paste")
			(net 185 "FPGA_POWER_OFF")
			(pinfunction "G")
			(pintype "passive")
		)
		(pad "2" smd rect
			(at -1.051 0.65 90)
			(size 0.6 0.6)
			(layers "F.Cu" "F.Mask" "F.Paste")
			(net 1 "GND")
			(pinfunction "S")
			(pintype "passive")
		)
		(pad "3" smd rect
			(at 1.05 0 90)
			(size 0.6 0.6)
			(layers "F.Cu" "F.Mask" "F.Paste")
			(net 137 "/Supply/~{PB_CTRL_CLR}")
			(pinfunction "D")
			(pintype "passive")
		)
	)
	(footprint "antmicro-footprints:LED_0603_1608Metric_G"
		(layer "F.Cu")
		(at 105.305 102.225 90)
		(descr "LED SMD 0603 Green")
		(tags "LED SMD 0603 Green")
		(property "Reference" "D7"
			(at -2.575 -0.305 90)
			(layer "F.SilkS")
			(hide yes)
			(effects
				(font
					(size 0.7 0.7)
					(thickness 0.15)
				)
				(justify left bottom)
			)
		)
		(property "Value" "LED_G_0603_KP-1608CGCK"
			(at -0.001 1.599 90)
			(layer "F.Fab")
			(effects
				(font
					(size 0.7 0.7)
					(thickness 0.15)
				)
				(justify left bottom)
			)
		)
		(property "Datasheet" "http://www.kingbright.com/attachments/file/psearch//000/00/00/KP-1608CGCK(Ver.23B).pdf"
			(at 0 0 90)
			(layer "F.Fab")
			(hide yes)
			(effects
				(font
					(size 1.27 1.27)
					(thickness 0.15)
				)
			)
		)
		(property "MPN" "KP-1608CGCK"
			(at 0 0 90)
			(unlocked yes)
			(layer "F.Fab")
			(hide yes)
			(effects
				(font
					(size 1 1)
					(thickness 0.15)
				)
			)
		)
		(property "Manufacturer" "Kingbright"
			(at 0 0 90)
			(unlocked yes)
			(layer "F.Fab")
			(hide yes)
			(effects
				(font
					(size 1 1)
					(thickness 0.15)
				)
			)
		)
		(property "Author" "Antmicro"
			(at 0 0 90)
			(unlocked yes)
			(layer "F.Fab")
			(hide yes)
			(effects
				(font
					(size 1 1)
					(thickness 0.15)
				)
			)
		)
		(property "License" "Apache-2.0"
			(at 0 0 90)
			(unlocked yes)
			(layer "F.Fab")
			(hide yes)
			(effects
				(font
					(size 1 1)
					(thickness 0.15)
				)
			)
		)
		(property "Color" "Green"
			(at 0 0 90)
			(unlocked yes)
			(layer "F.Fab")
			(hide yes)
			(effects
				(font
					(size 1 1)
					(thickness 0.15)
				)
			)
		)
		(sheetname "/FPGA banks HD/")
		(sheetfile "fpga-hd-banks.kicad_sch")
		(attr smd)
		(fp_line
			(start 0.22 -0.35)
			(end -0.22 -0.35)
			(stroke
				(width 0.15)
				(type solid)
			)
			(layer "F.SilkS")
		)
		(fp_line
			(start -1.18 -0.319)
			(end -1.18 0.321)
			(stroke
				(width 0.15)
				(type solid)
			)
			(layer "F.SilkS")
		)
		(fp_line
			(start 0.105328 0.001008)
			(end 0.24 0.001)
			(stroke
				(width 0.1)
				(type solid)
			)
			(layer "F.SilkS")
		)
		(fp_line
			(start -0.094672 0.001008)
			(end 0.105328 -0.198992)
			(stroke
				(width 0.1)
				(type solid)
			)
			(layer "F.SilkS")
		)
		(fp_line
			(start -0.094672 0.001008)
			(end -0.24 0.001008)
			(stroke
				(width 0.1)
				(type solid)
			)
			(layer "F.SilkS")
		)
		(fp_line
			(start 0.105328 0.201008)
			(end 0.105328 -0.198992)
			(stroke
				(width 0.1)
				(type solid)
			)
			(layer "F.SilkS")
		)
		(fp_line
			(start 0.105328 0.201008)
			(end -0.094672 0.001008)
			(stroke
				(width 0.1)
				(type solid)
			)
			(layer "F.SilkS")
		)
		(fp_line
			(start -0.094672 0.201008)
			(end -0.094672 -0.198992)
			(stroke
				(width 0.1)
				(type solid)
			)
			(layer "F.SilkS")
		)
		(fp_line
			(start 0.22 0.35)
			(end -0.22 0.35)
			(stroke
				(width 0.15)
				(type solid)
			)
			(layer "F.SilkS")
		)
		(fp_rect
			(start 1.25 0.65)
			(end -1.25 -0.65)
			(stroke
				(width 0.05)
				(type solid)
			)
			(fill no)
			(layer "F.CrtYd")
		)
		(fp_line
			(start 0.201 -0.202)
			(end -0.101 0)
			(stroke
				(width 0.15)
				(type solid)
			)
			(layer "F.Fab")
		)
		(fp_line
			(start -0.199 -0.202)
			(end -0.199 0.1)
			(stroke
				(width 0.15)
				(type solid)
			)
			(layer "F.Fab")
		)
		(fp_line
			(start 0.599 0)
			(end 0.201 0)
			(stroke
				(width 0.15)
				(type solid)
			)
			(layer "F.Fab")
		)
		(fp_line
			(start 0.201 0)
			(end 0.201 -0.202)
			(stroke
				(width 0.15)
				(type solid)
			)
			(layer "F.Fab")
		)
		(fp_line
			(start -0.101 0)
			(end 0.201 0.2)
			(stroke
				(width 0.15)
				(type solid)
			)
			(layer "F.Fab")
		)
		(fp_line
			(start -0.199 0)
			(end -0.597 0)
			(stroke
				(width 0.15)
				(type solid)
			)
			(layer "F.Fab")
		)
		(fp_line
			(start 0.201 0.2)
			(end 0.201 0)
			(stroke
				(width 0.15)
				(type solid)
			)
			(layer "F.Fab")
		)
		(fp_line
			(start -0.199 0.2)
			(end -0.199 0.1)
			(stroke
				(width 0.15)
				(type solid)
			)
			(layer "F.Fab")
		)
		(fp_rect
			(start 0.848 0.4)
			(end -0.85 -0.402)
			(stroke
				(width 0.15)
				(type solid)
			)
			(fill no)
			(layer "F.Fab")
		)
		(fp_text user "${REFERENCE}"
			(at -1.4224 5.999 90)
			(layer "F.Fab")
			(effects
				(font
					(size 0.7 0.7)
					(thickness 0.15)
				)
				(justify left bottom)
			)
		)
		(fp_text user "License: Apache-2.0"
			(at -1.4224 3.599 90)
			(layer "F.Fab")
			(effects
				(font
					(size 0.7 0.7)
					(thickness 0.15)
				)
				(justify left bottom)
			)
		)
		(fp_text user "Author: Antmicro"
			(at -1.4224 4.799 90)
			(layer "F.Fab")
			(effects
				(font
					(size 0.7 0.7)
					(thickness 0.15)
				)
				(justify left bottom)
			)
		)
		(pad "1" smd roundrect
			(at -0.7 0 270)
			(size 0.8 1)
			(layers "F.Cu" "F.Mask" "F.Paste")
			(roundrect_rratio 0.2)
			(net 151 "+3V3")
			(pinfunction "C")
			(pintype "passive")
		)
		(pad "2" smd roundrect
			(at 0.7 0 270)
			(size 0.8 1)
			(layers "F.Cu" "F.Mask" "F.Paste")
			(roundrect_rratio 0.2)
			(net 232 "Net-(D7-A)")
			(pinfunction "A")
			(pintype "passive")
		)
	)
	(footprint "antmicro-footprints:R_0402_1005Metric"
		(layer "F.Cu")
		(at 251.95 182.078 -90)
		(descr "Resistor SMD 0402")
		(tags "resistor SMD 0402")
		(property "Reference" "R96"
			(at -1.278 2.55 90)
			(layer "F.SilkS")
			(effects
				(font
					(size 0.7 0.7)
					(thickness 0.15)
				)
				(justify right bottom)
			)
		)
		(property "Value" "R_0R_0402"
			(at -1.011843 1.772047 90)
			(layer "F.Fab")
			(effects
				(font
					(size 0.7 0.7)
					(thickness 0.15)
				)
				(justify right bottom)
			)
		)
		(property "Datasheet" "https://industrial.panasonic.com/cdbs/www-data/pdf/RDA0000/AOA0000C301.pdf"
			(at 0 0 270)
			(layer "F.Fab")
			(hide yes)
			(effects
				(font
					(size 1.27 1.27)
					(thickness 0.15)
				)
			)
		)
		(property "MPN" "ERJ2GE0R00X"
			(at 0 0 270)
			(unlocked yes)
			(layer "F.Fab")
			(hide yes)
			(effects
				(font
					(size 1 1)
					(thickness 0.15)
				)
			)
		)
		(property "Manufacturer" "Panasonic"
			(at 0 0 270)
			(unlocked yes)
			(layer "F.Fab")
			(hide yes)
			(effects
				(font
					(size 1 1)
					(thickness 0.15)
				)
			)
		)
		(property "License" "Apache-2.0"
			(at 0 0 270)
			(unlocked yes)
			(layer "F.Fab")
			(hide yes)
			(effects
				(font
					(size 1 1)
					(thickness 0.15)
				)
			)
		)
		(property "Author" "Antmicro"
			(at 0 0 270)
			(unlocked yes)
			(layer "F.Fab")
			(hide yes)
			(effects
				(font
					(size 1 1)
					(thickness 0.15)
				)
			)
		)
		(property "Val" "0R"
			(at 0 0 270)
			(unlocked yes)
			(layer "F.Fab")
			(hide yes)
			(effects
				(font
					(size 1 1)
					(thickness 0.15)
				)
			)
		)
		(property "Tolerance" "~"
			(at 0 0 270)
			(unlocked yes)
			(layer "F.Fab")
			(hide yes)
			(effects
				(font
					(size 1 1)
					(thickness 0.15)
				)
			)
		)
		(property "Current" "1A"
			(at 0 0 270)
			(unlocked yes)
			(layer "F.Fab")
			(hide yes)
			(effects
				(font
					(size 1 1)
					(thickness 0.15)
				)
			)
		)
		(sheetname "/I^{2}C + I3C/")
		(sheetfile "i2c.kicad_sch")
		(attr smd exclude_from_bom dnp)
		(fp_rect
			(start -0.925 -0.47)
			(end 0.925 0.47)
			(stroke
				(width 0.05)
				(type default)
			)
			(fill no)
			(layer "F.CrtYd")
		)
		(fp_rect
			(start -0.5 -0.25)
			(end 0.5 0.25)
			(stroke
				(width 0.15)
				(type solid)
			)
			(fill no)
			(layer "F.Fab")
		)
		(fp_text user "Author: Antmicro"
			(at -0.95 4.169 270)
			(layer "F.Fab")
			(effects
				(font
					(size 0.7 0.7)
					(thickness 0.15)
				)
				(justify left bottom)
			)
		)
		(fp_text user "${REFERENCE}"
			(at -0.95 3.168 270)
			(layer "F.Fab")
			(effects
				(font
					(size 0.7 0.7)
					(thickness 0.15)
				)
				(justify left bottom)
			)
		)
		(fp_text user "License: Apache-2.0"
			(at -0.95 5.169 270)
			(layer "F.Fab")
			(effects
				(font
					(size 0.7 0.7)
					(thickness 0.15)
				)
				(justify left bottom)
			)
		)
		(pad "1" smd roundrect
			(at -0.48 0 270)
			(size 0.59 0.64)
			(layers "F.Cu" "F.Mask" "F.Paste")
			(roundrect_rratio 0.25)
			(net 775 "Net-(Q24-S)")
			(pintype "passive")
		)
		(pad "2" smd roundrect
			(at 0.48 0 270)
			(size 0.59 0.64)
			(layers "F.Cu" "F.Mask" "F.Paste")
			(roundrect_rratio 0.25)
			(net 151 "+3V3")
			(pintype "passive")
		)
	)
	(footprint "antmicro-footprints:R_0402_1005Metric"
		(layer "F.Cu")
		(at 248.169499 135.194 90)
		(descr "Resistor SMD 0402")
		(tags "resistor SMD 0402")
		(property "Reference" "R171"
			(at -1.356 -0.772697 90)
			(layer "F.SilkS")
			(effects
				(font
					(size 0.7 0.7)
					(thickness 0.15)
				)
				(justify left bottom)
			)
		)
		(property "Value" "R_47k_0402"
			(at -1.011843 1.772047 90)
			(layer "F.Fab")
			(effects
				(font
					(size 0.7 0.7)
					(thickness 0.15)
				)
				(justify left bottom)
			)
		)
		(property "Datasheet" "https://www.bourns.com/docs/product-datasheets/cr.pdf"
			(at 0 0 90)
			(layer "F.Fab")
			(hide yes)
			(effects
				(font
					(size 1.27 1.27)
					(thickness 0.15)
				)
			)
		)
		(property "Manufacturer" "Bourns"
			(at 0 0 90)
			(unlocked yes)
			(layer "F.Fab")
			(hide yes)
			(effects
				(font
					(size 1 1)
					(thickness 0.15)
				)
			)
		)
		(property "MPN" "CR0402-FX-4702GLF"
			(at 0 0 90)
			(unlocked yes)
			(layer "F.Fab")
			(hide yes)
			(effects
				(font
					(size 1 1)
					(thickness 0.15)
				)
			)
		)
		(property "Val" "47k"
			(at 0 0 90)
			(unlocked yes)
			(layer "F.Fab")
			(hide yes)
			(effects
				(font
					(size 1 1)
					(thickness 0.15)
				)
			)
		)
		(property "License" "Apache-2.0"
			(at 0 0 90)
			(unlocked yes)
			(layer "F.Fab")
			(hide yes)
			(effects
				(font
					(size 1 1)
					(thickness 0.15)
				)
			)
		)
		(property "Author" "Antmicro"
			(at 0 0 90)
			(unlocked yes)
			(layer "F.Fab")
			(hide yes)
			(effects
				(font
					(size 1 1)
					(thickness 0.15)
				)
			)
		)
		(property "Tolerance" "1%"
			(at 0 0 90)
			(unlocked yes)
			(layer "F.Fab")
			(hide yes)
			(effects
				(font
					(size 1 1)
					(thickness 0.15)
				)
			)
		)
		(sheetname "/Supply/")
		(sheetfile "supply.kicad_sch")
		(attr smd)
		(fp_rect
			(start -0.925 -0.47)
			(end 0.925 0.47)
			(stroke
				(width 0.05)
				(type default)
			)
			(fill no)
			(layer "F.CrtYd")
		)
		(fp_rect
			(start -0.5 -0.25)
			(end 0.5 0.25)
			(stroke
				(width 0.15)
				(type solid)
			)
			(fill no)
			(layer "F.Fab")
		)
		(fp_text user "Author: Antmicro"
			(at -0.95 4.169 90)
			(layer "F.Fab")
			(effects
				(font
					(size 0.7 0.7)
					(thickness 0.15)
				)
				(justify left bottom)
			)
		)
		(fp_text user "${REFERENCE}"
			(at -0.95 3.168 90)
			(layer "F.Fab")
			(effects
				(font
					(size 0.7 0.7)
					(thickness 0.15)
				)
				(justify left bottom)
			)
		)
		(fp_text user "License: Apache-2.0"
			(at -0.95 5.169 90)
			(layer "F.Fab")
			(effects
				(font
					(size 0.7 0.7)
					(thickness 0.15)
				)
				(justify left bottom)
			)
		)
		(pad "1" smd roundrect
			(at -0.48 0 90)
			(size 0.59 0.64)
			(layers "F.Cu" "F.Mask" "F.Paste")
			(roundrect_rratio 0.25)
			(net 1 "GND")
			(pintype "passive")
		)
		(pad "2" smd roundrect
			(at 0.48 0 90)
			(size 0.59 0.64)
			(layers "F.Cu" "F.Mask" "F.Paste")
			(roundrect_rratio 0.25)
			(net 184 "FPGA_POWER_CYCLE")
			(pintype "passive")
		)
	)
	(footprint "antmicro-footprints:R_0402_1005Metric"
		(layer "F.Cu")
		(at 253.42 167.8595 180)
		(descr "Resistor SMD 0402")
		(tags "resistor SMD 0402")
		(property "Reference" "R154"
			(at -1.28 0.4595 0)
			(layer "F.SilkS")
			(effects
				(font
					(size 0.7 0.7)
					(thickness 0.15)
				)
				(justify right bottom)
			)
		)
		(property "Value" "R_0R_0402"
			(at -1.011843 1.772047 0)
			(layer "F.Fab")
			(effects
				(font
					(size 0.7 0.7)
					(thickness 0.15)
				)
				(justify right bottom)
			)
		)
		(property "Datasheet" "https://industrial.panasonic.com/cdbs/www-data/pdf/RDA0000/AOA0000C301.pdf"
			(at 0 0 180)
			(layer "F.Fab")
			(hide yes)
			(effects
				(font
					(size 1.27 1.27)
					(thickness 0.15)
				)
			)
		)
		(property "Manufacturer" "Panasonic"
			(at 0 0 180)
			(unlocked yes)
			(layer "F.Fab")
			(hide yes)
			(effects
				(font
					(size 1 1)
					(thickness 0.15)
				)
			)
		)
		(property "MPN" "ERJ2GE0R00X"
			(at 0 0 180)
			(unlocked yes)
			(layer "F.Fab")
			(hide yes)
			(effects
				(font
					(size 1 1)
					(thickness 0.15)
				)
			)
		)
		(property "Val" "0R"
			(at 0 0 180)
			(unlocked yes)
			(layer "F.Fab")
			(hide yes)
			(effects
				(font
					(size 1 1)
					(thickness 0.15)
				)
			)
		)
		(property "License" "Apache-2.0"
			(at 0 0 180)
			(unlocked yes)
			(layer "F.Fab")
			(hide yes)
			(effects
				(font
					(size 1 1)
					(thickness 0.15)
				)
			)
		)
		(property "Author" "Antmicro"
			(at 0 0 180)
			(unlocked yes)
			(layer "F.Fab")
			(hide yes)
			(effects
				(font
					(size 1 1)
					(thickness 0.15)
				)
			)
		)
		(property "Tolerance" "~"
			(at 0 0 180)
			(unlocked yes)
			(layer "F.Fab")
			(hide yes)
			(effects
				(font
					(size 1 1)
					(thickness 0.15)
				)
			)
		)
		(property "Current" "1A"
			(at 0 0 180)
			(unlocked yes)
			(layer "F.Fab")
			(hide yes)
			(effects
				(font
					(size 1 1)
					(thickness 0.15)
				)
			)
		)
		(sheetname "/Supply/DC-DC AUX, MGT/")
		(sheetfile "dc-dc-aux-mgt.kicad_sch")
		(attr smd)
		(fp_rect
			(start -0.925 -0.47)
			(end 0.925 0.47)
			(stroke
				(width 0.05)
				(type default)
			)
			(fill no)
			(layer "F.CrtYd")
		)
		(fp_rect
			(start -0.5 -0.25)
			(end 0.5 0.25)
			(stroke
				(width 0.15)
				(type solid)
			)
			(fill no)
			(layer "F.Fab")
		)
		(fp_text user "${REFERENCE}"
			(at -0.95 3.168 180)
			(layer "F.Fab")
			(effects
				(font
					(size 0.7 0.7)
					(thickness 0.15)
				)
				(justify left bottom)
			)
		)
		(fp_text user "Author: Antmicro"
			(at -0.95 4.169 180)
			(layer "F.Fab")
			(effects
				(font
					(size 0.7 0.7)
					(thickness 0.15)
				)
				(justify left bottom)
			)
		)
		(fp_text user "License: Apache-2.0"
			(at -0.95 5.169 180)
			(layer "F.Fab")
			(effects
				(font
					(size 0.7 0.7)
					(thickness 0.15)
				)
				(justify left bottom)
			)
		)
		(pad "1" smd roundrect
			(at -0.48 0 180)
			(size 0.59 0.64)
			(layers "F.Cu" "F.Mask" "F.Paste")
			(roundrect_rratio 0.25)
			(net 713 "/Supply/DC-DC AUX, MGT/FB2")
			(pintype "passive")
		)
		(pad "2" smd roundrect
			(at 0.48 0 180)
			(size 0.59 0.64)
			(layers "F.Cu" "F.Mask" "F.Paste")
			(roundrect_rratio 0.25)
			(net 48 "/Supply/DC-DC AUX, MGT/MGTAVTT_local")
			(pintype "passive")
		)
	)
	(footprint "antmicro-footprints:QFN-2L_1.6x1x0.55mm"
		(layer "F.Cu")
		(at 243.449499 122.3 90)
		(property "Reference" "D16"
			(at -1.391 -0.779499 90)
			(layer "F.SilkS")
			(effects
				(font
					(size 0.7 0.7)
					(thickness 0.15)
				)
				(justify left bottom)
			)
		)
		(property "Value" "ESDA25P35-1U1M"
			(at 0 1.7 90)
			(layer "F.Fab")
			(effects
				(font
					(size 0.7 0.7)
					(thickness 0.15)
				)
				(justify left bottom)
			)
		)
		(property "Datasheet" "https://www.st.com/resource/en/datasheet/esda25p35-1u1m.pdf"
			(at 0 0 90)
			(layer "F.Fab")
			(hide yes)
			(effects
				(font
					(size 1.27 1.27)
					(thickness 0.15)
				)
			)
		)
		(property "MPN" "ESDA25P35-1U1M"
			(at 0 0 90)
			(unlocked yes)
			(layer "F.Fab")
			(hide yes)
			(effects
				(font
					(size 1 1)
					(thickness 0.15)
				)
			)
		)
		(property "Manufacturer" "STMicroelectronics"
			(at 0 0 90)
			(unlocked yes)
			(layer "F.Fab")
			(hide yes)
			(effects
				(font
					(size 1 1)
					(thickness 0.15)
				)
			)
		)
		(property "Author" "Antmicro"
			(at 0 0 90)
			(unlocked yes)
			(layer "F.Fab")
			(hide yes)
			(effects
				(font
					(size 1 1)
					(thickness 0.15)
				)
			)
		)
		(property "License" "Apache-2.0"
			(at 0 0 90)
			(unlocked yes)
			(layer "F.Fab")
			(hide yes)
			(effects
				(font
					(size 1 1)
					(thickness 0.15)
				)
			)
		)
		(sheetname "/Supply/")
		(sheetfile "supply.kicad_sch")
		(attr smd)
		(fp_line
			(start 0.23 -0.45)
			(end -0.23 -0.45)
			(stroke
				(width 0.15)
				(type solid)
			)
			(layer "F.SilkS")
		)
		(fp_line
			(start -1.2 -0.4)
			(end -1.2 0.4)
			(stroke
				(width 0.15)
				(type solid)
			)
			(layer "F.SilkS")
		)
		(fp_line
			(start 0.23 0.45)
			(end -0.23 0.45)
			(stroke
				(width 0.15)
				(type solid)
			)
			(layer "F.SilkS")
		)
		(fp_rect
			(start 1.25 0.65)
			(end -1.25 -0.65)
			(stroke
				(width 0.05)
				(type solid)
			)
			(fill no)
			(layer "F.CrtYd")
		)
		(fp_line
			(start 0.201 -0.202)
			(end -0.101 0)
			(stroke
				(width 0.15)
				(type solid)
			)
			(layer "F.Fab")
		)
		(fp_line
			(start -0.199 -0.202)
			(end -0.199 0.1)
			(stroke
				(width 0.15)
				(type solid)
			)
			(layer "F.Fab")
		)
		(fp_line
			(start 0.599 0)
			(end 0.201 0)
			(stroke
				(width 0.15)
				(type solid)
			)
			(layer "F.Fab")
		)
		(fp_line
			(start 0.201 0)
			(end 0.201 -0.202)
			(stroke
				(width 0.15)
				(type solid)
			)
			(layer "F.Fab")
		)
		(fp_line
			(start -0.101 0)
			(end 0.201 0.2)
			(stroke
				(width 0.15)
				(type solid)
			)
			(layer "F.Fab")
		)
		(fp_line
			(start -0.199 0)
			(end -0.597 0)
			(stroke
				(width 0.15)
				(type solid)
			)
			(layer "F.Fab")
		)
		(fp_line
			(start 0.201 0.2)
			(end 0.201 0)
			(stroke
				(width 0.15)
				(type solid)
			)
			(layer "F.Fab")
		)
		(fp_line
			(start -0.199 0.2)
			(end -0.199 0.1)
			(stroke
				(width 0.15)
				(type solid)
			)
			(layer "F.Fab")
		)
		(fp_rect
			(start 0.848 0.4)
			(end -0.85 -0.402)
			(stroke
				(width 0.15)
				(type solid)
			)
			(fill no)
			(layer "F.Fab")
		)
		(fp_text user "License: Apache-2.0"
			(at -1.31 5.769 90)
			(layer "F.Fab")
			(effects
				(font
					(size 0.7 0.7)
					(thickness 0.15)
				)
				(justify left bottom)
			)
		)
		(fp_text user "Author: Antmicro"
			(at -1.31 4.769 90)
			(layer "F.Fab")
			(effects
				(font
					(size 0.7 0.7)
					(thickness 0.15)
				)
				(justify left bottom)
			)
		)
		(fp_text user "${REFERENCE}"
			(at -1.31 3.769 90)
			(layer "F.Fab")
			(effects
				(font
					(size 0.7 0.7)
					(thickness 0.15)
				)
				(justify left bottom)
			)
		)
		(pad "1" smd roundrect
			(at -0.7 0 270)
			(size 0.8 1)
			(layers "F.Cu" "F.Mask" "F.Paste")
			(roundrect_rratio 0.2)
			(net 323 "/Supply/12V_aux_fused")
			(pinfunction "C")
			(pintype "passive")
		)
		(pad "2" smd roundrect
			(at 0.7 0 270)
			(size 0.8 1)
			(layers "F.Cu" "F.Mask" "F.Paste")
			(roundrect_rratio 0.2)
			(net 1 "GND")
			(pinfunction "A")
			(pintype "passive")
		)
	)
	(footprint "antmicro-footprints:R_0402_1005Metric"
		(layer "F.Cu")
		(at 112.037258 171.5335 -90)
		(descr "Resistor SMD 0402")
		(tags "resistor SMD 0402")
		(property "Reference" "R89"
			(at 0.9165 -0.362742 90)
			(layer "F.SilkS")
			(effects
				(font
					(size 0.7 0.7)
					(thickness 0.15)
				)
				(justify right bottom)
			)
		)
		(property "Value" "R_330R_0402"
			(at -1.011843 1.772047 90)
			(layer "F.Fab")
			(effects
				(font
					(size 0.7 0.7)
					(thickness 0.15)
				)
				(justify right bottom)
			)
		)
		(property "Datasheet" "https://www.bourns.com/docs/product-datasheets/cr.pdf"
			(at 0 0 270)
			(layer "F.Fab")
			(hide yes)
			(effects
				(font
					(size 1.27 1.27)
					(thickness 0.15)
				)
			)
		)
		(property "Manufacturer" "Bourns"
			(at 0 0 270)
			(unlocked yes)
			(layer "F.Fab")
			(hide yes)
			(effects
				(font
					(size 1 1)
					(thickness 0.15)
				)
			)
		)
		(property "MPN" "CR0402-FX-3300GLF"
			(at 0 0 270)
			(unlocked yes)
			(layer "F.Fab")
			(hide yes)
			(effects
				(font
					(size 1 1)
					(thickness 0.15)
				)
			)
		)
		(property "Val" "330R"
			(at 0 0 270)
			(unlocked yes)
			(layer "F.Fab")
			(hide yes)
			(effects
				(font
					(size 1 1)
					(thickness 0.15)
				)
			)
		)
		(property "License" "Apache-2.0"
			(at 0 0 270)
			(unlocked yes)
			(layer "F.Fab")
			(hide yes)
			(effects
				(font
					(size 1 1)
					(thickness 0.15)
				)
			)
		)
		(property "Author" "Antmicro"
			(at 0 0 270)
			(unlocked yes)
			(layer "F.Fab")
			(hide yes)
			(effects
				(font
					(size 1 1)
					(thickness 0.15)
				)
			)
		)
		(property "Tolerance" "1%"
			(at 0 0 270)
			(unlocked yes)
			(layer "F.Fab")
			(hide yes)
			(effects
				(font
					(size 1 1)
					(thickness 0.15)
				)
			)
		)
		(sheetname "/HDMI + SD Card/")
		(sheetfile "hdmi-sd-card.kicad_sch")
		(attr smd)
		(fp_rect
			(start -0.925 -0.47)
			(end 0.925 0.47)
			(stroke
				(width 0.05)
				(type default)
			)
			(fill no)
			(layer "F.CrtYd")
		)
		(fp_rect
			(start -0.5 -0.25)
			(end 0.5 0.25)
			(stroke
				(width 0.15)
				(type solid)
			)
			(fill no)
			(layer "F.Fab")
		)
		(fp_text user "Author: Antmicro"
			(at -0.95 4.169 270)
			(layer "F.Fab")
			(effects
				(font
					(size 0.7 0.7)
					(thickness 0.15)
				)
				(justify left bottom)
			)
		)
		(fp_text user "License: Apache-2.0"
			(at -0.95 5.169 270)
			(layer "F.Fab")
			(effects
				(font
					(size 0.7 0.7)
					(thickness 0.15)
				)
				(justify left bottom)
			)
		)
		(fp_text user "${REFERENCE}"
			(at -0.95 3.168 270)
			(layer "F.Fab")
			(effects
				(font
					(size 0.7 0.7)
					(thickness 0.15)
				)
				(justify left bottom)
			)
		)
		(pad "1" smd roundrect
			(at -0.48 0 270)
			(size 0.59 0.64)
			(layers "F.Cu" "F.Mask" "F.Paste")
			(roundrect_rratio 0.25)
			(net 1 "GND")
			(pintype "passive")
		)
		(pad "2" smd roundrect
			(at 0.48 0 270)
			(size 0.59 0.64)
			(layers "F.Cu" "F.Mask" "F.Paste")
			(roundrect_rratio 0.25)
			(net 188 "Net-(C132-Pad1)")
			(pintype "passive")
		)
	)
	(footprint "antmicro-footprints:SOD-523"
		(layer "F.Cu")
		(at 115.75 152.5 180)
		(property "Reference" "D19"
			(at -1 1.725 0)
			(layer "F.SilkS")
			(effects
				(font
					(size 0.7 0.7)
					(thickness 0.15)
				)
				(justify right bottom)
			)
		)
		(property "Value" "PESD5V0X1UB"
			(at 0 1.499 0)
			(layer "F.Fab")
			(effects
				(font
					(size 0.7 0.7)
					(thickness 0.15)
				)
				(justify right bottom)
			)
		)
		(property "Datasheet" "https://assets.nexperia.com/documents/data-sheet/PESD5V0X1UB.pdf"
			(at 0 0 180)
			(layer "F.Fab")
			(hide yes)
			(effects
				(font
					(size 1.27 1.27)
					(thickness 0.15)
				)
			)
		)
		(property "MPN" "PESD5V0X1UB,135"
			(at 0 0 180)
			(unlocked yes)
			(layer "F.Fab")
			(hide yes)
			(effects
				(font
					(size 1 1)
					(thickness 0.15)
				)
			)
		)
		(property "Manufacturer" "Nexperia"
			(at 0 0 180)
			(unlocked yes)
			(layer "F.Fab")
			(hide yes)
			(effects
				(font
					(size 1 1)
					(thickness 0.15)
				)
			)
		)
		(property "Author" "Antmicro"
			(at 0 0 180)
			(unlocked yes)
			(layer "F.Fab")
			(hide yes)
			(effects
				(font
					(size 1 1)
					(thickness 0.15)
				)
			)
		)
		(property "License" "Apache-2.0"
			(at 0 0 180)
			(unlocked yes)
			(layer "F.Fab")
			(hide yes)
			(effects
				(font
					(size 1 1)
					(thickness 0.15)
				)
			)
		)
		(sheetname "/HDMI + SD Card/")
		(sheetfile "hdmi-sd-card.kicad_sch")
		(attr smd)
		(fp_line
			(start -0.35 -0.5)
			(end -0.35 0.5)
			(stroke
				(width 0.15)
				(type solid)
			)
			(layer "F.SilkS")
		)
		(fp_rect
			(start -1 -0.6)
			(end 1 0.6)
			(stroke
				(width 0.05)
				(type solid)
			)
			(fill no)
			(layer "F.CrtYd")
		)
		(fp_line
			(start 0.65 -0.425)
			(end 0.65 0.423)
			(stroke
				(width 0.15)
				(type solid)
			)
			(layer "F.Fab")
		)
		(fp_line
			(start -0.35 -0.4)
			(end -0.35 0.4)
			(stroke
				(width 0.15)
				(type solid)
			)
			(layer "F.Fab")
		)
		(fp_line
			(start -0.652 0.423)
			(end 0.65 0.423)
			(stroke
				(width 0.15)
				(type solid)
			)
			(layer "F.Fab")
		)
		(fp_line
			(start -0.652 0.423)
			(end -0.652 -0.425)
			(stroke
				(width 0.15)
				(type solid)
			)
			(layer "F.Fab")
		)
		(fp_line
			(start -0.652 -0.425)
			(end 0.65 -0.425)
			(stroke
				(width 0.15)
				(type solid)
			)
			(layer "F.Fab")
		)
		(fp_text user "Author: Antmicro"
			(at -1.276 4.7 180)
			(layer "F.Fab")
			(effects
				(font
					(size 0.7 0.7)
					(thickness 0.15)
				)
				(justify left bottom)
			)
		)
		(fp_text user "License: Apache-2.0"
			(at -1.276 5.9 180)
			(layer "F.Fab")
			(effects
				(font
					(size 0.7 0.7)
					(thickness 0.15)
				)
				(justify left bottom)
			)
		)
		(fp_text user "${REFERENCE}"
			(at -1.276 3.499 180)
			(layer "F.Fab")
			(effects
				(font
					(size 0.7 0.7)
					(thickness 0.15)
				)
				(justify left bottom)
			)
		)
		(pad "1" smd roundrect
			(at -0.701 0 180)
			(size 0.5 0.6)
			(layers "F.Cu" "F.Mask" "F.Paste")
			(roundrect_rratio 0.25)
			(net 635 "/FPGA banks HP/SD.CD")
			(pinfunction "C")
			(pintype "passive")
		)
		(pad "2" smd roundrect
			(at 0.699 0 180)
			(size 0.5 0.6)
			(layers "F.Cu" "F.Mask" "F.Paste")
			(roundrect_rratio 0.25)
			(net 1 "GND")
			(pinfunction "A")
			(pintype "passive")
		)
	)
	(footprint "antmicro-footprints:USON-10_2.5x1mm_P0.5mm"
		(layer "F.Cu")
		(at 108.824499 143.749 180)
		(descr "USON-10 2.5x1mm_ Pitch 0.5mm")
		(tags "USON-10 2.5x1mm Pitch 0.5mm")
		(property "Reference" "U8"
			(at -2.025501 -0.151 90)
			(layer "F.SilkS")
			(effects
				(font
					(size 0.7 0.7)
					(thickness 0.15)
				)
				(justify right bottom)
			)
		)
		(property "Value" "TPD4E05U06QDQARQ1"
			(at 0.018 2.499 0)
			(layer "F.Fab")
			(effects
				(font
					(size 0.7 0.7)
					(thickness 0.15)
				)
				(justify right bottom)
			)
		)
		(property "Datasheet" "https://www.ti.com/lit/ds/symlink/tpd4e05u06-q1.pdf?HQS=dis-mous-null-mousermode-dsf-pf-null-wwe&ts=1663591265741&ref_url=https%253A%252F%252Fwww.mouser.com%252F"
			(at 0 0 180)
			(layer "F.Fab")
			(hide yes)
			(effects
				(font
					(size 1.27 1.27)
					(thickness 0.15)
				)
			)
		)
		(property "MPN" "TPD4E05U06QDQARQ1"
			(at 0 0 180)
			(unlocked yes)
			(layer "F.Fab")
			(hide yes)
			(effects
				(font
					(size 1 1)
					(thickness 0.15)
				)
			)
		)
		(property "Manufacturer" "Texas Instruments"
			(at 0 0 180)
			(unlocked yes)
			(layer "F.Fab")
			(hide yes)
			(effects
				(font
					(size 1 1)
					(thickness 0.15)
				)
			)
		)
		(property "Author" "Antmicro"
			(at 0 0 180)
			(unlocked yes)
			(layer "F.Fab")
			(hide yes)
			(effects
				(font
					(size 1 1)
					(thickness 0.15)
				)
			)
		)
		(property "License" "Apache-2.0"
			(at 0 0 180)
			(unlocked yes)
			(layer "F.Fab")
			(hide yes)
			(effects
				(font
					(size 1 1)
					(thickness 0.15)
				)
			)
		)
		(sheetname "/Debug FTDI + VNA/")
		(sheetfile "debug-ftdi.kicad_sch")
		(attr smd)
		(fp_line
			(start 0.498 1.398)
			(end -0.5 1.398)
			(stroke
				(width 0.15)
				(type solid)
			)
			(layer "F.SilkS")
		)
		(fp_line
			(start 0.498 -1.401)
			(end -0.5 -1.401)
			(stroke
				(width 0.15)
				(type solid)
			)
			(layer "F.SilkS")
		)
		(fp_circle
			(center -0.68 -1.27)
			(end -0.63 -1.27)
			(stroke
				(width 0.15)
				(type solid)
			)
			(fill yes)
			(layer "F.SilkS")
		)
		(fp_rect
			(start -0.8 -1.5)
			(end 0.8 1.499)
			(stroke
				(width 0.05)
				(type solid)
			)
			(fill no)
			(layer "F.CrtYd")
		)
		(fp_line
			(start 0.498 -1.25)
			(end 0.498 1.249)
			(stroke
				(width 0.15)
				(type solid)
			)
			(layer "F.Fab")
		)
		(fp_line
			(start 0.498 -1.25)
			(end -0.25 -1.25)
			(stroke
				(width 0.15)
				(type solid)
			)
			(layer "F.Fab")
		)
		(fp_line
			(start -0.25 -1.25)
			(end -0.5 -1)
			(stroke
				(width 0.15)
				(type solid)
			)
			(layer "F.Fab")
		)
		(fp_line
			(start -0.5 1.249)
			(end 0.498 1.249)
			(stroke
				(width 0.15)
				(type solid)
			)
			(layer "F.Fab")
		)
		(fp_line
			(start -0.5 -1)
			(end -0.5 1.249)
			(stroke
				(width 0.15)
				(type solid)
			)
			(layer "F.Fab")
		)
		(fp_text user "${REFERENCE}"
			(at -0.802 4.498 180)
			(layer "F.Fab")
			(effects
				(font
					(size 0.7 0.7)
					(thickness 0.15)
				)
				(justify left bottom)
			)
		)
		(fp_text user "Author: Antmicro"
			(at -0.802 5.7 180)
			(layer "F.Fab")
			(effects
				(font
					(size 0.7 0.7)
					(thickness 0.15)
				)
				(justify left bottom)
			)
		)
		(fp_text user "License: Apache-2.0"
			(at -0.802 6.9 180)
			(layer "F.Fab")
			(effects
				(font
					(size 0.7 0.7)
					(thickness 0.15)
				)
				(justify left bottom)
			)
		)
		(pad "1" smd roundrect
			(at -0.387 -1 90)
			(size 0.25 0.55)
			(layers "F.Cu" "F.Mask" "F.Paste")
			(roundrect_rratio 0.25)
			(net 366 "/Debug FTDI + VNA/CC2")
			(pintype "passive")
		)
		(pad "2" smd roundrect
			(at -0.387 -0.5 90)
			(size 0.25 0.55)
			(layers "F.Cu" "F.Mask" "F.Paste")
			(roundrect_rratio 0.25)
			(net 364 "/Debug FTDI + VNA/DBG_USB_P")
			(pintype "passive")
		)
		(pad "3" smd roundrect
			(at -0.387 0 90)
			(size 0.4 0.55)
			(layers "F.Cu" "F.Mask" "F.Paste")
			(roundrect_rratio 0.25)
			(net 1 "GND")
			(pintype "power_in")
		)
		(pad "4" smd roundrect
			(at -0.387 0.498 90)
			(size 0.25 0.55)
			(layers "F.Cu" "F.Mask" "F.Paste")
			(roundrect_rratio 0.25)
			(net 365 "/Debug FTDI + VNA/DBG_USB_N")
			(pintype "passive")
		)
		(pad "5" smd roundrect
			(at -0.387 0.998 90)
			(size 0.25 0.55)
			(layers "F.Cu" "F.Mask" "F.Paste")
			(roundrect_rratio 0.25)
			(net 363 "/Debug FTDI + VNA/CC1")
			(pintype "passive")
		)
		(pad "6" smd roundrect
			(at 0.385 0.998 90)
			(size 0.25 0.55)
			(layers "F.Cu" "F.Mask" "F.Paste")
			(roundrect_rratio 0.25)
			(net 363 "/Debug FTDI + VNA/CC1")
			(pintype "passive")
		)
		(pad "7" smd roundrect
			(at 0.385 0.498 90)
			(size 0.25 0.55)
			(layers "F.Cu" "F.Mask" "F.Paste")
			(roundrect_rratio 0.25)
			(net 365 "/Debug FTDI + VNA/DBG_USB_N")
			(pintype "passive")
		)
		(pad "8" smd roundrect
			(at 0.385 0 90)
			(size 0.4 0.55)
			(layers "F.Cu" "F.Mask" "F.Paste")
			(roundrect_rratio 0.25)
			(net 1 "GND")
			(pintype "passive")
		)
		(pad "9" smd roundrect
			(at 0.385 -0.5 90)
			(size 0.25 0.55)
			(layers "F.Cu" "F.Mask" "F.Paste")
			(roundrect_rratio 0.25)
			(net 364 "/Debug FTDI + VNA/DBG_USB_P")
			(pintype "passive")
		)
		(pad "10" smd roundrect
			(at 0.385 -1 90)
			(size 0.25 0.55)
			(layers "F.Cu" "F.Mask" "F.Paste")
			(roundrect_rratio 0.25)
			(net 366 "/Debug FTDI + VNA/CC2")
			(pintype "passive")
		)
	)
	(footprint "antmicro-footprints:LED_0402_1005Metric_G"
		(layer "F.Cu")
		(at 243.051 101.6)
		(property "Reference" "D22"
			(at 0 -0.6 0)
			(unlocked yes)
			(layer "F.SilkS")
			(hide yes)
			(effects
				(font
					(size 0.7 0.7)
					(thickness 0.15)
				)
				(justify left bottom)
			)
		)
		(property "Value" "LED_G_0402_VLMTG1500-GS08"
			(at 0 1.5 0)
			(unlocked yes)
			(layer "F.Fab")
			(effects
				(font
					(size 0.7 0.7)
					(thickness 0.15)
				)
				(justify left bottom)
			)
		)
		(property "Datasheet" "https://www.vishay.com/docs/82554/vlmo1500.pdf"
			(at 0 0 0)
			(layer "F.Fab")
			(hide yes)
			(effects
				(font
					(size 1.27 1.27)
					(thickness 0.15)
				)
			)
		)
		(property "MPN" "VLMTG1500-GS08"
			(at 0 0 0)
			(unlocked yes)
			(layer "F.Fab")
			(hide yes)
			(effects
				(font
					(size 1 1)
					(thickness 0.15)
				)
			)
		)
		(property "Manufacturer" "Vishay"
			(at 0 0 0)
			(unlocked yes)
			(layer "F.Fab")
			(hide yes)
			(effects
				(font
					(size 1 1)
					(thickness 0.15)
				)
			)
		)
		(property "Color" "Green"
			(at 0 0 0)
			(unlocked yes)
			(layer "F.Fab")
			(hide yes)
			(effects
				(font
					(size 1 1)
					(thickness 0.15)
				)
			)
		)
		(property "Author" "Antmicro"
			(at 0 0 0)
			(unlocked yes)
			(layer "F.Fab")
			(hide yes)
			(effects
				(font
					(size 1 1)
					(thickness 0.15)
				)
			)
		)
		(property "License" "Apache-2.0"
			(at 0 0 0)
			(unlocked yes)
			(layer "F.Fab")
			(hide yes)
			(effects
				(font
					(size 1 1)
					(thickness 0.15)
				)
			)
		)
		(sheetname "/DDR5 RDIMM/")
		(sheetfile "ddr5-rdimm.kicad_sch")
		(attr smd)
		(fp_line
			(start -0.9 -0.4)
			(end -0.9 0.4)
			(stroke
				(width 0.15)
				(type solid)
			)
			(layer "F.SilkS")
		)
		(fp_line
			(start -0.175 -0.4)
			(end 0.175 -0.4)
			(stroke
				(width 0.15)
				(type solid)
			)
			(layer "F.SilkS")
		)
		(fp_line
			(start -0.175 0.4)
			(end 0.175 0.4)
			(stroke
				(width 0.15)
				(type solid)
			)
			(layer "F.SilkS")
		)
		(fp_rect
			(start -0.925 -0.47)
			(end 0.925 0.47)
			(stroke
				(width 0.05)
				(type default)
			)
			(fill no)
			(layer "F.CrtYd")
		)
		(fp_line
			(start -0.489 -0.248)
			(end -0.489 0.26)
			(stroke
				(width 0.15)
				(type solid)
			)
			(layer "F.Fab")
		)
		(fp_line
			(start -0.489 -0.248)
			(end -0.489 0.26)
			(stroke
				(width 0.15)
				(type solid)
			)
			(layer "F.Fab")
		)
		(fp_line
			(start -0.489 0.26)
			(end -0.158 0.26)
			(stroke
				(width 0.15)
				(type solid)
			)
			(layer "F.Fab")
		)
		(fp_line
			(start -0.489 0.26)
			(end 0.501 0.26)
			(stroke
				(width 0.15)
				(type solid)
			)
			(layer "F.Fab")
		)
		(fp_line
			(start -0.173 -0.202)
			(end -0.173 0.102)
			(stroke
				(width 0.15)
				(type solid)
			)
			(layer "F.Fab")
		)
		(fp_line
			(start -0.173 0.202)
			(end -0.173 0.102)
			(stroke
				(width 0.15)
				(type solid)
			)
			(layer "F.Fab")
		)
		(fp_line
			(start -0.158 -0.248)
			(end -0.489 -0.248)
			(stroke
				(width 0.15)
				(type solid)
			)
			(layer "F.Fab")
		)
		(fp_line
			(start -0.158 0.26)
			(end -0.158 -0.248)
			(stroke
				(width 0.15)
				(type solid)
			)
			(layer "F.Fab")
		)
		(fp_line
			(start -0.074 0)
			(end 0.228 0.202)
			(stroke
				(width 0.15)
				(type solid)
			)
			(layer "F.Fab")
		)
		(fp_line
			(start 0.172 -0.248)
			(end 0.172 0.26)
			(stroke
				(width 0.15)
				(type solid)
			)
			(layer "F.Fab")
		)
		(fp_line
			(start 0.172 0.26)
			(end 0.501 0.26)
			(stroke
				(width 0.15)
				(type solid)
			)
			(layer "F.Fab")
		)
		(fp_line
			(start 0.228 -0.202)
			(end -0.074 0)
			(stroke
				(width 0.15)
				(type solid)
			)
			(layer "F.Fab")
		)
		(fp_line
			(start 0.228 0)
			(end 0.228 -0.202)
			(stroke
				(width 0.15)
				(type solid)
			)
			(layer "F.Fab")
		)
		(fp_line
			(start 0.228 0.202)
			(end 0.228 0)
			(stroke
				(width 0.15)
				(type solid)
			)
			(layer "F.Fab")
		)
		(fp_line
			(start 0.501 -0.248)
			(end -0.489 -0.248)
			(stroke
				(width 0.15)
				(type solid)
			)
			(layer "F.Fab")
		)
		(fp_line
			(start 0.501 -0.248)
			(end 0.172 -0.248)
			(stroke
				(width 0.15)
				(type solid)
			)
			(layer "F.Fab")
		)
		(fp_line
			(start 0.501 0.26)
			(end 0.501 -0.248)
			(stroke
				(width 0.15)
				(type solid)
			)
			(layer "F.Fab")
		)
		(fp_line
			(start 0.501 0.26)
			(end 0.501 -0.248)
			(stroke
				(width 0.15)
				(type solid)
			)
			(layer "F.Fab")
		)
		(fp_text user "Author: Antmicro"
			(at 0 4.15 0)
			(layer "F.Fab")
			(effects
				(font
					(size 0.7 0.7)
					(thickness 0.15)
				)
				(justify left bottom)
			)
		)
		(fp_text user "License: Apache-2.0"
			(at 0 5.35 0)
			(layer "F.Fab")
			(effects
				(font
					(size 0.7 0.7)
					(thickness 0.15)
				)
				(justify left bottom)
			)
		)
		(fp_text user "${REFERENCE}"
			(at 0 2.95 0)
			(unlocked yes)
			(layer "F.Fab")
			(effects
				(font
					(size 0.7 0.7)
					(thickness 0.15)
				)
				(justify left bottom)
			)
		)
		(pad "1" smd roundrect
			(at -0.48 0)
			(size 0.59 0.64)
			(layers "F.Cu" "F.Mask" "F.Paste")
			(roundrect_rratio 0.25)
			(net 805 "Net-(D22-C)")
			(pinfunction "C")
			(pintype "passive")
		)
		(pad "2" smd roundrect
			(at 0.48 0)
			(size 0.59 0.64)
			(layers "F.Cu" "F.Mask" "F.Paste")
			(roundrect_rratio 0.25)
			(net 803 "/DDR5 RDIMM/VIN_MGMT")
			(pinfunction "A")
			(pintype "passive")
		)
	)
	(footprint "antmicro-footprints:SW_KMR211NGLFS_SMD"
		(layer "F.Cu")
		(at 260.573 137.475 90)
		(property "Reference" "SW2"
			(at -1.1 -2 90)
			(layer "F.SilkS")
			(hide yes)
			(effects
				(font
					(size 0.7 0.7)
					(thickness 0.15)
				)
				(justify left bottom)
			)
		)
		(property "Value" "SW_KMR211NGLFS_SMD"
			(at 0 2.8 90)
			(layer "F.Fab")
			(effects
				(font
					(size 0.7 0.7)
					(thickness 0.15)
				)
				(justify left bottom)
			)
		)
		(property "Datasheet" "http://www.farnell.com/datasheets/2631211.pdf"
			(at 0 0 90)
			(layer "F.Fab")
			(hide yes)
			(effects
				(font
					(size 1.27 1.27)
					(thickness 0.15)
				)
			)
		)
		(property "MPN" "KMR211NGLFS"
			(at 0 0 90)
			(unlocked yes)
			(layer "F.Fab")
			(hide yes)
			(effects
				(font
					(size 1 1)
					(thickness 0.15)
				)
			)
		)
		(property "Manufacturer" "C&K"
			(at 0 0 90)
			(unlocked yes)
			(layer "F.Fab")
			(hide yes)
			(effects
				(font
					(size 1 1)
					(thickness 0.15)
				)
			)
		)
		(property "Author" "Antmicro"
			(at 0 0 90)
			(unlocked yes)
			(layer "F.Fab")
			(hide yes)
			(effects
				(font
					(size 1 1)
					(thickness 0.15)
				)
			)
		)
		(property "License" "Apache-2.0"
			(at 0 0 90)
			(unlocked yes)
			(layer "F.Fab")
			(hide yes)
			(effects
				(font
					(size 1 1)
					(thickness 0.15)
				)
			)
		)
		(sheetname "/FPGA Config/")
		(sheetfile "fpga-config.kicad_sch")
		(attr smd)
		(fp_line
			(start 2.101 -1.6)
			(end -2.1 -1.6)
			(stroke
				(width 0.15)
				(type solid)
			)
			(layer "F.SilkS")
		)
		(fp_line
			(start -2.1 -1.6)
			(end -2.1 -1.499)
			(stroke
				(width 0.15)
				(type solid)
			)
			(layer "F.SilkS")
		)
		(fp_line
			(start 2.101 -1.58)
			(end 2.101 -1.459)
			(stroke
				(width 0.15)
				(type solid)
			)
			(layer "F.SilkS")
		)
		(fp_line
			(start 2.101 1.601)
			(end 2.101 1.48)
			(stroke
				(width 0.15)
				(type solid)
			)
			(layer "F.SilkS")
		)
		(fp_line
			(start 2.101 1.601)
			(end -2.1 1.601)
			(stroke
				(width 0.15)
				(type solid)
			)
			(layer "F.SilkS")
		)
		(fp_line
			(start -2.1 1.601)
			(end -2.1 1.48)
			(stroke
				(width 0.15)
				(type solid)
			)
			(layer "F.SilkS")
		)
		(fp_rect
			(start 2.751 1.75)
			(end -2.748 -1.749)
			(stroke
				(width 0.05)
				(type solid)
			)
			(fill no)
			(layer "F.CrtYd")
		)
		(fp_line
			(start 2.101 -1.6)
			(end -2.1 -1.6)
			(stroke
				(width 0.15)
				(type solid)
			)
			(layer "F.Fab")
		)
		(fp_line
			(start -2.1 -1.6)
			(end -2.1 1.601)
			(stroke
				(width 0.15)
				(type solid)
			)
			(layer "F.Fab")
		)
		(fp_line
			(start -0.248 -0.8)
			(end 0.25 -0.8)
			(stroke
				(width 0.15)
				(type solid)
			)
			(layer "F.Fab")
		)
		(fp_line
			(start 0.25 0.802)
			(end -0.248 0.802)
			(stroke
				(width 0.15)
				(type solid)
			)
			(layer "F.Fab")
		)
		(fp_line
			(start 2.101 1.601)
			(end 2.101 -1.6)
			(stroke
				(width 0.15)
				(type solid)
			)
			(layer "F.Fab")
		)
		(fp_line
			(start -2.1 1.601)
			(end 2.101 1.601)
			(stroke
				(width 0.15)
				(type solid)
			)
			(layer "F.Fab")
		)
		(fp_arc
			(start 0.25 -0.8)
			(mid 1.051001 0.001)
			(end 0.25 0.802)
			(stroke
				(width 0.15)
				(type solid)
			)
			(layer "F.Fab")
		)
		(fp_arc
			(start -0.248 0.802)
			(mid -1.050001 0.001)
			(end -0.248 -0.8)
			(stroke
				(width 0.15)
				(type solid)
			)
			(layer "F.Fab")
		)
		(fp_text user "Author: Antmicro"
			(at -3 5.5 90)
			(layer "F.Fab")
			(effects
				(font
					(size 0.7 0.7)
					(thickness 0.15)
				)
				(justify left bottom)
			)
		)
		(fp_text user "License: Apache-2.0"
			(at -3 6.75 90)
			(layer "F.Fab")
			(effects
				(font
					(size 0.7 0.7)
					(thickness 0.15)
				)
				(justify left bottom)
			)
		)
		(fp_text user "${REFERENCE}"
			(at -3 4.25 90)
			(layer "F.Fab")
			(effects
				(font
					(size 0.7 0.7)
					(thickness 0.15)
				)
				(justify left bottom)
			)
		)
		(pad "1" smd rect
			(at -2.048 -0.8 270)
			(size 0.9 1)
			(layers "F.Cu" "F.Mask" "F.Paste")
			(net 357 "/FPGA Config/PROGRAM_B")
			(pinfunction "1")
			(pintype "passive")
		)
		(pad "2" smd rect
			(at 2.05 -0.8 270)
			(size 0.9 1)
			(layers "F.Cu" "F.Mask" "F.Paste")
			(net 357 "/FPGA Config/PROGRAM_B")
			(pinfunction "2")
			(pintype "passive")
		)
		(pad "3" smd rect
			(at -2.048 0.802 270)
			(size 0.9 1)
			(layers "F.Cu" "F.Mask" "F.Paste")
			(net 1 "GND")
			(pinfunction "3")
			(pintype "passive")
		)
		(pad "4" smd rect
			(at 2.05 0.802 270)
			(size 0.9 1)
			(layers "F.Cu" "F.Mask" "F.Paste")
			(net 1 "GND")
			(pinfunction "4")
			(pintype "passive")
		)
	)
	(footprint "antmicro-footprints:Vishay_PowerPAK_1212-8_Single"
		(layer "F.Cu")
		(at 247.255 115.74 90)
		(descr "PowerPAK 1212-8 Single")
		(tags "Vishay PowerPAK 1212-8 Single")
		(property "Reference" "Q23"
			(at -2.16 1.845 0)
			(layer "F.SilkS")
			(effects
				(font
					(size 0.7 0.7)
					(thickness 0.15)
				)
				(justify right top)
			)
		)
		(property "Value" "SI7613DN-T1-GE3"
			(at 0 2.7 90)
			(layer "F.Fab")
			(effects
				(font
					(size 0.7 0.7)
					(thickness 0.15)
				)
				(justify left bottom)
			)
		)
		(property "Datasheet" "https://www.vishay.com/docs/64809/si7613dn.pdf"
			(at 0 0 90)
			(layer "F.Fab")
			(hide yes)
			(effects
				(font
					(size 1.27 1.27)
					(thickness 0.15)
				)
			)
		)
		(property "MPN" "SI7613DN-T1-GE3"
			(at 0 0 90)
			(unlocked yes)
			(layer "F.Fab")
			(hide yes)
			(effects
				(font
					(size 1 1)
					(thickness 0.15)
				)
			)
		)
		(property "Manufacturer" "Vishay"
			(at 0 0 90)
			(unlocked yes)
			(layer "F.Fab")
			(hide yes)
			(effects
				(font
					(size 1 1)
					(thickness 0.15)
				)
			)
		)
		(property "Author" "Antmicro"
			(at 0 0 90)
			(unlocked yes)
			(layer "F.Fab")
			(hide yes)
			(effects
				(font
					(size 1 1)
					(thickness 0.15)
				)
			)
		)
		(property "License" "Apache-2.0"
			(at 0 0 90)
			(unlocked yes)
			(layer "F.Fab")
			(hide yes)
			(effects
				(font
					(size 1 1)
					(thickness 0.15)
				)
			)
		)
		(sheetname "/DDR5 RDIMM/")
		(sheetfile "ddr5-rdimm.kicad_sch")
		(attr smd)
		(fp_line
			(start 1.648 -1.651)
			(end 1.648 -1.317)
			(stroke
				(width 0.15)
				(type solid)
			)
			(layer "F.SilkS")
		)
		(fp_line
			(start -1.651 -1.651)
			(end 1.648 -1.651)
			(stroke
				(width 0.15)
				(type solid)
			)
			(layer "F.SilkS")
		)
		(fp_line
			(start -1.651 -1.651)
			(end -1.651 -1.317)
			(stroke
				(width 0.15)
				(type solid)
			)
			(layer "F.SilkS")
		)
		(fp_line
			(start 1.634 1.3)
			(end 1.634 1.634)
			(stroke
				(width 0.15)
				(type solid)
			)
			(layer "F.SilkS")
		)
		(fp_line
			(start -1.635 1.3)
			(end -1.635 1.634)
			(stroke
				(width 0.15)
				(type solid)
			)
			(layer "F.SilkS")
		)
		(fp_line
			(start -1.635 1.634)
			(end 1.634 1.634)
			(stroke
				(width 0.15)
				(type solid)
			)
			(layer "F.SilkS")
		)
		(fp_circle
			(center -1.9 -1.4)
			(end -1.85 -1.4)
			(stroke
				(width 0.15)
				(type solid)
			)
			(fill yes)
			(layer "F.SilkS")
		)
		(fp_rect
			(start -2 -1.8)
			(end 2 1.798)
			(stroke
				(width 0.05)
				(type solid)
			)
			(fill no)
			(layer "F.CrtYd")
		)
		(fp_line
			(start -1.6425 -1.4175)
			(end -1.4175 -1.6425)
			(stroke
				(width 0.15)
				(type solid)
			)
			(layer "F.Fab")
		)
		(fp_rect
			(start -1.651 -1.651)
			(end 1.648 1.648)
			(stroke
				(width 0.15)
				(type solid)
			)
			(fill no)
			(layer "F.Fab")
		)
		(fp_text user "License: Apache-2.0"
			(at -8 7.1 90)
			(layer "F.Fab")
			(effects
				(font
					(size 0.7 0.7)
					(thickness 0.15)
				)
				(justify left bottom)
			)
		)
		(fp_text user "${REFERENCE}"
			(at -8 4.7 90)
			(layer "F.Fab")
			(effects
				(font
					(size 0.7 0.7)
					(thickness 0.15)
				)
				(justify left bottom)
			)
		)
		(fp_text user "Author: Antmicro"
			(at -8 5.9 90)
			(layer "F.Fab")
			(effects
				(font
					(size 0.7 0.7)
					(thickness 0.15)
				)
				(justify left bottom)
			)
		)
		(pad "1" smd rect
			(at -1.436 -0.99 90)
			(size 0.99 0.405)
			(layers "F.Cu" "F.Mask" "F.Paste")
			(net 35 "VDC")
			(pinfunction "S")
			(pintype "passive")
		)
		(pad "2" smd rect
			(at -1.436 -0.332 90)
			(size 0.99 0.405)
			(layers "F.Cu" "F.Mask" "F.Paste")
			(net 35 "VDC")
			(pinfunction "S")
			(pintype "passive")
		)
		(pad "3" smd rect
			(at -1.436 0.33 90)
			(size 0.99 0.405)
			(layers "F.Cu" "F.Mask" "F.Paste")
			(net 35 "VDC")
			(pinfunction "S")
			(pintype "passive")
		)
		(pad "4" smd rect
			(at -1.436 0.988 90)
			(size 0.99 0.405)
			(layers "F.Cu" "F.Mask" "F.Paste")
			(net 806 "Net-(Q23-G)")
			(pinfunction "G")
			(pintype "passive")
		)
		(pad "5" smd custom
			(at 0.557 0 90)
			(size 1.725 2.235)
			(layers "F.Cu" "F.Mask" "F.Paste")
			(net 802 "/DDR5 RDIMM/VIN_BULK")
			(pinfunction "D")
			(pintype "passive")
			(zone_connect 2)
			(options
				(clearance outline)
				(anchor rect)
			)
			(primitives
				(gr_poly
					(pts
						(xy 0.8625 0.1275) (xy 0.8625 -0.1275) (xy 1.3725 -0.1275) (xy 1.3725 -0.5325) (xy 0.8625 -0.5325)
						(xy 0.8625 -0.7875) (xy 1.3725 -0.7875) (xy 1.3725 -1.195) (xy 0.6125 -1.195) (xy 0.6125 1.195)
						(xy 1.3725 1.195) (xy 1.3725 0.7875) (xy 0.8625 0.7875) (xy 0.8625 0.5325) (xy 1.3725 0.5325)
						(xy 1.3725 0.1275)
					)
					(width 0)
					(fill yes)
				)
			)
		)
	)
	(footprint "antmicro-footprints:TP_SMD_1mm"
		(layer "F.Cu")
		(at 244.05 155.925)
		(property "Reference" "TP12"
			(at 0 -0.731898 0)
			(layer "F.SilkS")
			(hide yes)
			(effects
				(font
					(size 0.7 0.7)
					(thickness 0.15)
				)
				(justify left bottom)
			)
		)
		(property "Value" "TP_1mm_SMD"
			(at 0 1.4 0)
			(layer "F.Fab")
			(effects
				(font
					(size 0.7 0.7)
					(thickness 0.15)
				)
				(justify left bottom)
			)
		)
		(property "MPN" ""
			(at 0 0 0)
			(unlocked yes)
			(layer "F.Fab")
			(hide yes)
			(effects
				(font
					(size 1 1)
					(thickness 0.15)
				)
			)
		)
		(property "Manufacturer" ""
			(at 0 0 0)
			(unlocked yes)
			(layer "F.Fab")
			(hide yes)
			(effects
				(font
					(size 1 1)
					(thickness 0.15)
				)
			)
		)
		(property "Author" "Antmicro"
			(at 0 0 0)
			(unlocked yes)
			(layer "F.Fab")
			(hide yes)
			(effects
				(font
					(size 1 1)
					(thickness 0.15)
				)
			)
		)
		(property "License" "Apache-2.0"
			(at 0 0 0)
			(unlocked yes)
			(layer "F.Fab")
			(hide yes)
			(effects
				(font
					(size 1 1)
					(thickness 0.15)
				)
			)
		)
		(sheetname "/Supply/DC-DC IO/")
		(sheetfile "dc-dc-io.kicad_sch")
		(attr exclude_from_pos_files)
		(fp_circle
			(center 0 0)
			(end 0.6 0)
			(stroke
				(width 0.05)
				(type default)
			)
			(fill no)
			(layer "F.CrtYd")
		)
		(fp_text user "${REFERENCE}"
			(at -0.5 2.8 0)
			(layer "F.Fab")
			(effects
				(font
					(size 0.7 0.7)
					(thickness 0.15)
				)
				(justify left bottom)
			)
		)
		(fp_text user "Author: Antmicro"
			(at -0.5 4 0)
			(layer "F.Fab")
			(effects
				(font
					(size 0.7 0.7)
					(thickness 0.15)
				)
				(justify left bottom)
			)
		)
		(fp_text user "License: Apache-2.0"
			(at -0.5 5.2 0)
			(layer "F.Fab")
			(effects
				(font
					(size 0.7 0.7)
					(thickness 0.15)
				)
				(justify left bottom)
			)
		)
		(pad "1" smd circle
			(at 0 0)
			(size 1 1)
			(layers "F.Cu" "F.Mask")
			(net 151 "+3V3")
			(pinfunction "1")
			(pintype "passive")
		)
	)
	(footprint "antmicro-footprints:R_0402_1005Metric"
		(layer "F.Cu")
		(at 119.15 147.61 180)
		(descr "Resistor SMD 0402")
		(tags "resistor SMD 0402")
		(property "Reference" "R30"
			(at -5.12 -0.42 0)
			(layer "F.SilkS")
			(effects
				(font
					(size 0.7 0.7)
					(thickness 0.15)
				)
				(justify right bottom)
			)
		)
		(property "Value" "R_49k9_0402"
			(at -1.011843 1.772047 0)
			(layer "F.Fab")
			(effects
				(font
					(size 0.7 0.7)
					(thickness 0.15)
				)
				(justify right bottom)
			)
		)
		(property "Datasheet" "https://www.bourns.com/docs/product-datasheets/cr.pdf"
			(at 0 0 180)
			(layer "F.Fab")
			(hide yes)
			(effects
				(font
					(size 1.27 1.27)
					(thickness 0.15)
				)
			)
		)
		(property "MPN" "CR0402-FX-4992GLF"
			(at 0 0 180)
			(unlocked yes)
			(layer "F.Fab")
			(hide yes)
			(effects
				(font
					(size 1 1)
					(thickness 0.15)
				)
			)
		)
		(property "Manufacturer" "Bourns"
			(at 0 0 180)
			(unlocked yes)
			(layer "F.Fab")
			(hide yes)
			(effects
				(font
					(size 1 1)
					(thickness 0.15)
				)
			)
		)
		(property "License" "Apache-2.0"
			(at 0 0 180)
			(unlocked yes)
			(layer "F.Fab")
			(hide yes)
			(effects
				(font
					(size 1 1)
					(thickness 0.15)
				)
			)
		)
		(property "Author" "Antmicro"
			(at 0 0 180)
			(unlocked yes)
			(layer "F.Fab")
			(hide yes)
			(effects
				(font
					(size 1 1)
					(thickness 0.15)
				)
			)
		)
		(property "Val" "49k9"
			(at 0 0 180)
			(unlocked yes)
			(layer "F.Fab")
			(hide yes)
			(effects
				(font
					(size 1 1)
					(thickness 0.15)
				)
			)
		)
		(property "Tolerance" "1%"
			(at 0 0 180)
			(unlocked yes)
			(layer "F.Fab")
			(hide yes)
			(effects
				(font
					(size 1 1)
					(thickness 0.15)
				)
			)
		)
		(sheetname "/HDMI + SD Card/")
		(sheetfile "hdmi-sd-card.kicad_sch")
		(attr smd)
		(fp_rect
			(start -0.925 -0.47)
			(end 0.925 0.47)
			(stroke
				(width 0.05)
				(type default)
			)
			(fill no)
			(layer "F.CrtYd")
		)
		(fp_rect
			(start -0.5 -0.25)
			(end 0.5 0.25)
			(stroke
				(width 0.15)
				(type solid)
			)
			(fill no)
			(layer "F.Fab")
		)
		(fp_text user "Author: Antmicro"
			(at -0.95 4.169 180)
			(layer "F.Fab")
			(effects
				(font
					(size 0.7 0.7)
					(thickness 0.15)
				)
				(justify left bottom)
			)
		)
		(fp_text user "License: Apache-2.0"
			(at -0.95 5.169 180)
			(layer "F.Fab")
			(effects
				(font
					(size 0.7 0.7)
					(thickness 0.15)
				)
				(justify left bottom)
			)
		)
		(fp_text user "${REFERENCE}"
			(at -0.95 3.168 180)
			(layer "F.Fab")
			(effects
				(font
					(size 0.7 0.7)
					(thickness 0.15)
				)
				(justify left bottom)
			)
		)
		(pad "1" smd roundrect
			(at -0.48 0 180)
			(size 0.59 0.64)
			(layers "F.Cu" "F.Mask" "F.Paste")
			(roundrect_rratio 0.25)
			(net 676 "Net-(L6-Pad2)")
			(pintype "passive")
		)
		(pad "2" smd roundrect
			(at 0.48 0 180)
			(size 0.59 0.64)
			(layers "F.Cu" "F.Mask" "F.Paste")
			(roundrect_rratio 0.25)
			(net 322 "Net-(C300-Pad2)")
			(pintype "passive")
		)
	)
	(footprint "antmicro-footprints:Conn_JST_SH_1x4_BM04B-SRSS-TB-LF-SN"
		(layer "F.Cu")
		(at 255.975 184.975)
		(property "Reference" "J12"
			(at -2.195 4.17 0)
			(layer "F.SilkS")
			(effects
				(font
					(size 0.7 0.7)
					(thickness 0.15)
				)
				(justify left bottom)
			)
		)
		(property "Value" "JST_SH_1x4_BM04B-SRSS-TB-LF-SN"
			(at -3.25 5 0)
			(layer "F.Fab")
			(effects
				(font
					(size 0.7 0.7)
					(thickness 0.15)
				)
				(justify left bottom)
			)
		)
		(property "Datasheet" "https://www.jst-mfg.com/product/pdf/eng/eSH.pdf"
			(at 0 0 0)
			(layer "F.Fab")
			(hide yes)
			(effects
				(font
					(size 1.27 1.27)
					(thickness 0.15)
				)
			)
		)
		(property "MPN" "BM04B-SRSS-TB(LF)(SN) "
			(at 0 0 0)
			(unlocked yes)
			(layer "F.Fab")
			(hide yes)
			(effects
				(font
					(size 1 1)
					(thickness 0.15)
				)
			)
		)
		(property "Manufacturer" "JST Automotive Connectors"
			(at 0 0 0)
			(unlocked yes)
			(layer "F.Fab")
			(hide yes)
			(effects
				(font
					(size 1 1)
					(thickness 0.15)
				)
			)
		)
		(property "Author" "Antmicro"
			(at 0 0 0)
			(unlocked yes)
			(layer "F.Fab")
			(hide yes)
			(effects
				(font
					(size 1 1)
					(thickness 0.15)
				)
			)
		)
		(property "License" "Apache-2.0"
			(at 0 0 0)
			(unlocked yes)
			(layer "F.Fab")
			(hide yes)
			(effects
				(font
					(size 1 1)
					(thickness 0.15)
				)
			)
		)
		(sheetname "/I^{2}C + I3C/")
		(sheetfile "i2c.kicad_sch")
		(attr smd)
		(fp_line
			(start -1.125 -2.999)
			(end -1.125 -2.201)
			(stroke
				(width 0.15)
				(type solid)
			)
			(layer "F.SilkS")
		)
		(fp_line
			(start -1.125 2.999)
			(end -1.125 2.201)
			(stroke
				(width 0.15)
				(type solid)
			)
			(layer "F.SilkS")
		)
		(fp_line
			(start -0.251 -2.999)
			(end -1.125 -2.999)
			(stroke
				(width 0.15)
				(type solid)
			)
			(layer "F.SilkS")
		)
		(fp_line
			(start -0.251 2.999)
			(end -1.125 2.999)
			(stroke
				(width 0.15)
				(type solid)
			)
			(layer "F.SilkS")
		)
		(fp_line
			(start 1.774 -1.7)
			(end 1.774 1.702)
			(stroke
				(width 0.15)
				(type solid)
			)
			(layer "F.SilkS")
		)
		(fp_circle
			(center -1.6 -2.1)
			(end -1.55 -2.1)
			(stroke
				(width 0.15)
				(type solid)
			)
			(fill yes)
			(layer "F.SilkS")
		)
		(fp_rect
			(start -2.05 -3.95)
			(end 2.05 3.95)
			(stroke
				(width 0.05)
				(type solid)
			)
			(fill no)
			(layer "F.CrtYd")
		)
		(fp_rect
			(start -1.8 -3)
			(end 1.8 3)
			(stroke
				(width 0.15)
				(type solid)
			)
			(fill no)
			(layer "F.Fab")
		)
		(fp_text user "Author: Antmicro"
			(at -3.25 7 0)
			(layer "F.Fab")
			(effects
				(font
					(size 0.7 0.7)
					(thickness 0.15)
				)
				(justify left bottom)
			)
		)
		(fp_text user "${REFERENCE}"
			(at -3.25 8.2 0)
			(layer "F.Fab")
			(effects
				(font
					(size 0.7 0.7)
					(thickness 0.15)
				)
				(justify left bottom)
			)
		)
		(fp_text user "License: Apache-2.0"
			(at -3.25 9.4 0)
			(layer "F.Fab")
			(effects
				(font
					(size 0.7 0.7)
					(thickness 0.15)
				)
				(justify left bottom)
			)
		)
		(pad "1" smd roundrect
			(at -1.45 -1.5 270)
			(size 0.6 1.55)
			(layers "F.Cu" "F.Mask" "F.Paste")
			(roundrect_rratio 0.25)
			(net 1 "GND")
			(pintype "passive")
		)
		(pad "2" smd roundrect
			(at -1.45 -0.5 270)
			(size 0.6 1.55)
			(layers "F.Cu" "F.Mask" "F.Paste")
			(roundrect_rratio 0.25)
			(net 664 "Net-(C325-Pad2)")
			(pintype "passive")
		)
		(pad "3" smd roundrect
			(at -1.45 0.5 270)
			(size 0.6 1.55)
			(layers "F.Cu" "F.Mask" "F.Paste")
			(roundrect_rratio 0.25)
			(net 369 "/I^{2}C + I3C/I3C_EXT.SCL")
			(pintype "passive")
		)
		(pad "4" smd roundrect
			(at -1.45 1.5 270)
			(size 0.6 1.55)
			(layers "F.Cu" "F.Mask" "F.Paste")
			(roundrect_rratio 0.25)
			(net 368 "/I^{2}C + I3C/I3C_EXT.SDA")
			(pintype "passive")
		)
		(pad "MP" smd roundrect
			(at 1.075 -2.8 270)
			(size 1.2 1.8)
			(layers "F.Cu" "F.Mask" "F.Paste")
			(roundrect_rratio 0.25)
			(net 1 "GND")
			(pintype "passive")
		)
		(pad "MP" smd roundrect
			(at 1.075 2.8 270)
			(size 1.2 1.8)
			(layers "F.Cu" "F.Mask" "F.Paste")
			(roundrect_rratio 0.25)
			(net 1 "GND")
			(pintype "passive")
		)
	)
	(footprint "antmicro-footprints:R_0402_1005Metric"
		(layer "F.Cu")
		(at 127.681 168.3125 90)
		(descr "Resistor SMD 0402")
		(tags "resistor SMD 0402")
		(property "Reference" "R77"
			(at -3.15 0.619 90)
			(layer "F.SilkS")
			(effects
				(font
					(size 0.7 0.7)
					(thickness 0.15)
				)
				(justify left bottom)
			)
		)
		(property "Value" "R_64k9_0402"
			(at -1.011843 1.772047 90)
			(layer "F.Fab")
			(effects
				(font
					(size 0.7 0.7)
					(thickness 0.15)
				)
				(justify left bottom)
			)
		)
		(property "Datasheet" "https://www.bourns.com/docs/product-datasheets/cr.pdf"
			(at 0 0 90)
			(layer "F.Fab")
			(hide yes)
			(effects
				(font
					(size 1.27 1.27)
					(thickness 0.15)
				)
			)
		)
		(property "MPN" "CR0402-FX-6492GLF"
			(at 0 0 90)
			(unlocked yes)
			(layer "F.Fab")
			(hide yes)
			(effects
				(font
					(size 1 1)
					(thickness 0.15)
				)
			)
		)
		(property "Manufacturer" "Bourns"
			(at 0 0 90)
			(unlocked yes)
			(layer "F.Fab")
			(hide yes)
			(effects
				(font
					(size 1 1)
					(thickness 0.15)
				)
			)
		)
		(property "License" "Apache-2.0"
			(at 0 0 90)
			(unlocked yes)
			(layer "F.Fab")
			(hide yes)
			(effects
				(font
					(size 1 1)
					(thickness 0.15)
				)
			)
		)
		(property "Author" "Antmicro"
			(at 0 0 90)
			(unlocked yes)
			(layer "F.Fab")
			(hide yes)
			(effects
				(font
					(size 1 1)
					(thickness 0.15)
				)
			)
		)
		(property "Val" "64k9"
			(at 0 0 90)
			(unlocked yes)
			(layer "F.Fab")
			(hide yes)
			(effects
				(font
					(size 1 1)
					(thickness 0.15)
				)
			)
		)
		(property "Tolerance" "1%"
			(at 0 0 90)
			(unlocked yes)
			(layer "F.Fab")
			(hide yes)
			(effects
				(font
					(size 1 1)
					(thickness 0.15)
				)
			)
		)
		(sheetname "/HDMI + SD Card/")
		(sheetfile "hdmi-sd-card.kicad_sch")
		(attr smd exclude_from_bom)
		(fp_rect
			(start -0.925 -0.47)
			(end 0.925 0.47)
			(stroke
				(width 0.05)
				(type default)
			)
			(fill no)
			(layer "F.CrtYd")
		)
		(fp_rect
			(start -0.5 -0.25)
			(end 0.5 0.25)
			(stroke
				(width 0.15)
				(type solid)
			)
			(fill no)
			(layer "F.Fab")
		)
		(fp_text user "License: Apache-2.0"
			(at -0.95 5.169 90)
			(layer "F.Fab")
			(effects
				(font
					(size 0.7 0.7)
					(thickness 0.15)
				)
				(justify left bottom)
			)
		)
		(fp_text user "${REFERENCE}"
			(at -0.95 3.168 90)
			(layer "F.Fab")
			(effects
				(font
					(size 0.7 0.7)
					(thickness 0.15)
				)
				(justify left bottom)
			)
		)
		(fp_text user "Author: Antmicro"
			(at -0.95 4.169 90)
			(layer "F.Fab")
			(effects
				(font
					(size 0.7 0.7)
					(thickness 0.15)
				)
				(justify left bottom)
			)
		)
		(pad "1" smd roundrect
			(at -0.48 0 90)
			(size 0.59 0.64)
			(layers "F.Cu" "F.Mask" "F.Paste")
			(roundrect_rratio 0.25)
			(net 1 "GND")
			(pintype "passive")
		)
		(pad "2" smd roundrect
			(at 0.48 0 90)
			(size 0.59 0.64)
			(layers "F.Cu" "F.Mask" "F.Paste")
			(roundrect_rratio 0.25)
			(net 710 "/HDMI + SD Card/I2C_EN{slash}PIN")
			(pintype "passive")
		)
	)
	(footprint "antmicro-footprints:C_0402_1005Metric"
		(layer "F.Cu")
		(at 250.4 115.98 90)
		(descr "Capacitor SMD 0402")
		(tags "capacitor SMD 0402")
		(property "Reference" "C6"
			(at -0.61 -0.52 90)
			(layer "F.SilkS")
			(effects
				(font
					(size 0.7 0.7)
					(thickness 0.15)
				)
				(justify left bottom)
			)
		)
		(property "Value" "C_100n_0402"
			(at -1.022927 2.155213 90)
			(layer "F.Fab")
			(effects
				(font
					(size 0.7 0.7)
					(thickness 0.15)
				)
				(justify left bottom)
			)
		)
		(property "Datasheet" "https://www.murata.com/products/productdetail?partno=GRM155R61H104KE14%23"
			(at 0 0 90)
			(layer "F.Fab")
			(hide yes)
			(effects
				(font
					(size 1.27 1.27)
					(thickness 0.15)
				)
			)
		)
		(property "MPN" "GRM155R61H104KE14D"
			(at 0 0 90)
			(unlocked yes)
			(layer "F.Fab")
			(hide yes)
			(effects
				(font
					(size 1 1)
					(thickness 0.15)
				)
			)
		)
		(property "Manufacturer" "Murata"
			(at 0 0 90)
			(unlocked yes)
			(layer "F.Fab")
			(hide yes)
			(effects
				(font
					(size 1 1)
					(thickness 0.15)
				)
			)
		)
		(property "License" "Apache-2.0"
			(at 0 0 90)
			(unlocked yes)
			(layer "F.Fab")
			(hide yes)
			(effects
				(font
					(size 1 1)
					(thickness 0.15)
				)
			)
		)
		(property "Author" "Antmicro"
			(at 0 0 90)
			(unlocked yes)
			(layer "F.Fab")
			(hide yes)
			(effects
				(font
					(size 1 1)
					(thickness 0.15)
				)
			)
		)
		(property "Val" "100n"
			(at 0 0 90)
			(unlocked yes)
			(layer "F.Fab")
			(hide yes)
			(effects
				(font
					(size 1 1)
					(thickness 0.15)
				)
			)
		)
		(property "Voltage" "50V"
			(at 0 0 90)
			(unlocked yes)
			(layer "F.Fab")
			(hide yes)
			(effects
				(font
					(size 1 1)
					(thickness 0.15)
				)
			)
		)
		(property "Dielectric" "X5R"
			(at 0 0 90)
			(unlocked yes)
			(layer "F.Fab")
			(hide yes)
			(effects
				(font
					(size 1 1)
					(thickness 0.15)
				)
			)
		)
		(sheetname "/DDR5 RDIMM/")
		(sheetfile "ddr5-rdimm.kicad_sch")
		(attr smd)
		(fp_rect
			(start -0.925 -0.47)
			(end 0.925 0.47)
			(stroke
				(width 0.05)
				(type default)
			)
			(fill no)
			(layer "F.CrtYd")
		)
		(fp_line
			(start 0.504 -0.25)
			(end 0.504 0.248)
			(stroke
				(width 0.15)
				(type solid)
			)
			(layer "F.Fab")
		)
		(fp_line
			(start -0.494 -0.25)
			(end 0.504 -0.25)
			(stroke
				(width 0.15)
				(type solid)
			)
			(layer "F.Fab")
		)
		(fp_line
			(start 0.504 0.248)
			(end -0.494 0.248)
			(stroke
				(width 0.15)
				(type solid)
			)
			(layer "F.Fab")
		)
		(fp_line
			(start -0.494 0.248)
			(end -0.494 -0.25)
			(stroke
				(width 0.15)
				(type solid)
			)
			(layer "F.Fab")
		)
		(fp_text user "Author: Antmicro"
			(at -0.939 3.399 90)
			(layer "F.Fab")
			(effects
				(font
					(size 0.7 0.7)
					(thickness 0.15)
				)
				(justify left bottom)
			)
		)
		(fp_text user "License: Apache-2.0"
			(at -0.939 5.799 90)
			(layer "F.Fab")
			(effects
				(font
					(size 0.7 0.7)
					(thickness 0.15)
				)
				(justify left bottom)
			)
		)
		(fp_text user "${REFERENCE}"
			(at -0.939 4.599 90)
			(layer "F.Fab")
			(effects
				(font
					(size 0.7 0.7)
					(thickness 0.15)
				)
				(justify left bottom)
			)
		)
		(pad "1" smd roundrect
			(at -0.48 0 90)
			(size 0.59 0.64)
			(layers "F.Cu" "F.Mask" "F.Paste")
			(roundrect_rratio 0.25)
			(net 1 "GND")
			(pintype "passive")
		)
		(pad "2" smd roundrect
			(at 0.48 0 90)
			(size 0.59 0.64)
			(layers "F.Cu" "F.Mask" "F.Paste")
			(roundrect_rratio 0.25)
			(net 802 "/DDR5 RDIMM/VIN_BULK")
			(pintype "passive")
		)
	)
	(footprint "antmicro-footprints:X1QFN-16-1EP_2.5x2.5mm"
		(layer "F.Cu")
		(at 138.423499 180.299)
		(property "Reference" "U9"
			(at 1.651 1.85 0)
			(unlocked yes)
			(layer "F.SilkS")
			(effects
				(font
					(size 0.7 0.7)
					(thickness 0.15)
				)
				(justify left bottom)
			)
		)
		(property "Value" "SN74HC595B"
			(at -6.9 2.69 0)
			(unlocked yes)
			(layer "F.Fab")
			(effects
				(font
					(size 0.7 0.7)
					(thickness 0.15)
				)
				(justify left bottom)
			)
		)
		(property "Datasheet" "https://www.ti.com/general/docs/suppproductinfo.tsp?distId=26&gotoUrl=https://www.ti.com/lit/gpn/sn74hc595b"
			(at 0 0 0)
			(layer "F.Fab")
			(hide yes)
			(effects
				(font
					(size 1.27 1.27)
					(thickness 0.15)
				)
			)
		)
		(property "MPN" "SN74HC595BRWNR"
			(at 0 0 0)
			(unlocked yes)
			(layer "F.Fab")
			(hide yes)
			(effects
				(font
					(size 1 1)
					(thickness 0.15)
				)
			)
		)
		(property "Manufacturer" "Texas Instruments"
			(at 0 0 0)
			(unlocked yes)
			(layer "F.Fab")
			(hide yes)
			(effects
				(font
					(size 1 1)
					(thickness 0.15)
				)
			)
		)
		(property "Author" "Antmicro"
			(at 0 0 0)
			(unlocked yes)
			(layer "F.Fab")
			(hide yes)
			(effects
				(font
					(size 1 1)
					(thickness 0.15)
				)
			)
		)
		(property "License" "Apache-2.0"
			(at 0 0 0)
			(unlocked yes)
			(layer "F.Fab")
			(hide yes)
			(effects
				(font
					(size 1 1)
					(thickness 0.15)
				)
			)
		)
		(sheetname "/Debug FTDI + VNA/")
		(sheetfile "debug-ftdi.kicad_sch")
		(attr smd)
		(fp_line
			(start -1.351 -1.351)
			(end -0.803 -1.351)
			(stroke
				(width 0.15)
				(type solid)
			)
			(layer "F.SilkS")
		)
		(fp_line
			(start -1.351 1.35)
			(end -1.351 0.8)
			(stroke
				(width 0.15)
				(type solid)
			)
			(layer "F.SilkS")
		)
		(fp_line
			(start -0.803 1.35)
			(end -1.351 1.35)
			(stroke
				(width 0.15)
				(type solid)
			)
			(layer "F.SilkS")
		)
		(fp_line
			(start 0.8 -1.351)
			(end 1.35 -1.351)
			(stroke
				(width 0.15)
				(type solid)
			)
			(layer "F.SilkS")
		)
		(fp_line
			(start 1.35 -1.351)
			(end 1.35 -0.803)
			(stroke
				(width 0.15)
				(type solid)
			)
			(layer "F.SilkS")
		)
		(fp_line
			(start 1.35 0.8)
			(end 1.35 1.35)
			(stroke
				(width 0.15)
				(type solid)
			)
			(layer "F.SilkS")
		)
		(fp_line
			(start 1.35 1.35)
			(end 0.8 1.35)
			(stroke
				(width 0.15)
				(type solid)
			)
			(layer "F.SilkS")
		)
		(fp_circle
			(center -1.752 -0.6)
			(end -1.702 -0.6)
			(stroke
				(width 0.15)
				(type solid)
			)
			(fill yes)
			(layer "F.SilkS")
		)
		(fp_rect
			(start -1.75 -1.75)
			(end 1.749 1.749)
			(stroke
				(width 0.05)
				(type solid)
			)
			(fill no)
			(layer "F.CrtYd")
		)
		(fp_line
			(start -1.25 -1.05)
			(end -1.05 -1.25)
			(stroke
				(width 0.15)
				(type solid)
			)
			(layer "F.Fab")
		)
		(fp_rect
			(start -1.25 -1.25)
			(end 1.249 1.249)
			(stroke
				(width 0.15)
				(type solid)
			)
			(fill no)
			(layer "F.Fab")
		)
		(fp_text user "${REFERENCE}"
			(at -6.9 5.89 0)
			(layer "F.Fab")
			(effects
				(font
					(size 0.7 0.7)
					(thickness 0.15)
				)
				(justify left bottom)
			)
		)
		(fp_text user "Author: Antmicro"
			(at -6.9 4.69 0)
			(layer "F.Fab")
			(effects
				(font
					(size 0.7 0.7)
					(thickness 0.15)
				)
				(justify left bottom)
			)
		)
		(fp_text user "License: Apache-2.0"
			(at -6.9 7.09 0)
			(layer "F.Fab")
			(effects
				(font
					(size 0.7 0.7)
					(thickness 0.15)
				)
				(justify left bottom)
			)
		)
		(pad "1" smd roundrect
			(at -1.151 -0.6)
			(size 0.6 0.2)
			(layers "F.Cu" "F.Mask" "F.Paste")
			(roundrect_rratio 0.25)
			(net 416 "unconnected-(U9-QB-Pad1)")
			(pinfunction "QB")
			(pintype "output+no_connect")
		)
		(pad "2" smd roundrect
			(at -1.151 -0.203)
			(size 0.6 0.2)
			(layers "F.Cu" "F.Mask" "F.Paste")
			(roundrect_rratio 0.25)
			(net 417 "unconnected-(U9-QC-Pad2)")
			(pinfunction "QC")
			(pintype "output+no_connect")
		)
		(pad "3" smd roundrect
			(at -1.151 0.2)
			(size 0.6 0.2)
			(layers "F.Cu" "F.Mask" "F.Paste")
			(roundrect_rratio 0.25)
			(net 418 "unconnected-(U9-QD-Pad3)")
			(pinfunction "QD")
			(pintype "output+no_connect")
		)
		(pad "4" smd roundrect
			(at -1.151 0.597)
			(size 0.6 0.2)
			(layers "F.Cu" "F.Mask" "F.Paste")
			(roundrect_rratio 0.25)
			(net 443 "/Debug FTDI + VNA/LED_TX0")
			(pinfunction "QE")
			(pintype "output")
		)
		(pad "5" smd roundrect
			(at -0.6 1.148 90)
			(size 0.6 0.2)
			(layers "F.Cu" "F.Mask" "F.Paste")
			(roundrect_rratio 0.25)
			(net 444 "/Debug FTDI + VNA/LED_RX0")
			(pinfunction "QF")
			(pintype "output")
		)
		(pad "6" smd roundrect
			(at -0.203 1.148 90)
			(size 0.6 0.2)
			(layers "F.Cu" "F.Mask" "F.Paste")
			(roundrect_rratio 0.25)
			(net 445 "/Debug FTDI + VNA/LED_TX1")
			(pinfunction "QG")
			(pintype "output")
		)
		(pad "7" smd roundrect
			(at 0.2 1.148 90)
			(size 0.6 0.2)
			(layers "F.Cu" "F.Mask" "F.Paste")
			(roundrect_rratio 0.25)
			(net 446 "/Debug FTDI + VNA/LED_RX1")
			(pinfunction "QH")
			(pintype "output")
		)
		(pad "8" smd roundrect
			(at 0.597 1.148 90)
			(size 0.6 0.2)
			(layers "F.Cu" "F.Mask" "F.Paste")
			(roundrect_rratio 0.25)
			(net 1 "GND")
			(pinfunction "GND")
			(pintype "power_in")
		)
		(pad "9" smd roundrect
			(at 1.148 0.597)
			(size 0.6 0.2)
			(layers "F.Cu" "F.Mask" "F.Paste")
			(roundrect_rratio 0.25)
			(net 419 "unconnected-(U9-QH'-Pad9)")
			(pinfunction "QH'")
			(pintype "output+no_connect")
		)
		(pad "10" smd roundrect
			(at 1.148 0.2)
			(size 0.6 0.2)
			(layers "F.Cu" "F.Mask" "F.Paste")
			(roundrect_rratio 0.25)
			(net 6 "/Debug FTDI + VNA/FTDI_3V3")
			(pinfunction "~{SRCLR}")
			(pintype "input")
		)
		(pad "11" smd roundrect
			(at 1.148 -0.203)
			(size 0.6 0.2)
			(layers "F.Cu" "F.Mask" "F.Paste")
			(roundrect_rratio 0.25)
			(net 794 "/Debug FTDI + VNA/FTDI_EECLK")
			(pinfunction "SRCLK")
			(pintype "input")
		)
		(pad "12" smd roundrect
			(at 1.148 -0.6)
			(size 0.6 0.2)
			(layers "F.Cu" "F.Mask" "F.Paste")
			(roundrect_rratio 0.25)
			(net 780 "/Debug FTDI + VNA/FTDI_EECS")
			(pinfunction "RCLK")
			(pintype "input")
		)
		(pad "13" smd roundrect
			(at 0.597 -1.151 90)
			(size 0.6 0.2)
			(layers "F.Cu" "F.Mask" "F.Paste")
			(roundrect_rratio 0.25)
			(net 372 "/Debug FTDI + VNA/FTDI_PWREN")
			(pinfunction "~{OE}")
			(pintype "input")
		)
		(pad "14" smd roundrect
			(at 0.2 -1.151 90)
			(size 0.6 0.2)
			(layers "F.Cu" "F.Mask" "F.Paste")
			(roundrect_rratio 0.25)
			(net 793 "/Debug FTDI + VNA/FTDI_EEDAT")
			(pinfunction "SER")
			(pintype "input")
		)
		(pad "15" smd roundrect
			(at -0.203 -1.151 90)
			(size 0.6 0.2)
			(layers "F.Cu" "F.Mask" "F.Paste")
			(roundrect_rratio 0.25)
			(net 420 "unconnected-(U9-QA-Pad15)")
			(pinfunction "QA")
			(pintype "output+no_connect")
		)
		(pad "16" smd roundrect
			(at -0.6 -1.151 90)
			(size 0.6 0.2)
			(layers "F.Cu" "F.Mask" "F.Paste")
			(roundrect_rratio 0.25)
			(net 6 "/Debug FTDI + VNA/FTDI_3V3")
			(pinfunction "VCC")
			(pintype "power_in")
		)
		(pad "17" smd roundrect
			(at 0 0 90)
			(size 1.2 1.2)
			(layers "F.Cu" "F.Mask" "F.Paste")
			(roundrect_rratio 0.04166666667)
			(net 421 "unconnected-(U9-EP-Pad17)")
			(pinfunction "EP")
			(pintype "no_connect")
		)
	)
	(footprint "antmicro-footprints:C_0805_2012Metric"
		(layer "F.Cu")
		(at 260.9555 155.371 90)
		(descr "Capacitor SMD 0805")
		(tags "capacitor SMD 0805")
		(property "Reference" "C178"
			(at -4.699 1.3445 90)
			(layer "F.SilkS")
			(effects
				(font
					(size 0.7 0.7)
					(thickness 0.15)
				)
				(justify left bottom)
			)
		)
		(property "Value" "C_22u_25V_0805"
			(at -2.055717 1.963152 90)
			(layer "F.Fab")
			(effects
				(font
					(size 0.7 0.7)
					(thickness 0.15)
				)
				(justify left bottom)
			)
		)
		(property "Datasheet" "https://product.samsungsem.com/mlcc/CL21A226MAYNNN.do"
			(at 0 0 90)
			(layer "F.Fab")
			(hide yes)
			(effects
				(font
					(size 1.27 1.27)
					(thickness 0.15)
				)
			)
		)
		(property "Manufacturer" "Samsung Electro-Mechanics"
			(at 0 0 90)
			(unlocked yes)
			(layer "F.Fab")
			(hide yes)
			(effects
				(font
					(size 1 1)
					(thickness 0.15)
				)
			)
		)
		(property "MPN" "CL21A226MAYNNNE"
			(at 0 0 90)
			(unlocked yes)
			(layer "F.Fab")
			(hide yes)
			(effects
				(font
					(size 1 1)
					(thickness 0.15)
				)
			)
		)
		(property "Val" "22u"
			(at 0 0 90)
			(unlocked yes)
			(layer "F.Fab")
			(hide yes)
			(effects
				(font
					(size 1 1)
					(thickness 0.15)
				)
			)
		)
		(property "License" "Apache-2.0"
			(at 0 0 90)
			(unlocked yes)
			(layer "F.Fab")
			(hide yes)
			(effects
				(font
					(size 1 1)
					(thickness 0.15)
				)
			)
		)
		(property "Author" "Antmicro"
			(at 0 0 90)
			(unlocked yes)
			(layer "F.Fab")
			(hide yes)
			(effects
				(font
					(size 1 1)
					(thickness 0.15)
				)
			)
		)
		(property "Voltage" "25V"
			(at 0 0 90)
			(unlocked yes)
			(layer "F.Fab")
			(hide yes)
			(effects
				(font
					(size 1 1)
					(thickness 0.15)
				)
			)
		)
		(property "Dielectric" "X5R"
			(at 0 0 90)
			(unlocked yes)
			(layer "F.Fab")
			(hide yes)
			(effects
				(font
					(size 1 1)
					(thickness 0.15)
				)
			)
		)
		(property "Public" "False"
			(at 0 0 90)
			(unlocked yes)
			(layer "F.Fab")
			(hide yes)
			(effects
				(font
					(size 1 1)
					(thickness 0.15)
				)
			)
		)
		(sheetname "/Supply/DC-DC IO/")
		(sheetfile "dc-dc-io.kicad_sch")
		(attr smd)
		(fp_line
			(start -0.3 -0.7)
			(end 0.3 -0.7)
			(stroke
				(width 0.15)
				(type solid)
			)
			(layer "F.SilkS")
		)
		(fp_line
			(start -0.3 0.7)
			(end 0.3 0.7)
			(stroke
				(width 0.15)
				(type solid)
			)
			(layer "F.SilkS")
		)
		(fp_rect
			(start 1.95 -0.9)
			(end -1.95 0.9)
			(stroke
				(width 0.05)
				(type default)
			)
			(fill no)
			(layer "F.CrtYd")
		)
		(fp_rect
			(start -0.95 -0.675)
			(end 0.95 0.675)
			(stroke
				(width 0.15)
				(type solid)
			)
			(fill no)
			(layer "F.Fab")
		)
		(fp_text user "${REFERENCE}"
			(at -1.9 3.947 90)
			(layer "F.Fab")
			(effects
				(font
					(size 0.7 0.7)
					(thickness 0.15)
				)
				(justify left bottom)
			)
		)
		(fp_text user "Author: Antmicro"
			(at -1.9 5.947 90)
			(layer "F.Fab")
			(effects
				(font
					(size 0.7 0.7)
					(thickness 0.15)
				)
				(justify left bottom)
			)
		)
		(fp_text user "License: Apache-2.0"
			(at -1.9 4.947 90)
			(layer "F.Fab")
			(effects
				(font
					(size 0.7 0.7)
					(thickness 0.15)
				)
				(justify left bottom)
			)
		)
		(pad "1" smd roundrect
			(at -1.1 0 90)
			(size 1.2 1.3)
			(layers "F.Cu" "F.Mask" "F.Paste")
			(roundrect_rratio 0.25)
			(net 1 "GND")
			(pintype "passive")
		)
		(pad "2" smd roundrect
			(at 1.1 0 90)
			(size 1.2 1.3)
			(layers "F.Cu" "F.Mask" "F.Paste")
			(roundrect_rratio 0.25)
			(net 35 "VDC")
			(pintype "passive")
		)
	)
	(footprint "antmicro-footprints:LED_0603_1608Metric_G"
		(layer "F.Cu")
		(at 137.424499 185.549 90)
		(descr "LED SMD 0603 Green")
		(tags "LED SMD 0603 Green")
		(property "Reference" "D11"
			(at -0.001 -0.901 90)
			(layer "F.SilkS")
			(hide yes)
			(effects
				(font
					(size 0.7 0.7)
					(thickness 0.15)
				)
				(justify left bottom)
			)
		)
		(property "Value" "LED_G_0603_KP-1608CGCK"
			(at -0.001 1.599 90)
			(layer "F.Fab")
			(effects
				(font
					(size 0.7 0.7)
					(thickness 0.15)
				)
				(justify left bottom)
			)
		)
		(property "Datasheet" "http://www.kingbright.com/attachments/file/psearch//000/00/00/KP-1608CGCK(Ver.23B).pdf"
			(at 0 0 90)
			(layer "F.Fab")
			(hide yes)
			(effects
				(font
					(size 1.27 1.27)
					(thickness 0.15)
				)
			)
		)
		(property "MPN" "KP-1608CGCK"
			(at 0 0 90)
			(unlocked yes)
			(layer "F.Fab")
			(hide yes)
			(effects
				(font
					(size 1 1)
					(thickness 0.15)
				)
			)
		)
		(property "Manufacturer" "Kingbright"
			(at 0 0 90)
			(unlocked yes)
			(layer "F.Fab")
			(hide yes)
			(effects
				(font
					(size 1 1)
					(thickness 0.15)
				)
			)
		)
		(property "Color" "Green"
			(at 0 0 90)
			(unlocked yes)
			(layer "F.Fab")
			(hide yes)
			(effects
				(font
					(size 1 1)
					(thickness 0.15)
				)
			)
		)
		(property "Author" "Antmicro"
			(at 0 0 90)
			(unlocked yes)
			(layer "F.Fab")
			(hide yes)
			(effects
				(font
					(size 1 1)
					(thickness 0.15)
				)
			)
		)
		(property "License" "Apache-2.0"
			(at 0 0 90)
			(unlocked yes)
			(layer "F.Fab")
			(hide yes)
			(effects
				(font
					(size 1 1)
					(thickness 0.15)
				)
			)
		)
		(sheetname "/Debug FTDI + VNA/")
		(sheetfile "debug-ftdi.kicad_sch")
		(attr smd)
		(fp_line
			(start 0.22 -0.35)
			(end -0.22 -0.35)
			(stroke
				(width 0.15)
				(type solid)
			)
			(layer "F.SilkS")
		)
		(fp_line
			(start -1.18 -0.319)
			(end -1.18 0.321)
			(stroke
				(width 0.15)
				(type solid)
			)
			(layer "F.SilkS")
		)
		(fp_line
			(start 0.105328 0.001008)
			(end 0.24 0.001)
			(stroke
				(width 0.1)
				(type solid)
			)
			(layer "F.SilkS")
		)
		(fp_line
			(start -0.094672 0.001008)
			(end 0.105328 -0.198992)
			(stroke
				(width 0.1)
				(type solid)
			)
			(layer "F.SilkS")
		)
		(fp_line
			(start -0.094672 0.001008)
			(end -0.24 0.001008)
			(stroke
				(width 0.1)
				(type solid)
			)
			(layer "F.SilkS")
		)
		(fp_line
			(start 0.105328 0.201008)
			(end 0.105328 -0.198992)
			(stroke
				(width 0.1)
				(type solid)
			)
			(layer "F.SilkS")
		)
		(fp_line
			(start 0.105328 0.201008)
			(end -0.094672 0.001008)
			(stroke
				(width 0.1)
				(type solid)
			)
			(layer "F.SilkS")
		)
		(fp_line
			(start -0.094672 0.201008)
			(end -0.094672 -0.198992)
			(stroke
				(width 0.1)
				(type solid)
			)
			(layer "F.SilkS")
		)
		(fp_line
			(start 0.22 0.35)
			(end -0.22 0.35)
			(stroke
				(width 0.15)
				(type solid)
			)
			(layer "F.SilkS")
		)
		(fp_rect
			(start 1.25 0.65)
			(end -1.25 -0.65)
			(stroke
				(width 0.05)
				(type solid)
			)
			(fill no)
			(layer "F.CrtYd")
		)
		(fp_line
			(start 0.201 -0.202)
			(end -0.101 0)
			(stroke
				(width 0.15)
				(type solid)
			)
			(layer "F.Fab")
		)
		(fp_line
			(start -0.199 -0.202)
			(end -0.199 0.1)
			(stroke
				(width 0.15)
				(type solid)
			)
			(layer "F.Fab")
		)
		(fp_line
			(start 0.599 0)
			(end 0.201 0)
			(stroke
				(width 0.15)
				(type solid)
			)
			(layer "F.Fab")
		)
		(fp_line
			(start 0.201 0)
			(end 0.201 -0.202)
			(stroke
				(width 0.15)
				(type solid)
			)
			(layer "F.Fab")
		)
		(fp_line
			(start -0.101 0)
			(end 0.201 0.2)
			(stroke
				(width 0.15)
				(type solid)
			)
			(layer "F.Fab")
		)
		(fp_line
			(start -0.199 0)
			(end -0.597 0)
			(stroke
				(width 0.15)
				(type solid)
			)
			(layer "F.Fab")
		)
		(fp_line
			(start 0.201 0.2)
			(end 0.201 0)
			(stroke
				(width 0.15)
				(type solid)
			)
			(layer "F.Fab")
		)
		(fp_line
			(start -0.199 0.2)
			(end -0.199 0.1)
			(stroke
				(width 0.15)
				(type solid)
			)
			(layer "F.Fab")
		)
		(fp_rect
			(start 0.848 0.4)
			(end -0.85 -0.402)
			(stroke
				(width 0.15)
				(type solid)
			)
			(fill no)
			(layer "F.Fab")
		)
		(fp_text user "Author: Antmicro"
			(at -1.4224 4.799 90)
			(layer "F.Fab")
			(effects
				(font
					(size 0.7 0.7)
					(thickness 0.15)
				)
				(justify left bottom)
			)
		)
		(fp_text user "License: Apache-2.0"
			(at -1.4224 3.599 90)
			(layer "F.Fab")
			(effects
				(font
					(size 0.7 0.7)
					(thickness 0.15)
				)
				(justify left bottom)
			)
		)
		(fp_text user "${REFERENCE}"
			(at -1.4224 5.999 90)
			(layer "F.Fab")
			(effects
				(font
					(size 0.7 0.7)
					(thickness 0.15)
				)
				(justify left bottom)
			)
		)
		(pad "1" smd roundrect
			(at -0.7 0 270)
			(size 0.8 1)
			(layers "F.Cu" "F.Mask" "F.Paste")
			(roundrect_rratio 0.2)
			(net 1 "GND")
			(pinfunction "C")
			(pintype "passive")
		)
		(pad "2" smd roundrect
			(at 0.7 0 270)
			(size 0.8 1)
			(layers "F.Cu" "F.Mask" "F.Paste")
			(roundrect_rratio 0.2)
			(net 41 "Net-(D11-A)")
			(pinfunction "A")
			(pintype "passive")
		)
	)
	(footprint "antmicro-footprints:TQFN-25_4x5mm"
		(layer "F.Cu")
		(at 229.945001 182.240001 -90)
		(property "Reference" "U36"
			(at 3.629999 4.315001 0)
			(unlocked yes)
			(layer "F.SilkS")
			(effects
				(font
					(size 0.7 0.7)
					(thickness 0.15)
				)
				(justify left bottom)
			)
		)
		(property "Value" "MP8796B"
			(at 12.501 7.605 270)
			(unlocked yes)
			(layer "F.Fab")
			(effects
				(font
					(size 0.7 0.7)
					(thickness 0.15)
				)
				(justify left bottom)
			)
		)
		(property "Datasheet" "https://www.monolithicpower.com/en/documentview/productdocument/index/version/2/document_type/Datasheet/lang/en/sku/MP8796B/"
			(at 0 0 270)
			(layer "F.Fab")
			(hide yes)
			(effects
				(font
					(size 1.27 1.27)
					(thickness 0.15)
				)
			)
		)
		(property "MPN" "MP8796BGVT-0000-Z"
			(at 0 0 270)
			(unlocked yes)
			(layer "F.Fab")
			(hide yes)
			(effects
				(font
					(size 1 1)
					(thickness 0.15)
				)
			)
		)
		(property "Manufacturer" "Monolithic Power Systems"
			(at 0 0 270)
			(unlocked yes)
			(layer "F.Fab")
			(hide yes)
			(effects
				(font
					(size 1 1)
					(thickness 0.15)
				)
			)
		)
		(property "Author" "Antmicro"
			(at 0 0 270)
			(unlocked yes)
			(layer "F.Fab")
			(hide yes)
			(effects
				(font
					(size 1 1)
					(thickness 0.15)
				)
			)
		)
		(property "License" "Apache-2.0"
			(at 0 0 270)
			(unlocked yes)
			(layer "F.Fab")
			(hide yes)
			(effects
				(font
					(size 1 1)
					(thickness 0.15)
				)
			)
		)
		(sheetname "/Supply/DC-DC VCCINT/")
		(sheetfile "dc-dc-vccint.kicad_sch")
		(attr smd)
		(fp_line
			(start -2.1 2.2)
			(end -2.1 1.7)
			(stroke
				(width 0.15)
				(type solid)
			)
			(layer "F.SilkS")
		)
		(fp_line
			(start 2.1 2.2)
			(end 2.1 1.7)
			(stroke
				(width 0.15)
				(type solid)
			)
			(layer "F.SilkS")
		)
		(fp_line
			(start -2.1 -1.7)
			(end -2.1 -2.2)
			(stroke
				(width 0.15)
				(type solid)
			)
			(layer "F.SilkS")
		)
		(fp_line
			(start 2.1 -2.2)
			(end 2.1 -1.7)
			(stroke
				(width 0.15)
				(type solid)
			)
			(layer "F.SilkS")
		)
		(fp_circle
			(center -2.34 -2.59)
			(end -2.29 -2.59)
			(stroke
				(width 0.15)
				(type solid)
			)
			(fill yes)
			(layer "F.SilkS")
		)
		(fp_rect
			(start -2.5 -2.75)
			(end 2.55 2.76)
			(stroke
				(width 0.05)
				(type solid)
			)
			(fill no)
			(layer "F.CrtYd")
		)
		(fp_text user "Author: Antmicro"
			(at -2.67 5.79 270)
			(layer "F.Fab")
			(effects
				(font
					(size 0.7 0.7)
					(thickness 0.15)
				)
				(justify left bottom)
			)
		)
		(fp_text user "License: Apache-2.0"
			(at -2.67 8.19 270)
			(layer "F.Fab")
			(effects
				(font
					(size 0.7 0.7)
					(thickness 0.15)
				)
				(justify left bottom)
			)
		)
		(fp_text user "${REFERENCE}"
			(at -2.67 6.99 270)
			(unlocked yes)
			(layer "F.Fab")
			(effects
				(font
					(size 0.7 0.7)
					(thickness 0.15)
				)
				(justify left bottom)
			)
		)
		(pad "1" smd roundrect
			(at -1.2 -1.195 90)
			(size 2.1 0.4)
			(layers "F.Cu" "F.Mask" "F.Paste")
			(roundrect_rratio 0.25)
			(net 35 "VDC")
			(pinfunction "IN")
			(pintype "power_in")
		)
		(pad "2" smd roundrect
			(at -1.2 -0.545 90)
			(size 2.1 0.4)
			(layers "F.Cu" "F.Mask" "F.Paste")
			(roundrect_rratio 0.25)
			(net 207 "Net-(C216-Pad2)")
			(pinfunction "SW")
			(pintype "passive")
		)
		(pad "3" smd roundrect
			(at -1.2 0.555 90)
			(size 2.1 0.4)
			(layers "F.Cu" "F.Mask" "F.Paste")
			(roundrect_rratio 0.25)
			(net 207 "Net-(C216-Pad2)")
			(pinfunction "SW")
			(pintype "passive")
		)
		(pad "4" smd roundrect
			(at -1.2 1.205 90)
			(size 2.1 0.4)
			(layers "F.Cu" "F.Mask" "F.Paste")
			(roundrect_rratio 0.25)
			(net 1 "GND")
			(pinfunction "P_{GND}")
			(pintype "passive")
		)
		(pad "5" smd roundrect
			(at -1.7 2.355)
			(size 0.9 0.3)
			(layers "F.Cu" "F.Mask" "F.Paste")
			(roundrect_rratio 0.25)
			(net 49 "Net-(U36-V_{DRV})")
			(pinfunction "V_{DRV}")
			(pintype "passive")
		)
		(pad "6" smd roundrect
			(at -1.2 2.355)
			(size 0.9 0.2)
			(layers "F.Cu" "F.Mask" "F.Paste")
			(roundrect_rratio 0.25)
			(net 749 "/I^{2}C + I3C/PWR.SCL")
			(pinfunction "SCL")
			(pintype "open_collector")
		)
		(pad "7" smd roundrect
			(at -0.8 2.355)
			(size 0.9 0.2)
			(layers "F.Cu" "F.Mask" "F.Paste")
			(roundrect_rratio 0.25)
			(net 533 "/I^{2}C + I3C/PWR.SDA")
			(pinfunction "SDA")
			(pintype "open_collector")
		)
		(pad "8" smd roundrect
			(at -0.4 2.355)
			(size 0.9 0.2)
			(layers "F.Cu" "F.Mask" "F.Paste")
			(roundrect_rratio 0.25)
			(net 748 "/Supply/DC-DC VCCINT/PWR.~{ALT}2")
			(pinfunction "~{ALT}")
			(pintype "open_collector")
		)
		(pad "9" smd roundrect
			(at 0 2.355)
			(size 0.9 0.2)
			(layers "F.Cu" "F.Mask" "F.Paste")
			(roundrect_rratio 0.25)
			(net 168 "/Supply/EN1")
			(pinfunction "CTRL")
			(pintype "input")
		)
		(pad "10" smd roundrect
			(at 0.4 2.355)
			(size 0.9 0.2)
			(layers "F.Cu" "F.Mask" "F.Paste")
			(roundrect_rratio 0.25)
			(net 482 "PG1")
			(pinfunction "PG")
			(pintype "open_collector")
		)
		(pad "11" smd roundrect
			(at 0.8 2.355)
			(size 0.9 0.2)
			(layers "F.Cu" "F.Mask" "F.Paste")
			(roundrect_rratio 0.25)
			(net 723 "/Supply/DC-DC VCCINT/PASS1")
			(pinfunction "PASS")
			(pintype "output")
		)
		(pad "12" smd roundrect
			(at 1.2 2.355)
			(size 0.9 0.2)
			(layers "F.Cu" "F.Mask" "F.Paste")
			(roundrect_rratio 0.25)
			(net 722 "/Supply/DC-DC VCCINT/TAKE1")
			(pinfunction "TAKE")
			(pintype "input")
		)
		(pad "13" smd roundrect
			(at 1.7 2.355)
			(size 0.9 0.3)
			(layers "F.Cu" "F.Mask" "F.Paste")
			(roundrect_rratio 0.25)
			(net 742 "/Supply/DC-DC VCCINT/SET")
			(pinfunction "SET")
			(pintype "bidirectional")
		)
		(pad "14" smd roundrect
			(at 1.2 1.205 90)
			(size 2.1 0.4)
			(layers "F.Cu" "F.Mask" "F.Paste")
			(roundrect_rratio 0.25)
			(net 1 "GND")
			(pinfunction "P_{GND}")
			(pintype "power_in")
		)
		(pad "15" smd roundrect
			(at 1.25 0.005 90)
			(size 2.1 0.4)
			(layers "F.Cu" "F.Mask" "F.Paste")
			(roundrect_rratio 0.25)
			(net 1 "GND")
			(pinfunction "P_{GND}")
			(pintype "passive")
		)
		(pad "16" smd roundrect
			(at 1.2 -1.195 90)
			(size 2.1 0.4)
			(layers "F.Cu" "F.Mask" "F.Paste")
			(roundrect_rratio 0.25)
			(net 35 "VDC")
			(pinfunction "IN")
			(pintype "passive")
		)
		(pad "17" smd roundrect
			(at 1.7 -2.345)
			(size 0.9 0.3)
			(layers "F.Cu" "F.Mask" "F.Paste")
			(roundrect_rratio 0.25)
			(net 777 "/Supply/DC-DC VCCINT/~{PS}")
			(pinfunction "~{PS}")
			(pintype "passive")
		)
		(pad "18" smd roundrect
			(at 1.2 -2.345)
			(size 0.9 0.2)
			(layers "F.Cu" "F.Mask" "F.Paste")
			(roundrect_rratio 0.25)
			(net 728 "Net-(U36-ADDR)")
			(pinfunction "ADDR")
			(pintype "passive")
		)
		(pad "19" smd roundrect
			(at 0.8 -2.345)
			(size 0.9 0.2)
			(layers "F.Cu" "F.Mask" "F.Paste")
			(roundrect_rratio 0.25)
			(net 743 "/Supply/DC-DC VCCINT/I_{SUM}")
			(pinfunction "I_{SUM}")
			(pintype "passive")
		)
		(pad "20" smd roundrect
			(at 0.4 -2.345)
			(size 0.9 0.2)
			(layers "F.Cu" "F.Mask" "F.Paste")
			(roundrect_rratio 0.25)
			(net 726 "Net-(U36-I_{REF})")
			(pinfunction "I_{REF}")
			(pintype "passive")
		)
		(pad "21" smd roundrect
			(at 0 -2.345)
			(size 0.9 0.2)
			(layers "F.Cu" "F.Mask" "F.Paste")
			(roundrect_rratio 0.25)
			(net 755 "/Supply/DC-DC VCCINT/VREF-")
			(pinfunction "V_{OSNS}-")
			(pintype "passive")
		)
		(pad "22" smd roundrect
			(at -0.4 -2.345)
			(size 0.9 0.2)
			(layers "F.Cu" "F.Mask" "F.Paste")
			(roundrect_rratio 0.25)
			(net 226 "/Supply/DC-DC VCCINT/V_{0SNS+}")
			(pinfunction "V_{OSNS}+")
			(pintype "passive")
		)
		(pad "23" smd roundrect
			(at -0.8 -2.345)
			(size 0.9 0.2)
			(layers "F.Cu" "F.Mask" "F.Paste")
			(roundrect_rratio 0.25)
			(net 1 "GND")
			(pinfunction "A_{GND}")
			(pintype "power_in")
		)
		(pad "24" smd roundrect
			(at -1.2 -2.345)
			(size 0.9 0.2)
			(layers "F.Cu" "F.Mask" "F.Paste")
			(roundrect_rratio 0.25)
			(net 163 "/Supply/DC-DC VCCINT/V_{CC}")
			(pinfunction "V_{CC}")
			(pintype "power_out")
		)
		(pad "25" smd roundrect
			(at -1.7 -2.345)
			(size 0.9 0.3)
			(layers "F.Cu" "F.Mask" "F.Paste")
			(roundrect_rratio 0.25)
			(net 167 "Net-(U36-BST)")
			(pinfunction "BST")
			(pintype "passive")
		)
	)
	(footprint "antmicro-footprints:C_0402_1005Metric"
		(layer "F.Cu")
		(at 113.026 171.5345 90)
		(descr "Capacitor SMD 0402")
		(tags "capacitor SMD 0402")
		(property "Reference" "C132"
			(at -2.6155 1.33 90)
			(layer "F.SilkS")
			(effects
				(font
					(size 0.7 0.7)
					(thickness 0.15)
				)
				(justify left bottom)
			)
		)
		(property "Value" "C_100n_0402"
			(at -1.022927 2.155213 90)
			(layer "F.Fab")
			(effects
				(font
					(size 0.7 0.7)
					(thickness 0.15)
				)
				(justify left bottom)
			)
		)
		(property "Datasheet" "https://www.murata.com/products/productdetail?partno=GRM155R61H104KE14%23"
			(at 0 0 90)
			(layer "F.Fab")
			(hide yes)
			(effects
				(font
					(size 1.27 1.27)
					(thickness 0.15)
				)
			)
		)
		(property "Manufacturer" "Murata"
			(at 0 0 90)
			(unlocked yes)
			(layer "F.Fab")
			(hide yes)
			(effects
				(font
					(size 1 1)
					(thickness 0.15)
				)
			)
		)
		(property "MPN" "GRM155R61H104KE14D"
			(at 0 0 90)
			(unlocked yes)
			(layer "F.Fab")
			(hide yes)
			(effects
				(font
					(size 1 1)
					(thickness 0.15)
				)
			)
		)
		(property "Val" "100n"
			(at 0 0 90)
			(unlocked yes)
			(layer "F.Fab")
			(hide yes)
			(effects
				(font
					(size 1 1)
					(thickness 0.15)
				)
			)
		)
		(property "License" "Apache-2.0"
			(at 0 0 90)
			(unlocked yes)
			(layer "F.Fab")
			(hide yes)
			(effects
				(font
					(size 1 1)
					(thickness 0.15)
				)
			)
		)
		(property "Author" "Antmicro"
			(at 0 0 90)
			(unlocked yes)
			(layer "F.Fab")
			(hide yes)
			(effects
				(font
					(size 1 1)
					(thickness 0.15)
				)
			)
		)
		(property "Voltage" "50V"
			(at 0 0 90)
			(unlocked yes)
			(layer "F.Fab")
			(hide yes)
			(effects
				(font
					(size 1 1)
					(thickness 0.15)
				)
			)
		)
		(property "Dielectric" "X5R"
			(at 0 0 90)
			(unlocked yes)
			(layer "F.Fab")
			(hide yes)
			(effects
				(font
					(size 1 1)
					(thickness 0.15)
				)
			)
		)
		(sheetname "/HDMI + SD Card/")
		(sheetfile "hdmi-sd-card.kicad_sch")
		(attr smd)
		(fp_rect
			(start -0.925 -0.47)
			(end 0.925 0.47)
			(stroke
				(width 0.05)
				(type default)
			)
			(fill no)
			(layer "F.CrtYd")
		)
		(fp_line
			(start 0.504 -0.25)
			(end 0.504 0.248)
			(stroke
				(width 0.15)
				(type solid)
			)
			(layer "F.Fab")
		)
		(fp_line
			(start -0.494 -0.25)
			(end 0.504 -0.25)
			(stroke
				(width 0.15)
				(type solid)
			)
			(layer "F.Fab")
		)
		(fp_line
			(start 0.504 0.248)
			(end -0.494 0.248)
			(stroke
				(width 0.15)
				(type solid)
			)
			(layer "F.Fab")
		)
		(fp_line
			(start -0.494 0.248)
			(end -0.494 -0.25)
			(stroke
				(width 0.15)
				(type solid)
			)
			(layer "F.Fab")
		)
		(fp_text user "License: Apache-2.0"
			(at -0.939 5.799 90)
			(layer "F.Fab")
			(effects
				(font
					(size 0.7 0.7)
					(thickness 0.15)
				)
				(justify left bottom)
			)
		)
		(fp_text user "${REFERENCE}"
			(at -0.939 4.599 90)
			(layer "F.Fab")
			(effects
				(font
					(size 0.7 0.7)
					(thickness 0.15)
				)
				(justify left bottom)
			)
		)
		(fp_text user "Author: Antmicro"
			(at -0.939 3.399 90)
			(layer "F.Fab")
			(effects
				(font
					(size 0.7 0.7)
					(thickness 0.15)
				)
				(justify left bottom)
			)
		)
		(pad "1" smd roundrect
			(at -0.48 0 90)
			(size 0.59 0.64)
			(layers "F.Cu" "F.Mask" "F.Paste")
			(roundrect_rratio 0.25)
			(net 188 "Net-(C132-Pad1)")
			(pintype "passive")
		)
		(pad "2" smd roundrect
			(at 0.48 0 90)
			(size 0.59 0.64)
			(layers "F.Cu" "F.Mask" "F.Paste")
			(roundrect_rratio 0.25)
			(net 1 "GND")
			(pintype "passive")
		)
	)
	(footprint "antmicro-footprints:R_0402_1005Metric"
		(layer "F.Cu")
		(at 141.024499 183.264 90)
		(descr "Resistor SMD 0402")
		(tags "resistor SMD 0402")
		(property "Reference" "R67"
			(at -1.061 2.375501 90)
			(layer "F.SilkS")
			(effects
				(font
					(size 0.7 0.7)
					(thickness 0.15)
				)
				(justify left bottom)
			)
		)
		(property "Value" "R_330R_0402"
			(at -1.011843 1.772047 90)
			(layer "F.Fab")
			(effects
				(font
					(size 0.7 0.7)
					(thickness 0.15)
				)
				(justify left bottom)
			)
		)
		(property "Datasheet" "https://www.bourns.com/docs/product-datasheets/cr.pdf"
			(at 0 0 90)
			(layer "F.Fab")
			(hide yes)
			(effects
				(font
					(size 1.27 1.27)
					(thickness 0.15)
				)
			)
		)
		(property "Manufacturer" "Bourns"
			(at 0 0 90)
			(unlocked yes)
			(layer "F.Fab")
			(hide yes)
			(effects
				(font
					(size 1 1)
					(thickness 0.15)
				)
			)
		)
		(property "MPN" "CR0402-FX-3300GLF"
			(at 0 0 90)
			(unlocked yes)
			(layer "F.Fab")
			(hide yes)
			(effects
				(font
					(size 1 1)
					(thickness 0.15)
				)
			)
		)
		(property "Val" "330R"
			(at 0 0 90)
			(unlocked yes)
			(layer "F.Fab")
			(hide yes)
			(effects
				(font
					(size 1 1)
					(thickness 0.15)
				)
			)
		)
		(property "License" "Apache-2.0"
			(at 0 0 90)
			(unlocked yes)
			(layer "F.Fab")
			(hide yes)
			(effects
				(font
					(size 1 1)
					(thickness 0.15)
				)
			)
		)
		(property "Author" "Antmicro"
			(at 0 0 90)
			(unlocked yes)
			(layer "F.Fab")
			(hide yes)
			(effects
				(font
					(size 1 1)
					(thickness 0.15)
				)
			)
		)
		(property "Tolerance" "1%"
			(at 0 0 90)
			(unlocked yes)
			(layer "F.Fab")
			(hide yes)
			(effects
				(font
					(size 1 1)
					(thickness 0.15)
				)
			)
		)
		(sheetname "/Debug FTDI + VNA/")
		(sheetfile "debug-ftdi.kicad_sch")
		(attr smd)
		(fp_rect
			(start -0.925 -0.47)
			(end 0.925 0.47)
			(stroke
				(width 0.05)
				(type default)
			)
			(fill no)
			(layer "F.CrtYd")
		)
		(fp_rect
			(start -0.5 -0.25)
			(end 0.5 0.25)
			(stroke
				(width 0.15)
				(type solid)
			)
			(fill no)
			(layer "F.Fab")
		)
		(fp_text user "Author: Antmicro"
			(at -0.95 4.169 90)
			(layer "F.Fab")
			(effects
				(font
					(size 0.7 0.7)
					(thickness 0.15)
				)
				(justify left bottom)
			)
		)
		(fp_text user "License: Apache-2.0"
			(at -0.95 5.169 90)
			(layer "F.Fab")
			(effects
				(font
					(size 0.7 0.7)
					(thickness 0.15)
				)
				(justify left bottom)
			)
		)
		(fp_text user "${REFERENCE}"
			(at -0.95 3.168 90)
			(layer "F.Fab")
			(effects
				(font
					(size 0.7 0.7)
					(thickness 0.15)
				)
				(justify left bottom)
			)
		)
		(pad "1" smd roundrect
			(at -0.48 0 90)
			(size 0.59 0.64)
			(layers "F.Cu" "F.Mask" "F.Paste")
			(roundrect_rratio 0.25)
			(net 43 "Net-(D13-A)")
			(pintype "passive")
		)
		(pad "2" smd roundrect
			(at 0.48 0 90)
			(size 0.59 0.64)
			(layers "F.Cu" "F.Mask" "F.Paste")
			(roundrect_rratio 0.25)
			(net 446 "/Debug FTDI + VNA/LED_RX1")
			(pintype "passive")
		)
	)
	(footprint "antmicro-footprints:LED_0402_1005Metric_G"
		(layer "F.Cu")
		(at 243.051 116.4)
		(property "Reference" "D21"
			(at 0 -0.6 0)
			(unlocked yes)
			(layer "F.SilkS")
			(hide yes)
			(effects
				(font
					(size 0.7 0.7)
					(thickness 0.15)
				)
				(justify left bottom)
			)
		)
		(property "Value" "LED_G_0402_VLMTG1500-GS08"
			(at 0 1.5 0)
			(unlocked yes)
			(layer "F.Fab")
			(effects
				(font
					(size 0.7 0.7)
					(thickness 0.15)
				)
				(justify left bottom)
			)
		)
		(property "Datasheet" "https://www.vishay.com/docs/82554/vlmo1500.pdf"
			(at 0 0 0)
			(layer "F.Fab")
			(hide yes)
			(effects
				(font
					(size 1.27 1.27)
					(thickness 0.15)
				)
			)
		)
		(property "MPN" "VLMTG1500-GS08"
			(at 0 0 0)
			(unlocked yes)
			(layer "F.Fab")
			(hide yes)
			(effects
				(font
					(size 1 1)
					(thickness 0.15)
				)
			)
		)
		(property "Manufacturer" "Vishay"
			(at 0 0 0)
			(unlocked yes)
			(layer "F.Fab")
			(hide yes)
			(effects
				(font
					(size 1 1)
					(thickness 0.15)
				)
			)
		)
		(property "Color" "Green"
			(at 0 0 0)
			(unlocked yes)
			(layer "F.Fab")
			(hide yes)
			(effects
				(font
					(size 1 1)
					(thickness 0.15)
				)
			)
		)
		(property "Author" "Antmicro"
			(at 0 0 0)
			(unlocked yes)
			(layer "F.Fab")
			(hide yes)
			(effects
				(font
					(size 1 1)
					(thickness 0.15)
				)
			)
		)
		(property "License" "Apache-2.0"
			(at 0 0 0)
			(unlocked yes)
			(layer "F.Fab")
			(hide yes)
			(effects
				(font
					(size 1 1)
					(thickness 0.15)
				)
			)
		)
		(sheetname "/DDR5 RDIMM/")
		(sheetfile "ddr5-rdimm.kicad_sch")
		(attr smd)
		(fp_line
			(start -0.9 -0.4)
			(end -0.9 0.4)
			(stroke
				(width 0.15)
				(type solid)
			)
			(layer "F.SilkS")
		)
		(fp_line
			(start -0.175 -0.4)
			(end 0.175 -0.4)
			(stroke
				(width 0.15)
				(type solid)
			)
			(layer "F.SilkS")
		)
		(fp_line
			(start -0.175 0.4)
			(end 0.175 0.4)
			(stroke
				(width 0.15)
				(type solid)
			)
			(layer "F.SilkS")
		)
		(fp_rect
			(start -0.925 -0.47)
			(end 0.925 0.47)
			(stroke
				(width 0.05)
				(type default)
			)
			(fill no)
			(layer "F.CrtYd")
		)
		(fp_line
			(start -0.489 -0.248)
			(end -0.489 0.26)
			(stroke
				(width 0.15)
				(type solid)
			)
			(layer "F.Fab")
		)
		(fp_line
			(start -0.489 -0.248)
			(end -0.489 0.26)
			(stroke
				(width 0.15)
				(type solid)
			)
			(layer "F.Fab")
		)
		(fp_line
			(start -0.489 0.26)
			(end -0.158 0.26)
			(stroke
				(width 0.15)
				(type solid)
			)
			(layer "F.Fab")
		)
		(fp_line
			(start -0.489 0.26)
			(end 0.501 0.26)
			(stroke
				(width 0.15)
				(type solid)
			)
			(layer "F.Fab")
		)
		(fp_line
			(start -0.173 -0.202)
			(end -0.173 0.102)
			(stroke
				(width 0.15)
				(type solid)
			)
			(layer "F.Fab")
		)
		(fp_line
			(start -0.173 0.202)
			(end -0.173 0.102)
			(stroke
				(width 0.15)
				(type solid)
			)
			(layer "F.Fab")
		)
		(fp_line
			(start -0.158 -0.248)
			(end -0.489 -0.248)
			(stroke
				(width 0.15)
				(type solid)
			)
			(layer "F.Fab")
		)
		(fp_line
			(start -0.158 0.26)
			(end -0.158 -0.248)
			(stroke
				(width 0.15)
				(type solid)
			)
			(layer "F.Fab")
		)
		(fp_line
			(start -0.074 0)
			(end 0.228 0.202)
			(stroke
				(width 0.15)
				(type solid)
			)
			(layer "F.Fab")
		)
		(fp_line
			(start 0.172 -0.248)
			(end 0.172 0.26)
			(stroke
				(width 0.15)
				(type solid)
			)
			(layer "F.Fab")
		)
		(fp_line
			(start 0.172 0.26)
			(end 0.501 0.26)
			(stroke
				(width 0.15)
				(type solid)
			)
			(layer "F.Fab")
		)
		(fp_line
			(start 0.228 -0.202)
			(end -0.074 0)
			(stroke
				(width 0.15)
				(type solid)
			)
			(layer "F.Fab")
		)
		(fp_line
			(start 0.228 0)
			(end 0.228 -0.202)
			(stroke
				(width 0.15)
				(type solid)
			)
			(layer "F.Fab")
		)
		(fp_line
			(start 0.228 0.202)
			(end 0.228 0)
			(stroke
				(width 0.15)
				(type solid)
			)
			(layer "F.Fab")
		)
		(fp_line
			(start 0.501 -0.248)
			(end -0.489 -0.248)
			(stroke
				(width 0.15)
				(type solid)
			)
			(layer "F.Fab")
		)
		(fp_line
			(start 0.501 -0.248)
			(end 0.172 -0.248)
			(stroke
				(width 0.15)
				(type solid)
			)
			(layer "F.Fab")
		)
		(fp_line
			(start 0.501 0.26)
			(end 0.501 -0.248)
			(stroke
				(width 0.15)
				(type solid)
			)
			(layer "F.Fab")
		)
		(fp_line
			(start 0.501 0.26)
			(end 0.501 -0.248)
			(stroke
				(width 0.15)
				(type solid)
			)
			(layer "F.Fab")
		)
		(fp_text user "${REFERENCE}"
			(at 0 2.95 0)
			(unlocked yes)
			(layer "F.Fab")
			(effects
				(font
					(size 0.7 0.7)
					(thickness 0.15)
				)
				(justify left bottom)
			)
		)
		(fp_text user "License: Apache-2.0"
			(at 0 5.35 0)
			(layer "F.Fab")
			(effects
				(font
					(size 0.7 0.7)
					(thickness 0.15)
				)
				(justify left bottom)
			)
		)
		(fp_text user "Author: Antmicro"
			(at 0 4.15 0)
			(layer "F.Fab")
			(effects
				(font
					(size 0.7 0.7)
					(thickness 0.15)
				)
				(justify left bottom)
			)
		)
		(pad "1" smd roundrect
			(at -0.48 0)
			(size 0.59 0.64)
			(layers "F.Cu" "F.Mask" "F.Paste")
			(roundrect_rratio 0.25)
			(net 804 "Net-(D21-C)")
			(pinfunction "C")
			(pintype "passive")
		)
		(pad "2" smd roundrect
			(at 0.48 0)
			(size 0.59 0.64)
			(layers "F.Cu" "F.Mask" "F.Paste")
			(roundrect_rratio 0.25)
			(net 802 "/DDR5 RDIMM/VIN_BULK")
			(pinfunction "A")
			(pintype "passive")
		)
	)
	(footprint "antmicro-footprints:R_0402_1005Metric"
		(layer "F.Cu")
		(at 260.52 176.1095 -90)
		(descr "Resistor SMD 0402")
		(tags "resistor SMD 0402")
		(property "Reference" "R165"
			(at 1.9905 -0.38 90)
			(layer "F.SilkS")
			(effects
				(font
					(size 0.7 0.7)
					(thickness 0.15)
				)
				(justify right bottom)
			)
		)
		(property "Value" "R_0R_0402"
			(at -1.011843 1.772047 90)
			(layer "F.Fab")
			(effects
				(font
					(size 0.7 0.7)
					(thickness 0.15)
				)
				(justify right bottom)
			)
		)
		(property "Datasheet" "https://industrial.panasonic.com/cdbs/www-data/pdf/RDA0000/AOA0000C301.pdf"
			(at 0 0 270)
			(layer "F.Fab")
			(hide yes)
			(effects
				(font
					(size 1.27 1.27)
					(thickness 0.15)
				)
			)
		)
		(property "Manufacturer" "Panasonic"
			(at 0 0 270)
			(unlocked yes)
			(layer "F.Fab")
			(hide yes)
			(effects
				(font
					(size 1 1)
					(thickness 0.15)
				)
			)
		)
		(property "MPN" "ERJ2GE0R00X"
			(at 0 0 270)
			(unlocked yes)
			(layer "F.Fab")
			(hide yes)
			(effects
				(font
					(size 1 1)
					(thickness 0.15)
				)
			)
		)
		(property "Val" "0R"
			(at 0 0 270)
			(unlocked yes)
			(layer "F.Fab")
			(hide yes)
			(effects
				(font
					(size 1 1)
					(thickness 0.15)
				)
			)
		)
		(property "License" "Apache-2.0"
			(at 0 0 270)
			(unlocked yes)
			(layer "F.Fab")
			(hide yes)
			(effects
				(font
					(size 1 1)
					(thickness 0.15)
				)
			)
		)
		(property "Author" "Antmicro"
			(at 0 0 270)
			(unlocked yes)
			(layer "F.Fab")
			(hide yes)
			(effects
				(font
					(size 1 1)
					(thickness 0.15)
				)
			)
		)
		(property "Tolerance" "~"
			(at 0 0 270)
			(unlocked yes)
			(layer "F.Fab")
			(hide yes)
			(effects
				(font
					(size 1 1)
					(thickness 0.15)
				)
			)
		)
		(property "Current" "1A"
			(at 0 0 270)
			(unlocked yes)
			(layer "F.Fab")
			(hide yes)
			(effects
				(font
					(size 1 1)
					(thickness 0.15)
				)
			)
		)
		(sheetname "/Supply/DC-DC AUX, MGT/")
		(sheetfile "dc-dc-aux-mgt.kicad_sch")
		(attr smd)
		(fp_rect
			(start -0.925 -0.47)
			(end 0.925 0.47)
			(stroke
				(width 0.05)
				(type default)
			)
			(fill no)
			(layer "F.CrtYd")
		)
		(fp_rect
			(start -0.5 -0.25)
			(end 0.5 0.25)
			(stroke
				(width 0.15)
				(type solid)
			)
			(fill no)
			(layer "F.Fab")
		)
		(fp_text user "${REFERENCE}"
			(at -0.95 3.168 270)
			(layer "F.Fab")
			(effects
				(font
					(size 0.7 0.7)
					(thickness 0.15)
				)
				(justify left bottom)
			)
		)
		(fp_text user "Author: Antmicro"
			(at -0.95 4.169 270)
			(layer "F.Fab")
			(effects
				(font
					(size 0.7 0.7)
					(thickness 0.15)
				)
				(justify left bottom)
			)
		)
		(fp_text user "License: Apache-2.0"
			(at -0.95 5.169 270)
			(layer "F.Fab")
			(effects
				(font
					(size 0.7 0.7)
					(thickness 0.15)
				)
				(justify left bottom)
			)
		)
		(pad "1" smd roundrect
			(at -0.48 0 270)
			(size 0.59 0.64)
			(layers "F.Cu" "F.Mask" "F.Paste")
			(roundrect_rratio 0.25)
			(net 717 "/Supply/DC-DC AUX, MGT/FB4")
			(pintype "passive")
		)
		(pad "2" smd roundrect
			(at 0.48 0 270)
			(size 0.59 0.64)
			(layers "F.Cu" "F.Mask" "F.Paste")
			(roundrect_rratio 0.25)
			(net 225 "/Supply/DC-DC AUX, MGT/MGTAVCCAUX_local")
			(pintype "passive")
		)
	)
	(footprint "antmicro-footprints:SOT-23-6"
		(layer "F.Cu")
		(at 254.139499 140.3 90)
		(property "Reference" "U31"
			(at -0.7 2.960501 90)
			(layer "F.SilkS")
			(effects
				(font
					(size 0.7 0.7)
					(thickness 0.15)
				)
				(justify left bottom)
			)
		)
		(property "Value" "LM3880"
			(at -1.75 2.75 90)
			(layer "F.Fab")
			(effects
				(font
					(size 0.7 0.7)
					(thickness 0.15)
				)
				(justify left bottom)
			)
		)
		(property "Datasheet" "http://www.ti.com/lit/ds/symlink/lm3880.pdf"
			(at 0 0 90)
			(layer "F.Fab")
			(hide yes)
			(effects
				(font
					(size 1.27 1.27)
					(thickness 0.15)
				)
			)
		)
		(property "Manufacturer" "Texas Instruments"
			(at 0 0 90)
			(unlocked yes)
			(layer "F.Fab")
			(hide yes)
			(effects
				(font
					(size 1 1)
					(thickness 0.15)
				)
			)
		)
		(property "MPN" "LM3880MFX-1AA/NOPB"
			(at 0 0 90)
			(unlocked yes)
			(layer "F.Fab")
			(hide yes)
			(effects
				(font
					(size 1 1)
					(thickness 0.15)
				)
			)
		)
		(property "Author" "Antmicro"
			(at 0 0 90)
			(unlocked yes)
			(layer "F.Fab")
			(hide yes)
			(effects
				(font
					(size 1 1)
					(thickness 0.15)
				)
			)
		)
		(property "License" "Apache-2.0"
			(at 0 0 90)
			(unlocked yes)
			(layer "F.Fab")
			(hide yes)
			(effects
				(font
					(size 1 1)
					(thickness 0.15)
				)
			)
		)
		(property ki_fp_filters "SOT?23*")
		(sheetname "/Supply/")
		(sheetfile "supply.kicad_sch")
		(attr smd)
		(fp_line
			(start 1.45 -0.757)
			(end 1.45 -0.457)
			(stroke
				(width 0.12)
				(type solid)
			)
			(layer "F.SilkS")
		)
		(fp_line
			(start 1.3 -0.757)
			(end 1.45 -0.757)
			(stroke
				(width 0.12)
				(type solid)
			)
			(layer "F.SilkS")
		)
		(fp_line
			(start -1.3 -0.757)
			(end -1.45 -0.757)
			(stroke
				(width 0.12)
				(type solid)
			)
			(layer "F.SilkS")
		)
		(fp_line
			(start -1.45 -0.757)
			(end -1.45 -0.457)
			(stroke
				(width 0.12)
				(type solid)
			)
			(layer "F.SilkS")
		)
		(fp_line
			(start 1.45 0.643)
			(end 1.45 0.343)
			(stroke
				(width 0.12)
				(type solid)
			)
			(layer "F.SilkS")
		)
		(fp_line
			(start 1.3 0.643)
			(end 1.45 0.643)
			(stroke
				(width 0.12)
				(type solid)
			)
			(layer "F.SilkS")
		)
		(fp_line
			(start -1.45 0.643)
			(end -1.45 0.343)
			(stroke
				(width 0.12)
				(type solid)
			)
			(layer "F.SilkS")
		)
		(fp_rect
			(start -1.55 -1.85)
			(end 1.55 1.75)
			(stroke
				(width 0.05)
				(type solid)
			)
			(fill no)
			(layer "F.CrtYd")
		)
		(fp_line
			(start 1.5 -0.757)
			(end 1.5 0.643)
			(stroke
				(width 0.1)
				(type solid)
			)
			(layer "F.Fab")
		)
		(fp_line
			(start -1.5 -0.757)
			(end 1.5 -0.757)
			(stroke
				(width 0.1)
				(type solid)
			)
			(layer "F.Fab")
		)
		(fp_line
			(start 1.5 0.643)
			(end -1.5 0.643)
			(stroke
				(width 0.1)
				(type solid)
			)
			(layer "F.Fab")
		)
		(fp_line
			(start -1.5 0.643)
			(end -1.5 -0.757)
			(stroke
				(width 0.1)
				(type solid)
			)
			(layer "F.Fab")
		)
		(fp_text user "."
			(at -1.4 1.2 90)
			(layer "F.SilkS")
			(effects
				(font
					(size 1 1)
					(thickness 0.15)
				)
			)
		)
		(fp_text user "${REFERENCE}"
			(at -1.75 4 90)
			(layer "F.Fab")
			(effects
				(font
					(size 0.7 0.7)
					(thickness 0.15)
				)
				(justify left bottom)
			)
		)
		(fp_text user "Author: Antmicro"
			(at -1.829 5.25 90)
			(layer "F.Fab")
			(effects
				(font
					(size 0.7 0.7)
					(thickness 0.15)
				)
				(justify left bottom)
			)
		)
		(fp_text user "License: Apache-2.0"
			(at -1.75 6.5 90)
			(layer "F.Fab")
			(effects
				(font
					(size 0.7 0.7)
					(thickness 0.15)
				)
				(justify left bottom)
			)
		)
		(pad "1" smd roundrect
			(at -0.954 1.1 90)
			(size 0.55 1)
			(layers "F.Cu" "F.Mask" "F.Paste")
			(roundrect_rratio 0.15)
			(net 38 "+3V3_AON")
			(pinfunction "VCC")
			(pintype "power_in")
		)
		(pad "2" smd roundrect
			(at -0.003 1.1 90)
			(size 0.55 1)
			(layers "F.Cu" "F.Mask" "F.Paste")
			(roundrect_rratio 0.15)
			(net 1 "GND")
			(pinfunction "GND")
			(pintype "power_in")
		)
		(pad "3" smd roundrect
			(at 0.947 1.1 90)
			(size 0.55 1)
			(layers "F.Cu" "F.Mask" "F.Paste")
			(roundrect_rratio 0.15)
			(net 625 "Net-(Q17-D)")
			(pinfunction "EN")
			(pintype "input")
		)
		(pad "4" smd roundrect
			(at 0.947 -1.214 90)
			(size 0.55 1)
			(layers "F.Cu" "F.Mask" "F.Paste")
			(roundrect_rratio 0.15)
			(net 170 "/Supply/EN3")
			(pinfunction "FLAG3")
			(pintype "open_collector")
		)
		(pad "5" smd roundrect
			(at -0.003 -1.214 90)
			(size 0.55 1)
			(layers "F.Cu" "F.Mask" "F.Paste")
			(roundrect_rratio 0.15)
			(net 169 "/Supply/EN2")
			(pinfunction "FLAG2")
			(pintype "open_collector")
		)
		(pad "6" smd roundrect
			(at -0.954 -1.214 90)
			(size 0.55 1)
			(layers "F.Cu" "F.Mask" "F.Paste")
			(roundrect_rratio 0.15)
			(net 168 "/Supply/EN1")
			(pinfunction "FLAG1")
			(pintype "open_collector")
		)
	)
	(footprint "antmicro-footprints:NetTie-2_SMD_Pad0.127mm"
		(layer "F.Cu")
		(at 257.447 165.62)
		(descr "Net tie, 2 pin, 0.127mm  SMD pads")
		(tags "net tie")
		(property "Reference" "NT3"
			(at -0.128 -1.345 0)
			(layer "F.SilkS")
			(hide yes)
			(effects
				(font
					(size 0.7 0.7)
					(thickness 0.15)
				)
				(justify left bottom)
			)
		)
		(property "Value" "Net-Tie_P0.127mm"
			(at 0 1.199 0)
			(layer "F.Fab")
			(effects
				(font
					(size 0.7 0.7)
					(thickness 0.15)
				)
				(justify left bottom)
			)
		)
		(property "MPN" ""
			(at 0 0 0)
			(unlocked yes)
			(layer "F.Fab")
			(hide yes)
			(effects
				(font
					(size 1 1)
					(thickness 0.15)
				)
			)
		)
		(property "Manufacturer" ""
			(at 0 0 0)
			(unlocked yes)
			(layer "F.Fab")
			(hide yes)
			(effects
				(font
					(size 1 1)
					(thickness 0.15)
				)
			)
		)
		(property "Author" "Antmicro"
			(at 0 0 0)
			(unlocked yes)
			(layer "F.Fab")
			(hide yes)
			(effects
				(font
					(size 1 1)
					(thickness 0.15)
				)
			)
		)
		(property "License" "Apache-2.0"
			(at 0 0 0)
			(unlocked yes)
			(layer "F.Fab")
			(hide yes)
			(effects
				(font
					(size 1 1)
					(thickness 0.15)
				)
			)
		)
		(property ki_fp_filters "Net*Tie*")
		(sheetname "/Supply/DC-DC AUX, MGT/")
		(sheetfile "dc-dc-aux-mgt.kicad_sch")
		(attr through_hole exclude_from_pos_files exclude_from_bom)
		(net_tie_pad_groups "1, 2")
		(fp_poly
			(pts
				(xy -0.0635 -0.0635) (xy 0.0625 -0.0635) (xy 0.0625 0.0635) (xy -0.0635 0.0635)
			)
			(stroke
				(width 0)
				(type solid)
			)
			(fill yes)
			(layer "F.Cu")
		)
		(fp_poly
			(pts
				(xy 0.2 -0.16) (xy 0.29 -0.07) (xy 0.29 0.07) (xy 0.2 0.16) (xy -0.2 0.16) (xy -0.29 0.07) (xy -0.29 -0.06)
				(xy -0.19 -0.16)
			)
			(stroke
				(width 0.05)
				(type solid)
			)
			(fill no)
			(layer "F.CrtYd")
		)
		(fp_text user "Author: Antmicro"
			(at -0.128 4.4 0)
			(layer "F.Fab")
			(effects
				(font
					(size 0.7 0.7)
					(thickness 0.15)
				)
				(justify left bottom)
			)
		)
		(fp_text user "${REFERENCE}"
			(at -0.128 3.2 0)
			(layer "F.Fab")
			(effects
				(font
					(size 0.7 0.7)
					(thickness 0.15)
				)
				(justify left bottom)
			)
		)
		(fp_text user "License: Apache-2.0"
			(at -0.128 5.6 0)
			(layer "F.Fab")
			(effects
				(font
					(size 0.7 0.7)
					(thickness 0.15)
				)
				(justify left bottom)
			)
		)
		(pad "1" smd roundrect
			(at -0.127 0 180)
			(size 0.127 0.127)
			(layers "F.Cu")
			(roundrect_rratio 0.5)
			(chamfer_ratio 0)
			(chamfer top_left bottom_left)
			(net 683 "/Supply/DC-DC AUX, MGT/MGTAVCC_SEN_+")
			(pinfunction "1")
			(pintype "passive")
		)
		(pad "2" smd roundrect
			(at 0.126 0)
			(size 0.127 0.127)
			(layers "F.Cu")
			(roundrect_rratio 0.5)
			(chamfer_ratio 0)
			(chamfer top_left bottom_left)
			(net 47 "/Supply/DC-DC AUX, MGT/MGTAVCC_local")
			(pinfunction "2")
			(pintype "passive")
		)
	)
	(footprint "antmicro-footprints:C_0402_1005Metric"
		(layer "F.Cu")
		(at 164.45 163.064999)
		(descr "Capacitor SMD 0402")
		(tags "capacitor SMD 0402")
		(property "Reference" "C308"
			(at 0.84 0.4 0)
			(layer "F.SilkS")
			(effects
				(font
					(size 0.7 0.7)
					(thickness 0.15)
				)
				(justify left bottom)
			)
		)
		(property "Value" "C_100n_0402"
			(at -1.022927 2.155213 0)
			(layer "F.Fab")
			(effects
				(font
					(size 0.7 0.7)
					(thickness 0.15)
				)
				(justify left bottom)
			)
		)
		(property "Datasheet" "https://www.murata.com/products/productdetail?partno=GRM155R61H104KE14%23"
			(at 0 0 0)
			(layer "F.Fab")
			(hide yes)
			(effects
				(font
					(size 1.27 1.27)
					(thickness 0.15)
				)
			)
		)
		(property "Manufacturer" "Murata"
			(at 0 0 0)
			(unlocked yes)
			(layer "F.Fab")
			(hide yes)
			(effects
				(font
					(size 1 1)
					(thickness 0.15)
				)
			)
		)
		(property "MPN" "GRM155R61H104KE14D"
			(at 0 0 0)
			(unlocked yes)
			(layer "F.Fab")
			(hide yes)
			(effects
				(font
					(size 1 1)
					(thickness 0.15)
				)
			)
		)
		(property "Val" "100n"
			(at 0 0 0)
			(unlocked yes)
			(layer "F.Fab")
			(hide yes)
			(effects
				(font
					(size 1 1)
					(thickness 0.15)
				)
			)
		)
		(property "License" "Apache-2.0"
			(at 0 0 0)
			(unlocked yes)
			(layer "F.Fab")
			(hide yes)
			(effects
				(font
					(size 1 1)
					(thickness 0.15)
				)
			)
		)
		(property "Author" "Antmicro"
			(at 0 0 0)
			(unlocked yes)
			(layer "F.Fab")
			(hide yes)
			(effects
				(font
					(size 1 1)
					(thickness 0.15)
				)
			)
		)
		(property "Voltage" "50V"
			(at 0 0 0)
			(unlocked yes)
			(layer "F.Fab")
			(hide yes)
			(effects
				(font
					(size 1 1)
					(thickness 0.15)
				)
			)
		)
		(property "Dielectric" "X5R"
			(at 0 0 0)
			(unlocked yes)
			(layer "F.Fab")
			(hide yes)
			(effects
				(font
					(size 1 1)
					(thickness 0.15)
				)
			)
		)
		(sheetname "/FPGA MGT Interface/")
		(sheetfile "fpga-mgt.kicad_sch")
		(attr smd)
		(fp_rect
			(start -0.925 -0.47)
			(end 0.925 0.47)
			(stroke
				(width 0.05)
				(type default)
			)
			(fill no)
			(layer "F.CrtYd")
		)
		(fp_line
			(start -0.494 -0.25)
			(end 0.504 -0.25)
			(stroke
				(width 0.15)
				(type solid)
			)
			(layer "F.Fab")
		)
		(fp_line
			(start -0.494 0.248)
			(end -0.494 -0.25)
			(stroke
				(width 0.15)
				(type solid)
			)
			(layer "F.Fab")
		)
		(fp_line
			(start 0.504 -0.25)
			(end 0.504 0.248)
			(stroke
				(width 0.15)
				(type solid)
			)
			(layer "F.Fab")
		)
		(fp_line
			(start 0.504 0.248)
			(end -0.494 0.248)
			(stroke
				(width 0.15)
				(type solid)
			)
			(layer "F.Fab")
		)
		(fp_text user "License: Apache-2.0"
			(at -0.939 5.799 0)
			(layer "F.Fab")
			(effects
				(font
					(size 0.7 0.7)
					(thickness 0.15)
				)
				(justify left bottom)
			)
		)
		(fp_text user "${REFERENCE}"
			(at -0.939 4.599 0)
			(layer "F.Fab")
			(effects
				(font
					(size 0.7 0.7)
					(thickness 0.15)
				)
				(justify left bottom)
			)
		)
		(fp_text user "Author: Antmicro"
			(at -0.939 3.399 0)
			(layer "F.Fab")
			(effects
				(font
					(size 0.7 0.7)
					(thickness 0.15)
				)
				(justify left bottom)
			)
		)
		(pad "1" smd roundrect
			(at -0.48 0)
			(size 0.59 0.64)
			(layers "F.Cu" "F.Mask" "F.Paste")
			(roundrect_rratio 0.25)
			(net 386 "/FPGA MGT Interface/HDMI_SI5319_C_CLK_N")
			(pintype "passive")
		)
		(pad "2" smd roundrect
			(at 0.48 0)
			(size 0.59 0.64)
			(layers "F.Cu" "F.Mask" "F.Paste")
			(roundrect_rratio 0.25)
			(net 387 "/FPGA MGT Interface/HDMI_SI5319_CLK_N")
			(pintype "passive")
		)
	)
	(footprint "antmicro-footprints:WSON-8_2x2mm"
		(layer "F.Cu")
		(at 207.29 154.19)
		(property "Reference" "U35"
			(at -2.99 -1.24 0)
			(unlocked yes)
			(layer "F.SilkS")
			(effects
				(font
					(size 0.7 0.7)
					(thickness 0.15)
				)
				(justify left bottom)
			)
		)
		(property "Value" "TMP451AIDQFR"
			(at 0 2.2 0)
			(unlocked yes)
			(layer "F.Fab")
			(effects
				(font
					(size 0.7 0.7)
					(thickness 0.15)
				)
				(justify left bottom)
			)
		)
		(property "Datasheet" "https://www.ti.com/lit/ds/symlink/tmp451.pdf?ts=1727409102766"
			(at 0 0 0)
			(layer "F.Fab")
			(hide yes)
			(effects
				(font
					(size 1.27 1.27)
					(thickness 0.15)
				)
			)
		)
		(property "MPN" "TMP451AIDQFR"
			(at 0 0 0)
			(unlocked yes)
			(layer "F.Fab")
			(hide yes)
			(effects
				(font
					(size 1 1)
					(thickness 0.15)
				)
			)
		)
		(property "Manufacturer" "Texas Instruments"
			(at 0 0 0)
			(unlocked yes)
			(layer "F.Fab")
			(hide yes)
			(effects
				(font
					(size 1 1)
					(thickness 0.15)
				)
			)
		)
		(property "Author" "Antmicro"
			(at 0 0 0)
			(unlocked yes)
			(layer "F.Fab")
			(hide yes)
			(effects
				(font
					(size 1 1)
					(thickness 0.15)
				)
			)
		)
		(property "License" "Apache-2.0"
			(at 0 0 0)
			(unlocked yes)
			(layer "F.Fab")
			(hide yes)
			(effects
				(font
					(size 1 1)
					(thickness 0.15)
				)
			)
		)
		(sheetname "/FPGA Config/")
		(sheetfile "fpga-config.kicad_sch")
		(attr smd)
		(fp_line
			(start -0.381 -1.13)
			(end 0.381 -1.13)
			(stroke
				(width 0.15)
				(type solid)
			)
			(layer "F.SilkS")
		)
		(fp_line
			(start -0.381 1.13)
			(end 0.381 1.13)
			(stroke
				(width 0.15)
				(type solid)
			)
			(layer "F.SilkS")
		)
		(fp_circle
			(center -1.2 -1.05)
			(end -1.15 -1.05)
			(stroke
				(width 0.15)
				(type solid)
			)
			(fill yes)
			(layer "F.SilkS")
		)
		(fp_rect
			(start -1.3 -1.1)
			(end 1.3 1.1)
			(stroke
				(width 0.05)
				(type solid)
			)
			(fill no)
			(layer "F.CrtYd")
		)
		(fp_line
			(start -1.003 -0.598)
			(end -1.003 1.003)
			(stroke
				(width 0.15)
				(type solid)
			)
			(layer "F.Fab")
		)
		(fp_line
			(start -1.003 -0.598)
			(end -0.635 -1.003)
			(stroke
				(width 0.15)
				(type solid)
			)
			(layer "F.Fab")
		)
		(fp_line
			(start -1.003 -0.402)
			(end -1.003 -0.098)
			(stroke
				(width 0.15)
				(type solid)
			)
			(layer "F.Fab")
		)
		(fp_line
			(start -1.003 -0.402)
			(end -1.003 -0.098)
			(stroke
				(width 0.15)
				(type solid)
			)
			(layer "F.Fab")
		)
		(fp_line
			(start -1.003 0.098)
			(end -1.003 0.402)
			(stroke
				(width 0.15)
				(type solid)
			)
			(layer "F.Fab")
		)
		(fp_line
			(start -1.003 0.098)
			(end -1.003 0.402)
			(stroke
				(width 0.15)
				(type solid)
			)
			(layer "F.Fab")
		)
		(fp_line
			(start -1.003 0.598)
			(end -1.003 0.902)
			(stroke
				(width 0.15)
				(type solid)
			)
			(layer "F.Fab")
		)
		(fp_line
			(start -1.003 0.598)
			(end -1.003 0.902)
			(stroke
				(width 0.15)
				(type solid)
			)
			(layer "F.Fab")
		)
		(fp_line
			(start -1.003 1.003)
			(end 1.003 1.003)
			(stroke
				(width 0.15)
				(type solid)
			)
			(layer "F.Fab")
		)
		(fp_line
			(start -0.635 -1.003)
			(end 1.003 -1.003)
			(stroke
				(width 0.15)
				(type solid)
			)
			(layer "F.Fab")
		)
		(fp_line
			(start 1.003 -1.003)
			(end 1.003 1.003)
			(stroke
				(width 0.15)
				(type solid)
			)
			(layer "F.Fab")
		)
		(fp_line
			(start 1.003 -0.902)
			(end 1.003 -0.598)
			(stroke
				(width 0.15)
				(type solid)
			)
			(layer "F.Fab")
		)
		(fp_line
			(start 1.003 -0.902)
			(end 1.003 -0.598)
			(stroke
				(width 0.15)
				(type solid)
			)
			(layer "F.Fab")
		)
		(fp_line
			(start 1.003 -0.402)
			(end 1.003 -0.098)
			(stroke
				(width 0.15)
				(type solid)
			)
			(layer "F.Fab")
		)
		(fp_line
			(start 1.003 -0.402)
			(end 1.003 -0.098)
			(stroke
				(width 0.15)
				(type solid)
			)
			(layer "F.Fab")
		)
		(fp_line
			(start 1.003 0.098)
			(end 1.003 0.402)
			(stroke
				(width 0.15)
				(type solid)
			)
			(layer "F.Fab")
		)
		(fp_line
			(start 1.003 0.098)
			(end 1.003 0.402)
			(stroke
				(width 0.15)
				(type solid)
			)
			(layer "F.Fab")
		)
		(fp_line
			(start 1.003 0.598)
			(end 1.003 0.902)
			(stroke
				(width 0.15)
				(type solid)
			)
			(layer "F.Fab")
		)
		(fp_line
			(start 1.003 0.598)
			(end 1.003 0.902)
			(stroke
				(width 0.15)
				(type solid)
			)
			(layer "F.Fab")
		)
		(fp_text user "Author: Antmicro"
			(at -1.3 6.6 0)
			(layer "F.Fab")
			(effects
				(font
					(size 0.7 0.7)
					(thickness 0.15)
				)
				(justify left bottom)
			)
		)
		(fp_text user "${REFERENCE}"
			(at -1.3 4.2 0)
			(layer "F.Fab")
			(effects
				(font
					(size 0.7 0.7)
					(thickness 0.15)
				)
				(justify left bottom)
			)
		)
		(fp_text user "License: Apache-2.0"
			(at -1.3 5.4 0)
			(layer "F.Fab")
			(effects
				(font
					(size 0.7 0.7)
					(thickness 0.15)
				)
				(justify left bottom)
			)
		)
		(pad "1" smd rect
			(at -0.8 -0.75 270)
			(size 0.25 0.8)
			(layers "F.Cu" "F.Mask" "F.Paste")
			(net 151 "+3V3")
			(pinfunction "V+")
			(pintype "power_in")
		)
		(pad "2" smd rect
			(at -0.85 -0.25 270)
			(size 0.25 0.7)
			(layers "F.Cu" "F.Mask" "F.Paste")
			(net 668 "/FPGA Config/DX_P")
			(pinfunction "D+")
			(pintype "input")
		)
		(pad "3" smd rect
			(at -0.85 0.25 270)
			(size 0.25 0.7)
			(layers "F.Cu" "F.Mask" "F.Paste")
			(net 667 "/FPGA Config/DX_N")
			(pinfunction "D-")
			(pintype "input")
		)
		(pad "4" smd rect
			(at -0.85 0.75 270)
			(size 0.25 0.7)
			(layers "F.Cu" "F.Mask" "F.Paste")
			(net 705 "/FPGA Config/~{THERM}")
			(pinfunction "~{THERM}")
			(pintype "output")
		)
		(pad "5" smd rect
			(at 0.85 0.75 270)
			(size 0.25 0.7)
			(layers "F.Cu" "F.Mask" "F.Paste")
			(net 1 "GND")
			(pinfunction "GND")
			(pintype "power_in")
		)
		(pad "6" smd rect
			(at 0.85 0.25 270)
			(size 0.25 0.7)
			(layers "F.Cu" "F.Mask" "F.Paste")
			(net 477 "/FPGA Config/~{ALARM}")
			(pinfunction "~{ALERT}")
			(pintype "output")
		)
		(pad "7" smd rect
			(at 0.85 -0.25 270)
			(size 0.25 0.7)
			(layers "F.Cu" "F.Mask" "F.Paste")
			(net 746 "/FPGA Config/FPGA_PWR.SDA")
			(pinfunction "SDA")
			(pintype "bidirectional")
		)
		(pad "8" smd rect
			(at 0.85 -0.75 270)
			(size 0.25 0.7)
			(layers "F.Cu" "F.Mask" "F.Paste")
			(net 747 "/FPGA Config/FPGA_PWR.SCL")
			(pinfunction "SCL")
			(pintype "input")
		)
	)
	(footprint "antmicro-footprints:LED_0402_1005Metric_G"
		(layer "F.Cu")
		(at 104.64 114.725 180)
		(property "Reference" "D2"
			(at 0 -0.6 180)
			(unlocked yes)
			(layer "F.SilkS")
			(hide yes)
			(effects
				(font
					(size 0.7 0.7)
					(thickness 0.15)
				)
				(justify left bottom)
			)
		)
		(property "Value" "LED_G_0402_VLMTG1500-GS08"
			(at 0 1.5 180)
			(unlocked yes)
			(layer "F.Fab")
			(effects
				(font
					(size 0.7 0.7)
					(thickness 0.15)
				)
				(justify left bottom)
			)
		)
		(property "Datasheet" "https://www.vishay.com/docs/82554/vlmo1500.pdf"
			(at 0 0 180)
			(layer "F.Fab")
			(hide yes)
			(effects
				(font
					(size 1.27 1.27)
					(thickness 0.15)
				)
			)
		)
		(property "MPN" "VLMTG1500-GS08"
			(at 0 0 180)
			(unlocked yes)
			(layer "F.Fab")
			(hide yes)
			(effects
				(font
					(size 1 1)
					(thickness 0.15)
				)
			)
		)
		(property "Manufacturer" "Vishay"
			(at 0 0 180)
			(unlocked yes)
			(layer "F.Fab")
			(hide yes)
			(effects
				(font
					(size 1 1)
					(thickness 0.15)
				)
			)
		)
		(property "Color" "Green"
			(at 0 0 180)
			(unlocked yes)
			(layer "F.Fab")
			(hide yes)
			(effects
				(font
					(size 1 1)
					(thickness 0.15)
				)
			)
		)
		(property "Author" "Antmicro"
			(at 0 0 180)
			(unlocked yes)
			(layer "F.Fab")
			(hide yes)
			(effects
				(font
					(size 1 1)
					(thickness 0.15)
				)
			)
		)
		(property "License" "Apache-2.0"
			(at 0 0 180)
			(unlocked yes)
			(layer "F.Fab")
			(hide yes)
			(effects
				(font
					(size 1 1)
					(thickness 0.15)
				)
			)
		)
		(sheetname "/FPGA Config/")
		(sheetfile "fpga-config.kicad_sch")
		(attr smd)
		(fp_line
			(start -0.175 0.4)
			(end 0.175 0.4)
			(stroke
				(width 0.15)
				(type solid)
			)
			(layer "F.SilkS")
		)
		(fp_line
			(start -0.175 -0.4)
			(end 0.175 -0.4)
			(stroke
				(width 0.15)
				(type solid)
			)
			(layer "F.SilkS")
		)
		(fp_line
			(start -0.9 -0.4)
			(end -0.9 0.4)
			(stroke
				(width 0.15)
				(type solid)
			)
			(layer "F.SilkS")
		)
		(fp_rect
			(start -0.925 -0.47)
			(end 0.925 0.47)
			(stroke
				(width 0.05)
				(type default)
			)
			(fill no)
			(layer "F.CrtYd")
		)
		(fp_line
			(start 0.501 0.26)
			(end 0.501 -0.248)
			(stroke
				(width 0.15)
				(type solid)
			)
			(layer "F.Fab")
		)
		(fp_line
			(start 0.501 0.26)
			(end 0.501 -0.248)
			(stroke
				(width 0.15)
				(type solid)
			)
			(layer "F.Fab")
		)
		(fp_line
			(start 0.501 -0.248)
			(end 0.172 -0.248)
			(stroke
				(width 0.15)
				(type solid)
			)
			(layer "F.Fab")
		)
		(fp_line
			(start 0.501 -0.248)
			(end -0.489 -0.248)
			(stroke
				(width 0.15)
				(type solid)
			)
			(layer "F.Fab")
		)
		(fp_line
			(start 0.228 0.202)
			(end 0.228 0)
			(stroke
				(width 0.15)
				(type solid)
			)
			(layer "F.Fab")
		)
		(fp_line
			(start 0.228 0)
			(end 0.228 -0.202)
			(stroke
				(width 0.15)
				(type solid)
			)
			(layer "F.Fab")
		)
		(fp_line
			(start 0.228 -0.202)
			(end -0.074 0)
			(stroke
				(width 0.15)
				(type solid)
			)
			(layer "F.Fab")
		)
		(fp_line
			(start 0.172 0.26)
			(end 0.501 0.26)
			(stroke
				(width 0.15)
				(type solid)
			)
			(layer "F.Fab")
		)
		(fp_line
			(start 0.172 -0.248)
			(end 0.172 0.26)
			(stroke
				(width 0.15)
				(type solid)
			)
			(layer "F.Fab")
		)
		(fp_line
			(start -0.074 0)
			(end 0.228 0.202)
			(stroke
				(width 0.15)
				(type solid)
			)
			(layer "F.Fab")
		)
		(fp_line
			(start -0.158 0.26)
			(end -0.158 -0.248)
			(stroke
				(width 0.15)
				(type solid)
			)
			(layer "F.Fab")
		)
		(fp_line
			(start -0.158 -0.248)
			(end -0.489 -0.248)
			(stroke
				(width 0.15)
				(type solid)
			)
			(layer "F.Fab")
		)
		(fp_line
			(start -0.173 0.202)
			(end -0.173 0.102)
			(stroke
				(width 0.15)
				(type solid)
			)
			(layer "F.Fab")
		)
		(fp_line
			(start -0.173 -0.202)
			(end -0.173 0.102)
			(stroke
				(width 0.15)
				(type solid)
			)
			(layer "F.Fab")
		)
		(fp_line
			(start -0.489 0.26)
			(end 0.501 0.26)
			(stroke
				(width 0.15)
				(type solid)
			)
			(layer "F.Fab")
		)
		(fp_line
			(start -0.489 0.26)
			(end -0.158 0.26)
			(stroke
				(width 0.15)
				(type solid)
			)
			(layer "F.Fab")
		)
		(fp_line
			(start -0.489 -0.248)
			(end -0.489 0.26)
			(stroke
				(width 0.15)
				(type solid)
			)
			(layer "F.Fab")
		)
		(fp_line
			(start -0.489 -0.248)
			(end -0.489 0.26)
			(stroke
				(width 0.15)
				(type solid)
			)
			(layer "F.Fab")
		)
		(fp_text user "License: Apache-2.0"
			(at 0 5.35 180)
			(layer "F.Fab")
			(effects
				(font
					(size 0.7 0.7)
					(thickness 0.15)
				)
				(justify left bottom)
			)
		)
		(fp_text user "Author: Antmicro"
			(at 0 4.15 180)
			(layer "F.Fab")
			(effects
				(font
					(size 0.7 0.7)
					(thickness 0.15)
				)
				(justify left bottom)
			)
		)
		(fp_text user "${REFERENCE}"
			(at 0 2.95 180)
			(unlocked yes)
			(layer "F.Fab")
			(effects
				(font
					(size 0.7 0.7)
					(thickness 0.15)
				)
				(justify left bottom)
			)
		)
		(pad "1" smd roundrect
			(at -0.48 0 180)
			(size 0.59 0.64)
			(layers "F.Cu" "F.Mask" "F.Paste")
			(roundrect_rratio 0.25)
			(net 784 "Net-(D2-C)")
			(pinfunction "C")
			(pintype "passive")
		)
		(pad "2" smd roundrect
			(at 0.48 0 180)
			(size 0.59 0.64)
			(layers "F.Cu" "F.Mask" "F.Paste")
			(roundrect_rratio 0.25)
			(net 151 "+3V3")
			(pinfunction "A")
			(pintype "passive")
		)
	)
	(footprint "antmicro-footprints:VSSOP-8_2.3x2mm_P0.5mm"
		(layer "F.Cu")
		(at 239.274499 182.749)
		(property "Reference" "U24"
			(at -1.15 2.1 0)
			(layer "F.SilkS")
			(effects
				(font
					(size 0.7 0.7)
					(thickness 0.15)
				)
				(justify left bottom)
			)
		)
		(property "Value" "TS5A3359_VSSOP"
			(at 0 2.258 0)
			(layer "F.Fab")
			(effects
				(font
					(size 0.7 0.7)
					(thickness 0.15)
				)
				(justify left bottom)
			)
		)
		(property "Datasheet" "https://www.ti.com/general/docs/suppproductinfo.tsp?distId=26&gotoUrl=http%3A%2F%2Fwww.ti.com%2Flit%2Fgpn%2Fts5a3359"
			(at 0 0 0)
			(layer "F.Fab")
			(hide yes)
			(effects
				(font
					(size 1.27 1.27)
					(thickness 0.15)
				)
			)
		)
		(property "MPN" "TS5A3359DCUR"
			(at 0 0 0)
			(unlocked yes)
			(layer "F.Fab")
			(hide yes)
			(effects
				(font
					(size 1 1)
					(thickness 0.15)
				)
			)
		)
		(property "Manufacturer" "Texas Instruments"
			(at 0 0 0)
			(unlocked yes)
			(layer "F.Fab")
			(hide yes)
			(effects
				(font
					(size 1 1)
					(thickness 0.15)
				)
			)
		)
		(property "Author" "Antmicro"
			(at 0 0 0)
			(unlocked yes)
			(layer "F.Fab")
			(hide yes)
			(effects
				(font
					(size 1 1)
					(thickness 0.15)
				)
			)
		)
		(property "License" "Apache-2.0"
			(at 0 0 0)
			(unlocked yes)
			(layer "F.Fab")
			(hide yes)
			(effects
				(font
					(size 1 1)
					(thickness 0.15)
				)
			)
		)
		(sheetname "/I^{2}C + I3C/")
		(sheetfile "i2c.kicad_sch")
		(attr smd)
		(fp_line
			(start -0.82 -0.992)
			(end 0.825 -0.992)
			(stroke
				(width 0.15)
				(type solid)
			)
			(layer "F.SilkS")
		)
		(fp_line
			(start 0.825 1.007)
			(end -0.82 1.007)
			(stroke
				(width 0.15)
				(type solid)
			)
			(layer "F.SilkS")
		)
		(fp_circle
			(center -1.402 -1.192)
			(end -1.352 -1.192)
			(stroke
				(width 0.15)
				(type solid)
			)
			(fill yes)
			(layer "F.SilkS")
		)
		(fp_rect
			(start 1.8 1.35)
			(end -1.8 -1.35)
			(stroke
				(width 0.05)
				(type solid)
			)
			(fill no)
			(layer "F.CrtYd")
		)
		(fp_line
			(start -0.7 -0.99)
			(end -1.14 -0.55)
			(stroke
				(width 0.15)
				(type solid)
			)
			(layer "F.Fab")
		)
		(fp_rect
			(start -1.147 -0.992)
			(end 1.151 1.007)
			(stroke
				(width 0.15)
				(type solid)
			)
			(fill no)
			(layer "F.Fab")
		)
		(fp_text user "${REFERENCE}"
			(at -1.8 4.006 0)
			(layer "F.Fab")
			(effects
				(font
					(size 0.7 0.7)
					(thickness 0.15)
				)
				(justify left bottom)
			)
		)
		(fp_text user "Author: Antmicro"
			(at -1.8 5.208 0)
			(layer "F.Fab")
			(effects
				(font
					(size 0.7 0.7)
					(thickness 0.15)
				)
				(justify left bottom)
			)
		)
		(fp_text user "License: Apache-2.0"
			(at -1.8 6.408 0)
			(layer "F.Fab")
			(effects
				(font
					(size 0.7 0.7)
					(thickness 0.15)
				)
				(justify left bottom)
			)
		)
		(pad "1" smd rect
			(at -1.372 -0.742)
			(size 0.75 0.4)
			(layers "F.Cu" "F.Mask" "F.Paste")
			(net 465 "/FPGA banks HD/FPGA_DDR.SCL")
			(pinfunction "NO1")
			(pintype "passive")
		)
		(pad "2" smd rect
			(at -1.372 -0.244)
			(size 0.75 0.3)
			(layers "F.Cu" "F.Mask" "F.Paste")
			(net 747 "/FPGA Config/FPGA_PWR.SCL")
			(pinfunction "NO2")
			(pintype "passive")
		)
		(pad "3" smd rect
			(at -1.372 0.256)
			(size 0.75 0.3)
			(layers "F.Cu" "F.Mask" "F.Paste")
			(net 526 "/Debug FTDI + VNA/FTDI.SCL")
			(pinfunction "NO3")
			(pintype "passive")
		)
		(pad "4" smd rect
			(at -1.372 0.757)
			(size 0.75 0.4)
			(layers "F.Cu" "F.Mask" "F.Paste")
			(net 1 "GND")
			(pinfunction "GND")
			(pintype "passive")
		)
		(pad "5" smd rect
			(at 1.377 0.757)
			(size 0.75 0.4)
			(layers "F.Cu" "F.Mask" "F.Paste")
			(net 405 "IN2")
			(pinfunction "IN2")
			(pintype "passive")
		)
		(pad "6" smd rect
			(at 1.377 0.256)
			(size 0.75 0.3)
			(layers "F.Cu" "F.Mask" "F.Paste")
			(net 404 "IN1")
			(pinfunction "IN1")
			(pintype "passive")
		)
		(pad "7" smd rect
			(at 1.377 -0.244)
			(size 0.75 0.3)
			(layers "F.Cu" "F.Mask" "F.Paste")
			(net 749 "/I^{2}C + I3C/PWR.SCL")
			(pinfunction "COM")
			(pintype "passive")
		)
		(pad "8" smd rect
			(at 1.377 -0.742)
			(size 0.75 0.4)
			(layers "F.Cu" "F.Mask" "F.Paste")
			(net 38 "+3V3_AON")
			(pinfunction "VCC")
			(pintype "passive")
		)
	)
	(footprint "antmicro-footprints:NetTie-2_SMD_Pad0.127mm"
		(layer "F.Cu")
		(at 245.663 150.451 180)
		(descr "Net tie, 2 pin, 0.127mm  SMD pads")
		(tags "net tie")
		(property "Reference" "NT14"
			(at -0.128 -1.345 0)
			(layer "F.SilkS")
			(hide yes)
			(effects
				(font
					(size 0.7 0.7)
					(thickness 0.15)
				)
				(justify right bottom)
			)
		)
		(property "Value" "Net-Tie_P0.127mm"
			(at 0 1.199 0)
			(layer "F.Fab")
			(effects
				(font
					(size 0.7 0.7)
					(thickness 0.15)
				)
				(justify right bottom)
			)
		)
		(property "MPN" ""
			(at 0 0 180)
			(unlocked yes)
			(layer "F.Fab")
			(hide yes)
			(effects
				(font
					(size 1 1)
					(thickness 0.15)
				)
			)
		)
		(property "Manufacturer" ""
			(at 0 0 180)
			(unlocked yes)
			(layer "F.Fab")
			(hide yes)
			(effects
				(font
					(size 1 1)
					(thickness 0.15)
				)
			)
		)
		(property "Author" "Antmicro"
			(at 0 0 180)
			(unlocked yes)
			(layer "F.Fab")
			(hide yes)
			(effects
				(font
					(size 1 1)
					(thickness 0.15)
				)
			)
		)
		(property "License" "Apache-2.0"
			(at 0 0 180)
			(unlocked yes)
			(layer "F.Fab")
			(hide yes)
			(effects
				(font
					(size 1 1)
					(thickness 0.15)
				)
			)
		)
		(property ki_fp_filters "Net*Tie*")
		(sheetname "/Supply/DC-DC IO/")
		(sheetfile "dc-dc-io.kicad_sch")
		(attr through_hole exclude_from_pos_files exclude_from_bom)
		(net_tie_pad_groups "1, 2")
		(fp_poly
			(pts
				(xy -0.0635 -0.0635) (xy 0.0625 -0.0635) (xy 0.0625 0.0635) (xy -0.0635 0.0635)
			)
			(stroke
				(width 0)
				(type solid)
			)
			(fill yes)
			(layer "F.Cu")
		)
		(fp_poly
			(pts
				(xy 0.2 -0.16) (xy 0.29 -0.07) (xy 0.29 0.07) (xy 0.2 0.16) (xy -0.2 0.16) (xy -0.29 0.07) (xy -0.29 -0.06)
				(xy -0.19 -0.16)
			)
			(stroke
				(width 0.05)
				(type solid)
			)
			(fill no)
			(layer "F.CrtYd")
		)
		(fp_text user "Author: Antmicro"
			(at -0.128 4.4 180)
			(layer "F.Fab")
			(effects
				(font
					(size 0.7 0.7)
					(thickness 0.15)
				)
				(justify left bottom)
			)
		)
		(fp_text user "License: Apache-2.0"
			(at -0.128 5.6 180)
			(layer "F.Fab")
			(effects
				(font
					(size 0.7 0.7)
					(thickness 0.15)
				)
				(justify left bottom)
			)
		)
		(fp_text user "${REFERENCE}"
			(at -0.128 3.2 180)
			(layer "F.Fab")
			(effects
				(font
					(size 0.7 0.7)
					(thickness 0.15)
				)
				(justify left bottom)
			)
		)
		(pad "1" smd roundrect
			(at -0.127 0)
			(size 0.127 0.127)
			(layers "F.Cu")
			(roundrect_rratio 0.5)
			(chamfer_ratio 0)
			(chamfer top_left bottom_left)
			(net 694 "/Supply/DC-DC IO/5V_SEN_-")
			(pinfunction "1")
			(pintype "passive")
		)
		(pad "2" smd roundrect
			(at 0.126 0 180)
			(size 0.127 0.127)
			(layers "F.Cu")
			(roundrect_rratio 0.5)
			(chamfer_ratio 0)
			(chamfer top_left bottom_left)
			(net 152 "+5V")
			(pinfunction "2")
			(pintype "passive")
		)
	)
	(footprint "antmicro-footprints:C_0402_1005Metric"
		(layer "F.Cu")
		(at 120.096 176.032 -90)
		(descr "Capacitor SMD 0402")
		(tags "capacitor SMD 0402")
		(property "Reference" "C284"
			(at -4.06 -0.41 90)
			(layer "F.SilkS")
			(effects
				(font
					(size 0.7 0.7)
					(thickness 0.15)
				)
				(justify right bottom)
			)
		)
		(property "Value" "C_10u_10V_0402"
			(at -1.022927 2.155213 90)
			(layer "F.Fab")
			(effects
				(font
					(size 0.7 0.7)
					(thickness 0.15)
				)
				(justify right bottom)
			)
		)
		(property "Datasheet" "https://www.murata.com/products/productdetail?partno=GRM155R61A106ME11%23"
			(at 0 0 270)
			(layer "F.Fab")
			(hide yes)
			(effects
				(font
					(size 1.27 1.27)
					(thickness 0.15)
				)
			)
		)
		(property "MPN" "GRM155R61A106ME11D"
			(at 0 0 270)
			(unlocked yes)
			(layer "F.Fab")
			(hide yes)
			(effects
				(font
					(size 1 1)
					(thickness 0.15)
				)
			)
		)
		(property "Manufacturer" "Murata"
			(at 0 0 270)
			(unlocked yes)
			(layer "F.Fab")
			(hide yes)
			(effects
				(font
					(size 1 1)
					(thickness 0.15)
				)
			)
		)
		(property "License" "Apache-2.0"
			(at 0 0 270)
			(unlocked yes)
			(layer "F.Fab")
			(hide yes)
			(effects
				(font
					(size 1 1)
					(thickness 0.15)
				)
			)
		)
		(property "Author" "Antmicro"
			(at 0 0 270)
			(unlocked yes)
			(layer "F.Fab")
			(hide yes)
			(effects
				(font
					(size 1 1)
					(thickness 0.15)
				)
			)
		)
		(property "Val" "10u"
			(at 0 0 270)
			(unlocked yes)
			(layer "F.Fab")
			(hide yes)
			(effects
				(font
					(size 1 1)
					(thickness 0.15)
				)
			)
		)
		(property "Voltage" "10V"
			(at 0 0 270)
			(unlocked yes)
			(layer "F.Fab")
			(hide yes)
			(effects
				(font
					(size 1 1)
					(thickness 0.15)
				)
			)
		)
		(property "Dielectric" "X5R"
			(at 0 0 270)
			(unlocked yes)
			(layer "F.Fab")
			(hide yes)
			(effects
				(font
					(size 1 1)
					(thickness 0.15)
				)
			)
		)
		(property "Public" ""
			(at 0 0 270)
			(unlocked yes)
			(layer "F.Fab")
			(hide yes)
			(effects
				(font
					(size 1 1)
					(thickness 0.15)
				)
			)
		)
		(sheetname "/HDMI + SD Card/")
		(sheetfile "hdmi-sd-card.kicad_sch")
		(attr smd)
		(fp_rect
			(start -0.925 -0.47)
			(end 0.925 0.47)
			(stroke
				(width 0.05)
				(type default)
			)
			(fill no)
			(layer "F.CrtYd")
		)
		(fp_line
			(start -0.494 0.248)
			(end -0.494 -0.25)
			(stroke
				(width 0.15)
				(type solid)
			)
			(layer "F.Fab")
		)
		(fp_line
			(start 0.504 0.248)
			(end -0.494 0.248)
			(stroke
				(width 0.15)
				(type solid)
			)
			(layer "F.Fab")
		)
		(fp_line
			(start -0.494 -0.25)
			(end 0.504 -0.25)
			(stroke
				(width 0.15)
				(type solid)
			)
			(layer "F.Fab")
		)
		(fp_line
			(start 0.504 -0.25)
			(end 0.504 0.248)
			(stroke
				(width 0.15)
				(type solid)
			)
			(layer "F.Fab")
		)
		(fp_text user "${REFERENCE}"
			(at -0.939 4.599 270)
			(layer "F.Fab")
			(effects
				(font
					(size 0.7 0.7)
					(thickness 0.15)
				)
				(justify left bottom)
			)
		)
		(fp_text user "Author: Antmicro"
			(at -0.939 3.399 270)
			(layer "F.Fab")
			(effects
				(font
					(size 0.7 0.7)
					(thickness 0.15)
				)
				(justify left bottom)
			)
		)
		(fp_text user "License: Apache-2.0"
			(at -0.939 5.799 270)
			(layer "F.Fab")
			(effects
				(font
					(size 0.7 0.7)
					(thickness 0.15)
				)
				(justify left bottom)
			)
		)
		(pad "1" smd roundrect
			(at -0.48 0 270)
			(size 0.59 0.64)
			(layers "F.Cu" "F.Mask" "F.Paste")
			(roundrect_rratio 0.25)
			(net 1 "GND")
			(pintype "passive")
		)
		(pad "2" smd roundrect
			(at 0.48 0 270)
			(size 0.59 0.64)
			(layers "F.Cu" "F.Mask" "F.Paste")
			(roundrect_rratio 0.25)
			(net 810 "/HDMI + SD Card/HDMI_VDD")
			(pintype "passive")
		)
	)
	(footprint "antmicro-footprints:X2SON8_1.4x1x0.32mm_P0.35mm"
		(layer "F.Cu")
		(at 147.934499 163.984)
		(property "Reference" "U16"
			(at -0.834499 1.791 90)
			(layer "F.SilkS")
			(effects
				(font
					(size 0.7 0.7)
					(thickness 0.15)
				)
				(justify left bottom)
			)
		)
		(property "Value" "TXS0102DQER"
			(at 0 1.929 0)
			(layer "F.Fab")
			(effects
				(font
					(size 0.7 0.7)
					(thickness 0.15)
				)
				(justify left bottom)
			)
		)
		(property "Datasheet" "https://www.ti.com/lit/ds/symlink/txs0102.pdf?ts=1637914596981&ref_url=https%253A%252F%252Fwww.ti.com%252Fstore%252Fti%252Fen%252Fp%252Fproduct%252F%253Fp%253DTXS0102DCTR%2526keyMatch%253DTXS0102DCTR%2526tisearch%253Dsearch-everything%2526usecase%253DOPN"
			(at 0 0 0)
			(layer "F.Fab")
			(hide yes)
			(effects
				(font
					(size 1.27 1.27)
					(thickness 0.15)
				)
			)
		)
		(property "MPN" "TXS0102DQER"
			(at 0 0 0)
			(unlocked yes)
			(layer "F.Fab")
			(hide yes)
			(effects
				(font
					(size 1 1)
					(thickness 0.15)
				)
			)
		)
		(property "Manufacturer" "Texas Instruments"
			(at 0 0 0)
			(unlocked yes)
			(layer "F.Fab")
			(hide yes)
			(effects
				(font
					(size 1 1)
					(thickness 0.15)
				)
			)
		)
		(property "Author" "Antmicro"
			(at 0 0 0)
			(unlocked yes)
			(layer "F.Fab")
			(hide yes)
			(effects
				(font
					(size 1 1)
					(thickness 0.15)
				)
			)
		)
		(property "License" "Apache-2.0"
			(at 0 0 0)
			(unlocked yes)
			(layer "F.Fab")
			(hide yes)
			(effects
				(font
					(size 1 1)
					(thickness 0.15)
				)
			)
		)
		(sheetname "/Debug FTDI + VNA/")
		(sheetfile "debug-ftdi.kicad_sch")
		(attr smd)
		(fp_line
			(start -0.6 -0.801)
			(end -0.6 -0.7)
			(stroke
				(width 0.15)
				(type solid)
			)
			(layer "F.SilkS")
		)
		(fp_line
			(start -0.6 0.7)
			(end -0.6 0.801)
			(stroke
				(width 0.15)
				(type solid)
			)
			(layer "F.SilkS")
		)
		(fp_line
			(start -0.6 0.801)
			(end -0.5 0.801)
			(stroke
				(width 0.15)
				(type solid)
			)
			(layer "F.SilkS")
		)
		(fp_line
			(start -0.402 -0.801)
			(end -0.6 -0.801)
			(stroke
				(width 0.15)
				(type solid)
			)
			(layer "F.SilkS")
		)
		(fp_line
			(start 0.598 -0.801)
			(end 0.498 -0.801)
			(stroke
				(width 0.15)
				(type solid)
			)
			(layer "F.SilkS")
		)
		(fp_line
			(start 0.598 -0.7)
			(end 0.598 -0.801)
			(stroke
				(width 0.15)
				(type solid)
			)
			(layer "F.SilkS")
		)
		(fp_line
			(start 0.598 0.7)
			(end 0.598 0.801)
			(stroke
				(width 0.15)
				(type solid)
			)
			(layer "F.SilkS")
		)
		(fp_line
			(start 0.598 0.801)
			(end 0.498 0.801)
			(stroke
				(width 0.15)
				(type solid)
			)
			(layer "F.SilkS")
		)
		(fp_circle
			(center -0.81 -0.77)
			(end -0.81 -0.72)
			(stroke
				(width 0.15)
				(type solid)
			)
			(fill yes)
			(layer "F.SilkS")
		)
		(fp_rect
			(start 0.75 -0.925)
			(end -0.75 0.925)
			(stroke
				(width 0.05)
				(type solid)
			)
			(fill no)
			(layer "F.CrtYd")
		)
		(fp_line
			(start -0.5 -0.729)
			(end -0.5 0.719)
			(stroke
				(width 0.15)
				(type solid)
			)
			(layer "F.Fab")
		)
		(fp_line
			(start -0.5 -0.724)
			(end 0.498 -0.724)
			(stroke
				(width 0.15)
				(type solid)
			)
			(layer "F.Fab")
		)
		(fp_line
			(start -0.5 0.724)
			(end 0.498 0.724)
			(stroke
				(width 0.15)
				(type solid)
			)
			(layer "F.Fab")
		)
		(fp_line
			(start 0.498 -0.719)
			(end 0.498 0.719)
			(stroke
				(width 0.15)
				(type solid)
			)
			(layer "F.Fab")
		)
		(fp_text user "${REFERENCE}"
			(at -0.95 3.929 0)
			(layer "F.Fab")
			(effects
				(font
					(size 0.7 0.7)
					(thickness 0.15)
				)
				(justify left bottom)
			)
		)
		(fp_text user "License: Apache-2.0"
			(at -0.95 6.329 0)
			(layer "F.Fab")
			(effects
				(font
					(size 0.7 0.7)
					(thickness 0.15)
				)
				(justify left bottom)
			)
		)
		(fp_text user "Author: Antmicro"
			(at -0.95 5.129 0)
			(layer "F.Fab")
			(effects
				(font
					(size 0.7 0.7)
					(thickness 0.15)
				)
				(justify left bottom)
			)
		)
		(pad "1" smd rect
			(at -0.43 -0.526 270)
			(size 0.17 0.5)
			(layers "F.Cu" "F.Mask" "F.Paste")
			(net 6 "/Debug FTDI + VNA/FTDI_3V3")
			(pinfunction "VCCA")
			(pintype "power_in")
		)
		(pad "2" smd rect
			(at -0.43 -0.175 270)
			(size 0.17 0.5)
			(layers "F.Cu" "F.Mask" "F.Paste")
			(net 790 "/Debug FTDI + VNA/FTDI_UART0_RX")
			(pinfunction "A1")
			(pintype "bidirectional")
		)
		(pad "3" smd rect
			(at -0.43 0.175 270)
			(size 0.17 0.5)
			(layers "F.Cu" "F.Mask" "F.Paste")
			(net 789 "/Debug FTDI + VNA/FTDI_UART0_TX")
			(pinfunction "A2")
			(pintype "bidirectional")
		)
		(pad "4" smd rect
			(at -0.43 0.526 270)
			(size 0.17 0.5)
			(layers "F.Cu" "F.Mask" "F.Paste")
			(net 1 "GND")
			(pinfunction "GND")
			(pintype "power_in")
		)
		(pad "5" smd rect
			(at 0.43 0.526 270)
			(size 0.17 0.5)
			(layers "F.Cu" "F.Mask" "F.Paste")
			(net 6 "/Debug FTDI + VNA/FTDI_3V3")
			(pinfunction "OE")
			(pintype "tri_state")
		)
		(pad "6" smd rect
			(at 0.43 0.175 270)
			(size 0.17 0.5)
			(layers "F.Cu" "F.Mask" "F.Paste")
			(net 375 "Net-(U16-B2)")
			(pinfunction "B2")
			(pintype "bidirectional")
		)
		(pad "7" smd rect
			(at 0.43 -0.175 270)
			(size 0.17 0.5)
			(layers "F.Cu" "F.Mask" "F.Paste")
			(net 373 "Net-(U16-B1)")
			(pinfunction "B1")
			(pintype "bidirectional")
		)
		(pad "8" smd rect
			(at 0.43 -0.526 270)
			(size 0.17 0.5)
			(layers "F.Cu" "F.Mask" "F.Paste")
			(net 151 "+3V3")
			(pinfunction "VCCB")
			(pintype "power_in")
		)
	)
	(footprint "antmicro-footprints:C_0603_1608Metric"
		(layer "F.Cu")
		(at 226.639999 170.104999)
		(descr "Capacitor SMD 0603")
		(tags "capacitor 0603")
		(property "Reference" "C267"
			(at -1.36 -2.155 0)
			(layer "F.SilkS")
			(effects
				(font
					(size 0.7 0.7)
					(thickness 0.15)
				)
				(justify left bottom)
			)
		)
		(property "Value" "C_22u_0603"
			(at -1.42757 1.770288 0)
			(layer "F.Fab")
			(effects
				(font
					(size 0.7 0.7)
					(thickness 0.15)
				)
				(justify left bottom)
			)
		)
		(property "Datasheet" "https://www.murata.com/products/productdetail?partno=GRM188R60J226MEA0%23"
			(at 0 0 0)
			(layer "F.Fab")
			(hide yes)
			(effects
				(font
					(size 1.27 1.27)
					(thickness 0.15)
				)
			)
		)
		(property "Manufacturer" "Murata"
			(at 0 0 0)
			(unlocked yes)
			(layer "F.Fab")
			(hide yes)
			(effects
				(font
					(size 1 1)
					(thickness 0.15)
				)
			)
		)
		(property "MPN" "GRM188R60J226MEA0D"
			(at 0 0 0)
			(unlocked yes)
			(layer "F.Fab")
			(hide yes)
			(effects
				(font
					(size 1 1)
					(thickness 0.15)
				)
			)
		)
		(property "Val" "22u"
			(at 0 0 0)
			(unlocked yes)
			(layer "F.Fab")
			(hide yes)
			(effects
				(font
					(size 1 1)
					(thickness 0.15)
				)
			)
		)
		(property "License" "Apache-2.0"
			(at 0 0 0)
			(unlocked yes)
			(layer "F.Fab")
			(hide yes)
			(effects
				(font
					(size 1 1)
					(thickness 0.15)
				)
			)
		)
		(property "Author" "Antmicro"
			(at 0 0 0)
			(unlocked yes)
			(layer "F.Fab")
			(hide yes)
			(effects
				(font
					(size 1 1)
					(thickness 0.15)
				)
			)
		)
		(property "Voltage" ""
			(at 0 0 0)
			(unlocked yes)
			(layer "F.Fab")
			(hide yes)
			(effects
				(font
					(size 1 1)
					(thickness 0.15)
				)
			)
		)
		(property "Dielectric" ""
			(at 0 0 0)
			(unlocked yes)
			(layer "F.Fab")
			(hide yes)
			(effects
				(font
					(size 1 1)
					(thickness 0.15)
				)
			)
		)
		(sheetname "/Supply/DC-DC VCCINT/")
		(sheetfile "dc-dc-vccint.kicad_sch")
		(attr smd)
		(fp_line
			(start -0.15 -0.4)
			(end 0.15 -0.4)
			(stroke
				(width 0.15)
				(type solid)
			)
			(layer "F.SilkS")
		)
		(fp_line
			(start -0.15 0.4)
			(end 0.15 0.4)
			(stroke
				(width 0.15)
				(type solid)
			)
			(layer "F.SilkS")
		)
		(fp_rect
			(start -1.25 -0.65)
			(end 1.25 0.65)
			(stroke
				(width 0.05)
				(type solid)
			)
			(fill no)
			(layer "F.CrtYd")
		)
		(fp_rect
			(start -0.8 -0.4)
			(end 0.8 0.4)
			(stroke
				(width 0.15)
				(type solid)
			)
			(fill no)
			(layer "F.Fab")
		)
		(fp_text user "${REFERENCE}"
			(at -1.682 3.895 0)
			(layer "F.Fab")
			(effects
				(font
					(size 0.7 0.7)
					(thickness 0.15)
				)
				(justify left bottom)
			)
		)
		(fp_text user "Author: Antmicro"
			(at -1.682 4.894 0)
			(layer "F.Fab")
			(effects
				(font
					(size 0.7 0.7)
					(thickness 0.15)
				)
				(justify left bottom)
			)
		)
		(fp_text user "License: Apache-2.0"
			(at -1.682 5.895 0)
			(layer "F.Fab")
			(effects
				(font
					(size 0.7 0.7)
					(thickness 0.15)
				)
				(justify left bottom)
			)
		)
		(pad "1" smd roundrect
			(at -0.7 0)
			(size 0.8 1)
			(layers "F.Cu" "F.Mask" "F.Paste")
			(roundrect_rratio 0.2)
			(net 1 "GND")
			(pintype "passive")
		)
		(pad "2" smd roundrect
			(at 0.7 0)
			(size 0.8 1)
			(layers "F.Cu" "F.Mask" "F.Paste")
			(roundrect_rratio 0.2)
			(net 224 "/Supply/DC-DC VCCINT/0V85_REG1")
			(pintype "passive")
		)
	)
	(footprint "antmicro-footprints:R_0402_1005Metric"
		(layer "F.Cu")
		(at 149.374499 173.249 -90)
		(descr "Resistor SMD 0402")
		(tags "resistor SMD 0402")
		(property "Reference" "R92"
			(at 0.921 -0.485501 90)
			(layer "F.SilkS")
			(effects
				(font
					(size 0.7 0.7)
					(thickness 0.15)
				)
				(justify right bottom)
			)
		)
		(property "Value" "R_0R_0402"
			(at -1.011843 1.772047 90)
			(layer "F.Fab")
			(effects
				(font
					(size 0.7 0.7)
					(thickness 0.15)
				)
				(justify right bottom)
			)
		)
		(property "Datasheet" "https://industrial.panasonic.com/cdbs/www-data/pdf/RDA0000/AOA0000C301.pdf"
			(at 0 0 270)
			(layer "F.Fab")
			(hide yes)
			(effects
				(font
					(size 1.27 1.27)
					(thickness 0.15)
				)
			)
		)
		(property "Manufacturer" "Panasonic"
			(at 0 0 270)
			(unlocked yes)
			(layer "F.Fab")
			(hide yes)
			(effects
				(font
					(size 1 1)
					(thickness 0.15)
				)
			)
		)
		(property "MPN" "ERJ2GE0R00X"
			(at 0 0 270)
			(unlocked yes)
			(layer "F.Fab")
			(hide yes)
			(effects
				(font
					(size 1 1)
					(thickness 0.15)
				)
			)
		)
		(property "Val" "0R"
			(at 0 0 270)
			(unlocked yes)
			(layer "F.Fab")
			(hide yes)
			(effects
				(font
					(size 1 1)
					(thickness 0.15)
				)
			)
		)
		(property "License" "Apache-2.0"
			(at 0 0 270)
			(unlocked yes)
			(layer "F.Fab")
			(hide yes)
			(effects
				(font
					(size 1 1)
					(thickness 0.15)
				)
			)
		)
		(property "Author" "Antmicro"
			(at 0 0 270)
			(unlocked yes)
			(layer "F.Fab")
			(hide yes)
			(effects
				(font
					(size 1 1)
					(thickness 0.15)
				)
			)
		)
		(property "Tolerance" "~"
			(at 0 0 270)
			(unlocked yes)
			(layer "F.Fab")
			(hide yes)
			(effects
				(font
					(size 1 1)
					(thickness 0.15)
				)
			)
		)
		(property "Current" "1A"
			(at 0 0 270)
			(unlocked yes)
			(layer "F.Fab")
			(hide yes)
			(effects
				(font
					(size 1 1)
					(thickness 0.15)
				)
			)
		)
		(sheetname "/Debug FTDI + VNA/")
		(sheetfile "debug-ftdi.kicad_sch")
		(attr smd)
		(fp_rect
			(start -0.925 -0.47)
			(end 0.925 0.47)
			(stroke
				(width 0.05)
				(type default)
			)
			(fill no)
			(layer "F.CrtYd")
		)
		(fp_rect
			(start -0.5 -0.25)
			(end 0.5 0.25)
			(stroke
				(width 0.15)
				(type solid)
			)
			(fill no)
			(layer "F.Fab")
		)
		(fp_text user "Author: Antmicro"
			(at -0.95 4.169 270)
			(layer "F.Fab")
			(effects
				(font
					(size 0.7 0.7)
					(thickness 0.15)
				)
				(justify left bottom)
			)
		)
		(fp_text user "License: Apache-2.0"
			(at -0.95 5.169 270)
			(layer "F.Fab")
			(effects
				(font
					(size 0.7 0.7)
					(thickness 0.15)
				)
				(justify left bottom)
			)
		)
		(fp_text user "${REFERENCE}"
			(at -0.95 3.168 270)
			(layer "F.Fab")
			(effects
				(font
					(size 0.7 0.7)
					(thickness 0.15)
				)
				(justify left bottom)
			)
		)
		(pad "1" smd roundrect
			(at -0.48 0 270)
			(size 0.59 0.64)
			(layers "F.Cu" "F.Mask" "F.Paste")
			(roundrect_rratio 0.25)
			(net 447 "/Debug FTDI + VNA/FTDI_SCL")
			(pintype "passive")
		)
		(pad "2" smd roundrect
			(at 0.48 0 270)
			(size 0.59 0.64)
			(layers "F.Cu" "F.Mask" "F.Paste")
			(roundrect_rratio 0.25)
			(net 526 "/Debug FTDI + VNA/FTDI.SCL")
			(pintype "passive")
		)
	)
	(footprint "antmicro-footprints:Conn_JST_SH_1x4_BM04B-SRSS-TB-LF-SN"
		(layer "F.Cu")
		(at 227.15 160.341001 180)
		(property "Reference" "J8"
			(at 1.9 2.65 0)
			(layer "F.SilkS")
			(effects
				(font
					(size 0.7 0.7)
					(thickness 0.15)
				)
				(justify right top)
			)
		)
		(property "Value" "JST_SH_1x4_BM04B-SRSS-TB-LF-SN"
			(at 0 3.1 0)
			(layer "F.Fab")
			(effects
				(font
					(size 0.7 0.7)
					(thickness 0.15)
				)
				(justify right top)
			)
		)
		(property "Datasheet" "https://www.jst-mfg.com/product/pdf/eng/eSH.pdf"
			(at 0 0 0)
			(layer "F.Fab")
			(hide yes)
			(effects
				(font
					(size 1.27 1.27)
					(thickness 0.15)
				)
			)
		)
		(property "MPN" "BM04B-SRSS-TB(LF)(SN) "
			(at 0 0 180)
			(unlocked yes)
			(layer "F.Fab")
			(hide yes)
			(effects
				(font
					(size 1 1)
					(thickness 0.15)
				)
			)
		)
		(property "Manufacturer" "JST Automotive Connectors"
			(at 0 0 180)
			(unlocked yes)
			(layer "F.Fab")
			(hide yes)
			(effects
				(font
					(size 1 1)
					(thickness 0.15)
				)
			)
		)
		(property "Author" "Antmicro"
			(at 0 0 180)
			(unlocked yes)
			(layer "F.Fab")
			(hide yes)
			(effects
				(font
					(size 1 1)
					(thickness 0.15)
				)
			)
		)
		(property "License" "Apache-2.0"
			(at 0 0 180)
			(unlocked yes)
			(layer "F.Fab")
			(hide yes)
			(effects
				(font
					(size 1 1)
					(thickness 0.15)
				)
			)
		)
		(sheetname "/Supply/")
		(sheetfile "supply.kicad_sch")
		(attr smd)
		(fp_line
			(start 1.774 -1.7)
			(end 1.774 1.702)
			(stroke
				(width 0.15)
				(type solid)
			)
			(layer "F.SilkS")
		)
		(fp_line
			(start -0.251 2.999)
			(end -1.125 2.999)
			(stroke
				(width 0.15)
				(type solid)
			)
			(layer "F.SilkS")
		)
		(fp_line
			(start -0.251 -2.999)
			(end -1.125 -2.999)
			(stroke
				(width 0.15)
				(type solid)
			)
			(layer "F.SilkS")
		)
		(fp_line
			(start -1.125 2.999)
			(end -1.125 2.201)
			(stroke
				(width 0.15)
				(type solid)
			)
			(layer "F.SilkS")
		)
		(fp_line
			(start -1.125 -2.999)
			(end -1.125 -2.201)
			(stroke
				(width 0.15)
				(type solid)
			)
			(layer "F.SilkS")
		)
		(fp_circle
			(center -1.6 -2.1)
			(end -1.55 -2.1)
			(stroke
				(width 0.15)
				(type solid)
			)
			(fill yes)
			(layer "F.SilkS")
		)
		(fp_rect
			(start -2.05 -3.95)
			(end 2.05 3.95)
			(stroke
				(width 0.05)
				(type solid)
			)
			(fill no)
			(layer "F.CrtYd")
		)
		(fp_rect
			(start -1.8 -3)
			(end 1.8 3)
			(stroke
				(width 0.15)
				(type solid)
			)
			(fill no)
			(layer "F.Fab")
		)
		(fp_text user "${REFERENCE}"
			(at -3.25 8.2 180)
			(layer "F.Fab")
			(effects
				(font
					(size 0.7 0.7)
					(thickness 0.15)
				)
				(justify left bottom)
			)
		)
		(fp_text user "License: Apache-2.0"
			(at -3.25 9.4 180)
			(layer "F.Fab")
			(effects
				(font
					(size 0.7 0.7)
					(thickness 0.15)
				)
				(justify left bottom)
			)
		)
		(fp_text user "Author: Antmicro"
			(at -3.25 7 180)
			(layer "F.Fab")
			(effects
				(font
					(size 0.7 0.7)
					(thickness 0.15)
				)
				(justify left bottom)
			)
		)
		(pad "1" smd roundrect
			(at -1.45 -1.5 90)
			(size 0.6 1.55)
			(layers "F.Cu" "F.Mask" "F.Paste")
			(roundrect_rratio 0.25)
			(net 1 "GND")
			(pintype "passive")
		)
		(pad "2" smd roundrect
			(at -1.45 -0.5 90)
			(size 0.6 1.55)
			(layers "F.Cu" "F.Mask" "F.Paste")
			(roundrect_rratio 0.25)
			(net 152 "+5V")
			(pintype "passive")
		)
		(pad "3" smd roundrect
			(at -1.45 0.5 90)
			(size 0.6 1.55)
			(layers "F.Cu" "F.Mask" "F.Paste")
			(roundrect_rratio 0.25)
			(net 251 "unconnected-(J8-Pad3)")
			(pintype "passive+no_connect")
		)
		(pad "4" smd roundrect
			(at -1.45 1.5 90)
			(size 0.6 1.55)
			(layers "F.Cu" "F.Mask" "F.Paste")
			(roundrect_rratio 0.25)
			(net 250 "Net-(Q15-D)")
			(pintype "passive")
		)
		(pad "MP" smd roundrect
			(at 1.075 -2.8 90)
			(size 1.2 1.8)
			(layers "F.Cu" "F.Mask" "F.Paste")
			(roundrect_rratio 0.25)
			(net 1 "GND")
			(pintype "passive")
		)
		(pad "MP" smd roundrect
			(at 1.075 2.8 90)
			(size 1.2 1.8)
			(layers "F.Cu" "F.Mask" "F.Paste")
			(roundrect_rratio 0.25)
			(net 1 "GND")
			(pintype "passive")
		)
	)
	(footprint "antmicro-footprints:SOD-523"
		(layer "F.Cu")
		(at 257.8 138.825 90)
		(property "Reference" "D9"
			(at 0 -0.75 90)
			(layer "F.SilkS")
			(effects
				(font
					(size 0.7 0.7)
					(thickness 0.15)
				)
				(justify left bottom)
			)
		)
		(property "Value" "PESD5V0X1UB"
			(at 0 1.499 90)
			(layer "F.Fab")
			(effects
				(font
					(size 0.7 0.7)
					(thickness 0.15)
				)
				(justify left bottom)
			)
		)
		(property "Datasheet" "https://assets.nexperia.com/documents/data-sheet/PESD5V0X1UB.pdf"
			(at 0 0 90)
			(layer "F.Fab")
			(hide yes)
			(effects
				(font
					(size 1.27 1.27)
					(thickness 0.15)
				)
			)
		)
		(property "MPN" "PESD5V0X1UB,135"
			(at 0 0 90)
			(unlocked yes)
			(layer "F.Fab")
			(hide yes)
			(effects
				(font
					(size 1 1)
					(thickness 0.15)
				)
			)
		)
		(property "Manufacturer" "Nexperia"
			(at 0 0 90)
			(unlocked yes)
			(layer "F.Fab")
			(hide yes)
			(effects
				(font
					(size 1 1)
					(thickness 0.15)
				)
			)
		)
		(property "Author" "Antmicro"
			(at 0 0 90)
			(unlocked yes)
			(layer "F.Fab")
			(hide yes)
			(effects
				(font
					(size 1 1)
					(thickness 0.15)
				)
			)
		)
		(property "License" "Apache-2.0"
			(at 0 0 90)
			(unlocked yes)
			(layer "F.Fab")
			(hide yes)
			(effects
				(font
					(size 1 1)
					(thickness 0.15)
				)
			)
		)
		(sheetname "/FPGA Config/")
		(sheetfile "fpga-config.kicad_sch")
		(attr smd)
		(fp_line
			(start -0.35 -0.5)
			(end -0.35 0.5)
			(stroke
				(width 0.15)
				(type solid)
			)
			(layer "F.SilkS")
		)
		(fp_rect
			(start -1 -0.6)
			(end 1 0.6)
			(stroke
				(width 0.05)
				(type solid)
			)
			(fill no)
			(layer "F.CrtYd")
		)
		(fp_line
			(start 0.65 -0.425)
			(end 0.65 0.423)
			(stroke
				(width 0.15)
				(type solid)
			)
			(layer "F.Fab")
		)
		(fp_line
			(start -0.652 -0.425)
			(end 0.65 -0.425)
			(stroke
				(width 0.15)
				(type solid)
			)
			(layer "F.Fab")
		)
		(fp_line
			(start -0.35 -0.4)
			(end -0.35 0.4)
			(stroke
				(width 0.15)
				(type solid)
			)
			(layer "F.Fab")
		)
		(fp_line
			(start -0.652 0.423)
			(end -0.652 -0.425)
			(stroke
				(width 0.15)
				(type solid)
			)
			(layer "F.Fab")
		)
		(fp_line
			(start -0.652 0.423)
			(end 0.65 0.423)
			(stroke
				(width 0.15)
				(type solid)
			)
			(layer "F.Fab")
		)
		(fp_text user "Author: Antmicro"
			(at -1.276 4.7 90)
			(layer "F.Fab")
			(effects
				(font
					(size 0.7 0.7)
					(thickness 0.15)
				)
				(justify left bottom)
			)
		)
		(fp_text user "License: Apache-2.0"
			(at -1.276 5.9 90)
			(layer "F.Fab")
			(effects
				(font
					(size 0.7 0.7)
					(thickness 0.15)
				)
				(justify left bottom)
			)
		)
		(fp_text user "${REFERENCE}"
			(at -1.276 3.499 90)
			(layer "F.Fab")
			(effects
				(font
					(size 0.7 0.7)
					(thickness 0.15)
				)
				(justify left bottom)
			)
		)
		(pad "1" smd roundrect
			(at -0.701 0 90)
			(size 0.5 0.6)
			(layers "F.Cu" "F.Mask" "F.Paste")
			(roundrect_rratio 0.25)
			(net 357 "/FPGA Config/PROGRAM_B")
			(pinfunction "C")
			(pintype "passive")
		)
		(pad "2" smd roundrect
			(at 0.699 0 90)
			(size 0.5 0.6)
			(layers "F.Cu" "F.Mask" "F.Paste")
			(roundrect_rratio 0.25)
			(net 1 "GND")
			(pinfunction "A")
			(pintype "passive")
		)
	)
	(footprint "antmicro-footprints:C_0603_1608Metric"
		(layer "F.Cu")
		(at 109.273499 139.299 90)
		(descr "Capacitor SMD 0603")
		(tags "capacitor 0603")
		(property "Reference" "C109"
			(at -1.42757 -1.000252 90)
			(layer "F.SilkS")
			(effects
				(font
					(size 0.7 0.7)
					(thickness 0.15)
				)
				(justify left bottom)
			)
		)
		(property "Value" "C_10u_25V_0603"
			(at -1.42757 1.770288 90)
			(layer "F.Fab")
			(effects
				(font
					(size 0.7 0.7)
					(thickness 0.15)
				)
				(justify left bottom)
			)
		)
		(property "Datasheet" "https://product.tdk.com/en/search/capacitor/ceramic/mlcc/info?part_no=C1608X5R1E106M080AC"
			(at 0 0 90)
			(layer "F.Fab")
			(hide yes)
			(effects
				(font
					(size 1.27 1.27)
					(thickness 0.15)
				)
			)
		)
		(property "Manufacturer" "TDK"
			(at 0 0 90)
			(unlocked yes)
			(layer "F.Fab")
			(hide yes)
			(effects
				(font
					(size 1 1)
					(thickness 0.15)
				)
			)
		)
		(property "MPN" "C1608X5R1E106M080AC"
			(at 0 0 90)
			(unlocked yes)
			(layer "F.Fab")
			(hide yes)
			(effects
				(font
					(size 1 1)
					(thickness 0.15)
				)
			)
		)
		(property "Val" "10u"
			(at 0 0 90)
			(unlocked yes)
			(layer "F.Fab")
			(hide yes)
			(effects
				(font
					(size 1 1)
					(thickness 0.15)
				)
			)
		)
		(property "License" "Apache-2.0"
			(at 0 0 90)
			(unlocked yes)
			(layer "F.Fab")
			(hide yes)
			(effects
				(font
					(size 1 1)
					(thickness 0.15)
				)
			)
		)
		(property "Author" "Antmicro"
			(at 0 0 90)
			(unlocked yes)
			(layer "F.Fab")
			(hide yes)
			(effects
				(font
					(size 1 1)
					(thickness 0.15)
				)
			)
		)
		(property "Voltage" "25V"
			(at 0 0 90)
			(unlocked yes)
			(layer "F.Fab")
			(hide yes)
			(effects
				(font
					(size 1 1)
					(thickness 0.15)
				)
			)
		)
		(property "Dielectric" ""
			(at 0 0 90)
			(unlocked yes)
			(layer "F.Fab")
			(hide yes)
			(effects
				(font
					(size 1 1)
					(thickness 0.15)
				)
			)
		)
		(sheetname "/Debug FTDI + VNA/")
		(sheetfile "debug-ftdi.kicad_sch")
		(attr smd)
		(fp_line
			(start -0.15 -0.4)
			(end 0.15 -0.4)
			(stroke
				(width 0.15)
				(type solid)
			)
			(layer "F.SilkS")
		)
		(fp_line
			(start -0.15 0.4)
			(end 0.15 0.4)
			(stroke
				(width 0.15)
				(type solid)
			)
			(layer "F.SilkS")
		)
		(fp_rect
			(start -1.25 -0.65)
			(end 1.25 0.65)
			(stroke
				(width 0.05)
				(type solid)
			)
			(fill no)
			(layer "F.CrtYd")
		)
		(fp_rect
			(start -0.8 -0.4)
			(end 0.8 0.4)
			(stroke
				(width 0.15)
				(type solid)
			)
			(fill no)
			(layer "F.Fab")
		)
		(fp_text user "License: Apache-2.0"
			(at -1.682 5.895 90)
			(layer "F.Fab")
			(effects
				(font
					(size 0.7 0.7)
					(thickness 0.15)
				)
				(justify left bottom)
			)
		)
		(fp_text user "${REFERENCE}"
			(at -1.682 3.895 90)
			(layer "F.Fab")
			(effects
				(font
					(size 0.7 0.7)
					(thickness 0.15)
				)
				(justify left bottom)
			)
		)
		(fp_text user "Author: Antmicro"
			(at -1.682 4.894 90)
			(layer "F.Fab")
			(effects
				(font
					(size 0.7 0.7)
					(thickness 0.15)
				)
				(justify left bottom)
			)
		)
		(pad "1" smd roundrect
			(at -0.7 0 90)
			(size 0.8 1)
			(layers "F.Cu" "F.Mask" "F.Paste")
			(roundrect_rratio 0.2)
			(net 1 "GND")
			(pintype "passive")
		)
		(pad "2" smd roundrect
			(at 0.7 0 90)
			(size 0.8 1)
			(layers "F.Cu" "F.Mask" "F.Paste")
			(roundrect_rratio 0.2)
			(net 2 "/Debug FTDI + VNA/VBUS")
			(pintype "passive")
		)
	)
	(footprint "antmicro-footprints:C_0402_1005Metric"
		(layer "F.Cu")
		(at 121.5 164 90)
		(descr "Capacitor SMD 0402")
		(tags "capacitor SMD 0402")
		(property "Reference" "C295"
			(at -2.03 -0.63 90)
			(layer "F.SilkS")
			(effects
				(font
					(size 0.7 0.7)
					(thickness 0.15)
				)
				(justify left bottom)
			)
		)
		(property "Value" "C_100n_0402"
			(at -1.022927 2.155213 90)
			(layer "F.Fab")
			(effects
				(font
					(size 0.7 0.7)
					(thickness 0.15)
				)
				(justify left bottom)
			)
		)
		(property "Datasheet" "https://www.murata.com/products/productdetail?partno=GRM155R61H104KE14%23"
			(at 0 0 90)
			(layer "F.Fab")
			(hide yes)
			(effects
				(font
					(size 1.27 1.27)
					(thickness 0.15)
				)
			)
		)
		(property "MPN" "GRM155R61H104KE14D"
			(at 0 0 90)
			(unlocked yes)
			(layer "F.Fab")
			(hide yes)
			(effects
				(font
					(size 1 1)
					(thickness 0.15)
				)
			)
		)
		(property "Manufacturer" "Murata"
			(at 0 0 90)
			(unlocked yes)
			(layer "F.Fab")
			(hide yes)
			(effects
				(font
					(size 1 1)
					(thickness 0.15)
				)
			)
		)
		(property "License" "Apache-2.0"
			(at 0 0 90)
			(unlocked yes)
			(layer "F.Fab")
			(hide yes)
			(effects
				(font
					(size 1 1)
					(thickness 0.15)
				)
			)
		)
		(property "Author" "Antmicro"
			(at 0 0 90)
			(unlocked yes)
			(layer "F.Fab")
			(hide yes)
			(effects
				(font
					(size 1 1)
					(thickness 0.15)
				)
			)
		)
		(property "Val" "100n"
			(at 0 0 90)
			(unlocked yes)
			(layer "F.Fab")
			(hide yes)
			(effects
				(font
					(size 1 1)
					(thickness 0.15)
				)
			)
		)
		(property "Voltage" "50V"
			(at 0 0 90)
			(unlocked yes)
			(layer "F.Fab")
			(hide yes)
			(effects
				(font
					(size 1 1)
					(thickness 0.15)
				)
			)
		)
		(property "Dielectric" "X5R"
			(at 0 0 90)
			(unlocked yes)
			(layer "F.Fab")
			(hide yes)
			(effects
				(font
					(size 1 1)
					(thickness 0.15)
				)
			)
		)
		(sheetname "/HDMI + SD Card/")
		(sheetfile "hdmi-sd-card.kicad_sch")
		(attr smd)
		(fp_rect
			(start -0.925 -0.47)
			(end 0.925 0.47)
			(stroke
				(width 0.05)
				(type default)
			)
			(fill no)
			(layer "F.CrtYd")
		)
		(fp_line
			(start 0.504 -0.25)
			(end 0.504 0.248)
			(stroke
				(width 0.15)
				(type solid)
			)
			(layer "F.Fab")
		)
		(fp_line
			(start -0.494 -0.25)
			(end 0.504 -0.25)
			(stroke
				(width 0.15)
				(type solid)
			)
			(layer "F.Fab")
		)
		(fp_line
			(start 0.504 0.248)
			(end -0.494 0.248)
			(stroke
				(width 0.15)
				(type solid)
			)
			(layer "F.Fab")
		)
		(fp_line
			(start -0.494 0.248)
			(end -0.494 -0.25)
			(stroke
				(width 0.15)
				(type solid)
			)
			(layer "F.Fab")
		)
		(fp_text user "Author: Antmicro"
			(at -0.939 3.399 90)
			(layer "F.Fab")
			(effects
				(font
					(size 0.7 0.7)
					(thickness 0.15)
				)
				(justify left bottom)
			)
		)
		(fp_text user "License: Apache-2.0"
			(at -0.939 5.799 90)
			(layer "F.Fab")
			(effects
				(font
					(size 0.7 0.7)
					(thickness 0.15)
				)
				(justify left bottom)
			)
		)
		(fp_text user "${REFERENCE}"
			(at -0.939 4.599 90)
			(layer "F.Fab")
			(effects
				(font
					(size 0.7 0.7)
					(thickness 0.15)
				)
				(justify left bottom)
			)
		)
		(pad "1" smd roundrect
			(at -0.48 0 90)
			(size 0.59 0.64)
			(layers "F.Cu" "F.Mask" "F.Paste")
			(roundrect_rratio 0.25)
			(net 1 "GND")
			(pintype "passive")
		)
		(pad "2" smd roundrect
			(at 0.48 0 90)
			(size 0.59 0.64)
			(layers "F.Cu" "F.Mask" "F.Paste")
			(roundrect_rratio 0.25)
			(net 647 "/HDMI + SD Card/VCCB")
			(pintype "passive")
		)
	)
	(footprint "antmicro-footprints:R_0402_1005Metric"
		(layer "F.Cu")
		(at 122.681 166.1125 90)
		(descr "Resistor SMD 0402")
		(tags "resistor SMD 0402")
		(property "Reference" "R230"
			(at 0.9125 3.969 90)
			(layer "F.SilkS")
			(effects
				(font
					(size 0.7 0.7)
					(thickness 0.15)
				)
				(justify left bottom)
			)
		)
		(property "Value" "R_64k9_0402"
			(at -1.011843 1.772047 90)
			(layer "F.Fab")
			(effects
				(font
					(size 0.7 0.7)
					(thickness 0.15)
				)
				(justify left bottom)
			)
		)
		(property "Datasheet" "https://www.bourns.com/docs/product-datasheets/cr.pdf"
			(at 0 0 90)
			(layer "F.Fab")
			(hide yes)
			(effects
				(font
					(size 1.27 1.27)
					(thickness 0.15)
				)
			)
		)
		(property "MPN" "CR0402-FX-6492GLF"
			(at 0 0 90)
			(unlocked yes)
			(layer "F.Fab")
			(hide yes)
			(effects
				(font
					(size 1 1)
					(thickness 0.15)
				)
			)
		)
		(property "Manufacturer" "Bourns"
			(at 0 0 90)
			(unlocked yes)
			(layer "F.Fab")
			(hide yes)
			(effects
				(font
					(size 1 1)
					(thickness 0.15)
				)
			)
		)
		(property "License" "Apache-2.0"
			(at 0 0 90)
			(unlocked yes)
			(layer "F.Fab")
			(hide yes)
			(effects
				(font
					(size 1 1)
					(thickness 0.15)
				)
			)
		)
		(property "Author" "Antmicro"
			(at 0 0 90)
			(unlocked yes)
			(layer "F.Fab")
			(hide yes)
			(effects
				(font
					(size 1 1)
					(thickness 0.15)
				)
			)
		)
		(property "Val" "64k9"
			(at 0 0 90)
			(unlocked yes)
			(layer "F.Fab")
			(hide yes)
			(effects
				(font
					(size 1 1)
					(thickness 0.15)
				)
			)
		)
		(property "Tolerance" "1%"
			(at 0 0 90)
			(unlocked yes)
			(layer "F.Fab")
			(hide yes)
			(effects
				(font
					(size 1 1)
					(thickness 0.15)
				)
			)
		)
		(sheetname "/HDMI + SD Card/")
		(sheetfile "hdmi-sd-card.kicad_sch")
		(attr smd exclude_from_bom dnp)
		(fp_rect
			(start -0.925 -0.47)
			(end 0.925 0.47)
			(stroke
				(width 0.05)
				(type default)
			)
			(fill no)
			(layer "F.CrtYd")
		)
		(fp_rect
			(start -0.5 -0.25)
			(end 0.5 0.25)
			(stroke
				(width 0.15)
				(type solid)
			)
			(fill no)
			(layer "F.Fab")
		)
		(fp_text user "Author: Antmicro"
			(at -0.95 4.169 90)
			(layer "F.Fab")
			(effects
				(font
					(size 0.7 0.7)
					(thickness 0.15)
				)
				(justify left bottom)
			)
		)
		(fp_text user "${REFERENCE}"
			(at -0.95 3.168 90)
			(layer "F.Fab")
			(effects
				(font
					(size 0.7 0.7)
					(thickness 0.15)
				)
				(justify left bottom)
			)
		)
		(fp_text user "License: Apache-2.0"
			(at -0.95 5.169 90)
			(layer "F.Fab")
			(effects
				(font
					(size 0.7 0.7)
					(thickness 0.15)
				)
				(justify left bottom)
			)
		)
		(pad "1" smd roundrect
			(at -0.48 0 90)
			(size 0.59 0.64)
			(layers "F.Cu" "F.Mask" "F.Paste")
			(roundrect_rratio 0.25)
			(net 740 "/HDMI + SD Card/SLEW_CTL")
			(pintype "passive")
		)
		(pad "2" smd roundrect
			(at 0.48 0 90)
			(size 0.59 0.64)
			(layers "F.Cu" "F.Mask" "F.Paste")
			(roundrect_rratio 0.25)
			(net 151 "+3V3")
			(pintype "passive")
		)
	)
	(footprint "antmicro-footprints:C_0402_1005Metric"
		(layer "F.Cu")
		(at 226.365 179.185001 180)
		(descr "Capacitor SMD 0402")
		(tags "capacitor SMD 0402")
		(property "Reference" "C218"
			(at 1.335 -0.404999 315)
			(layer "F.SilkS")
			(effects
				(font
					(size 0.7 0.7)
					(thickness 0.15)
				)
				(justify right bottom)
			)
		)
		(property "Value" "C_4u7_25V_0402"
			(at -1.022927 2.155213 0)
			(layer "F.Fab")
			(effects
				(font
					(size 0.7 0.7)
					(thickness 0.15)
				)
				(justify right bottom)
			)
		)
		(property "Datasheet" "https://www.murata.com/products/productdetail?partno=GRM155C61E475ME15%23"
			(at 0 0 180)
			(layer "F.Fab")
			(hide yes)
			(effects
				(font
					(size 1.27 1.27)
					(thickness 0.15)
				)
			)
		)
		(property "MPN" "GRM155C61E475ME15J"
			(at 0 0 180)
			(unlocked yes)
			(layer "F.Fab")
			(hide yes)
			(effects
				(font
					(size 1 1)
					(thickness 0.15)
				)
			)
		)
		(property "Manufacturer" "Murata"
			(at 0 0 180)
			(unlocked yes)
			(layer "F.Fab")
			(hide yes)
			(effects
				(font
					(size 1 1)
					(thickness 0.15)
				)
			)
		)
		(property "License" "Apache-2.0"
			(at 0 0 180)
			(unlocked yes)
			(layer "F.Fab")
			(hide yes)
			(effects
				(font
					(size 1 1)
					(thickness 0.15)
				)
			)
		)
		(property "Author" "Antmicro"
			(at 0 0 180)
			(unlocked yes)
			(layer "F.Fab")
			(hide yes)
			(effects
				(font
					(size 1 1)
					(thickness 0.15)
				)
			)
		)
		(property "Val" "4u7"
			(at 0 0 180)
			(unlocked yes)
			(layer "F.Fab")
			(hide yes)
			(effects
				(font
					(size 1 1)
					(thickness 0.15)
				)
			)
		)
		(property "Voltage" "25V"
			(at 0 0 180)
			(unlocked yes)
			(layer "F.Fab")
			(hide yes)
			(effects
				(font
					(size 1 1)
					(thickness 0.15)
				)
			)
		)
		(property "Dielectric" "X5S"
			(at 0 0 180)
			(unlocked yes)
			(layer "F.Fab")
			(hide yes)
			(effects
				(font
					(size 1 1)
					(thickness 0.15)
				)
			)
		)
		(sheetname "/Supply/DC-DC VCCINT/")
		(sheetfile "dc-dc-vccint.kicad_sch")
		(attr smd)
		(fp_rect
			(start -0.925 -0.47)
			(end 0.925 0.47)
			(stroke
				(width 0.05)
				(type default)
			)
			(fill no)
			(layer "F.CrtYd")
		)
		(fp_line
			(start 0.504 0.248)
			(end -0.494 0.248)
			(stroke
				(width 0.15)
				(type solid)
			)
			(layer "F.Fab")
		)
		(fp_line
			(start 0.504 -0.25)
			(end 0.504 0.248)
			(stroke
				(width 0.15)
				(type solid)
			)
			(layer "F.Fab")
		)
		(fp_line
			(start -0.494 0.248)
			(end -0.494 -0.25)
			(stroke
				(width 0.15)
				(type solid)
			)
			(layer "F.Fab")
		)
		(fp_line
			(start -0.494 -0.25)
			(end 0.504 -0.25)
			(stroke
				(width 0.15)
				(type solid)
			)
			(layer "F.Fab")
		)
		(fp_text user "License: Apache-2.0"
			(at -0.939 5.799 180)
			(layer "F.Fab")
			(effects
				(font
					(size 0.7 0.7)
					(thickness 0.15)
				)
				(justify left bottom)
			)
		)
		(fp_text user "${REFERENCE}"
			(at -0.939 4.599 180)
			(layer "F.Fab")
			(effects
				(font
					(size 0.7 0.7)
					(thickness 0.15)
				)
				(justify left bottom)
			)
		)
		(fp_text user "Author: Antmicro"
			(at -0.939 3.399 180)
			(layer "F.Fab")
			(effects
				(font
					(size 0.7 0.7)
					(thickness 0.15)
				)
				(justify left bottom)
			)
		)
		(pad "1" smd roundrect
			(at -0.48 0 180)
			(size 0.59 0.64)
			(layers "F.Cu" "F.Mask" "F.Paste")
			(roundrect_rratio 0.25)
			(net 1 "GND")
			(pintype "passive")
		)
		(pad "2" smd roundrect
			(at 0.48 0 180)
			(size 0.59 0.64)
			(layers "F.Cu" "F.Mask" "F.Paste")
			(roundrect_rratio 0.25)
			(net 49 "Net-(U36-V_{DRV})")
			(pintype "passive")
		)
	)
	(footprint "antmicro-footprints:C_Pol_EIA-D"
		(layer "F.Cu")
		(at 216.44 160.4 90)
		(property "Reference" "C12"
			(at -6 2.434998 90)
			(layer "F.SilkS")
			(effects
				(font
					(size 0.7 0.7)
					(thickness 0.15)
				)
				(justify left bottom)
			)
		)
		(property "Value" "C_Pol_1m_2.5V_KEMET-T520-D"
			(at 0 3.4 90)
			(layer "F.Fab")
			(effects
				(font
					(size 0.7 0.7)
					(thickness 0.15)
				)
				(justify left bottom)
			)
		)
		(property "Datasheet" "https://www.kemet.com/en/us/capacitors/product/T520D108M2R5ATE030.html"
			(at 0 0 90)
			(layer "F.Fab")
			(hide yes)
			(effects
				(font
					(size 1.27 1.27)
					(thickness 0.15)
				)
			)
		)
		(property "MPN" "T520D108M2R5ATE030"
			(at 0 0 90)
			(unlocked yes)
			(layer "F.Fab")
			(hide yes)
			(effects
				(font
					(size 1 1)
					(thickness 0.15)
				)
			)
		)
		(property "Manufacturer" "KEMET"
			(at 0 0 90)
			(unlocked yes)
			(layer "F.Fab")
			(hide yes)
			(effects
				(font
					(size 1 1)
					(thickness 0.15)
				)
			)
		)
		(property "License" "Apache-2.0"
			(at 0 0 90)
			(unlocked yes)
			(layer "F.Fab")
			(hide yes)
			(effects
				(font
					(size 1 1)
					(thickness 0.15)
				)
			)
		)
		(property "Author" "Antmicro"
			(at 0 0 90)
			(unlocked yes)
			(layer "F.Fab")
			(hide yes)
			(effects
				(font
					(size 1 1)
					(thickness 0.15)
				)
			)
		)
		(property "Val" "1000u"
			(at 0 0 90)
			(unlocked yes)
			(layer "F.Fab")
			(hide yes)
			(effects
				(font
					(size 1 1)
					(thickness 0.15)
				)
			)
		)
		(property "Voltage" "2.5V"
			(at 0 0 90)
			(unlocked yes)
			(layer "F.Fab")
			(hide yes)
			(effects
				(font
					(size 1 1)
					(thickness 0.15)
				)
			)
		)
		(property "Dielectric" "template_dielectric"
			(at 0 0 90)
			(unlocked yes)
			(layer "F.Fab")
			(hide yes)
			(effects
				(font
					(size 1 1)
					(thickness 0.15)
				)
			)
		)
		(sheetname "/FPGA power/")
		(sheetfile "fpga-power.kicad_sch")
		(attr smd)
		(fp_line
			(start 3.6 -2.2)
			(end 3.6 -1.6)
			(stroke
				(width 0.15)
				(type solid)
			)
			(layer "F.SilkS")
		)
		(fp_line
			(start -3.58 -2.2)
			(end 3.6 -2.2)
			(stroke
				(width 0.15)
				(type solid)
			)
			(layer "F.SilkS")
		)
		(fp_line
			(start -4.1 -2.025)
			(end -4.1 -1.625)
			(stroke
				(width 0.12)
				(type solid)
			)
			(layer "F.SilkS")
		)
		(fp_line
			(start -4.3 -1.825)
			(end -3.9 -1.825)
			(stroke
				(width 0.12)
				(type solid)
			)
			(layer "F.SilkS")
		)
		(fp_line
			(start -3.58 -1.6)
			(end -3.58 -2.2)
			(stroke
				(width 0.15)
				(type solid)
			)
			(layer "F.SilkS")
		)
		(fp_line
			(start 3.6 1.6)
			(end 3.6 2.2)
			(stroke
				(width 0.15)
				(type solid)
			)
			(layer "F.SilkS")
		)
		(fp_line
			(start 3.6 2.2)
			(end -3.58 2.2)
			(stroke
				(width 0.15)
				(type solid)
			)
			(layer "F.SilkS")
		)
		(fp_line
			(start -3.58 2.2)
			(end -3.58 1.6)
			(stroke
				(width 0.15)
				(type solid)
			)
			(layer "F.SilkS")
		)
		(fp_line
			(start 3.77 -2.4)
			(end 3.77 -1.51)
			(stroke
				(width 0.05)
				(type solid)
			)
			(layer "F.CrtYd")
		)
		(fp_line
			(start -3.775 -2.4)
			(end 3.77 -2.4)
			(stroke
				(width 0.05)
				(type solid)
			)
			(layer "F.CrtYd")
		)
		(fp_line
			(start -3.775 -2.4)
			(end -3.775 -1.5)
			(stroke
				(width 0.05)
				(type solid)
			)
			(layer "F.CrtYd")
		)
		(fp_line
			(start 4.505 -1.51)
			(end 4.505 1.5)
			(stroke
				(width 0.05)
				(type solid)
			)
			(layer "F.CrtYd")
		)
		(fp_line
			(start 3.77 -1.51)
			(end 4.505 -1.51)
			(stroke
				(width 0.05)
				(type solid)
			)
			(layer "F.CrtYd")
		)
		(fp_line
			(start -3.775 -1.5)
			(end -4.505 -1.5)
			(stroke
				(width 0.05)
				(type solid)
			)
			(layer "F.CrtYd")
		)
		(fp_line
			(start 4.505 1.51)
			(end 3.77 1.51)
			(stroke
				(width 0.05)
				(type solid)
			)
			(layer "F.CrtYd")
		)
		(fp_line
			(start 3.77 1.51)
			(end 3.77 2.4)
			(stroke
				(width 0.05)
				(type solid)
			)
			(layer "F.CrtYd")
		)
		(fp_line
			(start -3.77 1.51)
			(end -4.505 1.51)
			(stroke
				(width 0.05)
				(type solid)
			)
			(layer "F.CrtYd")
		)
		(fp_line
			(start -4.505 1.51)
			(end -4.505 -1.5)
			(stroke
				(width 0.05)
				(type solid)
			)
			(layer "F.CrtYd")
		)
		(fp_line
			(start 3.77 2.4)
			(end -3.77 2.4)
			(stroke
				(width 0.05)
				(type solid)
			)
			(layer "F.CrtYd")
		)
		(fp_line
			(start -3.77 2.4)
			(end -3.77 1.51)
			(stroke
				(width 0.05)
				(type solid)
			)
			(layer "F.CrtYd")
		)
		(fp_rect
			(start -3.65 -2.15)
			(end 3.65 2.15)
			(stroke
				(width 0.15)
				(type solid)
			)
			(fill no)
			(layer "F.Fab")
		)
		(fp_text user "Author: Antmicro"
			(at -4.5 7.6 90)
			(layer "F.Fab")
			(effects
				(font
					(size 0.7 0.7)
					(thickness 0.15)
				)
				(justify left bottom)
			)
		)
		(fp_text user "License: Apache-2.0"
			(at -4.5 6.6 90)
			(layer "F.Fab")
			(effects
				(font
					(size 0.7 0.7)
					(thickness 0.15)
				)
				(justify left bottom)
			)
		)
		(fp_text user "${REFERENCE}"
			(at -4.5 5.6 90)
			(layer "F.Fab")
			(effects
				(font
					(size 0.7 0.7)
					(thickness 0.15)
				)
				(justify left bottom)
			)
		)
		(pad "1" smd roundrect
			(at -3.1 0 90)
			(size 2.31 2.52)
			(layers "F.Cu" "F.Mask" "F.Paste")
			(roundrect_rratio 0.1)
			(net 553 "+0V85")
			(pintype "passive")
		)
		(pad "2" smd roundrect
			(at 3.1 0 90)
			(size 2.31 2.52)
			(layers "F.Cu" "F.Mask" "F.Paste")
			(roundrect_rratio 0.1)
			(net 1 "GND")
			(pintype "passive")
		)
	)
	(footprint "antmicro-footprints:R_0402_1005Metric"
		(layer "F.Cu")
		(at 117.52 139.083 -90)
		(descr "Resistor SMD 0402")
		(tags "resistor SMD 0402")
		(property "Reference" "R183"
			(at -3.792 0.48 90)
			(layer "F.SilkS")
			(effects
				(font
					(size 0.7 0.7)
					(thickness 0.15)
				)
				(justify right top)
			)
		)
		(property "Value" "R_330R_0402"
			(at -1.011843 1.772047 90)
			(layer "F.Fab")
			(effects
				(font
					(size 0.7 0.7)
					(thickness 0.15)
				)
				(justify right top)
			)
		)
		(property "Datasheet" "https://www.bourns.com/docs/product-datasheets/cr.pdf"
			(at 0 0 90)
			(layer "F.Fab")
			(hide yes)
			(effects
				(font
					(size 1.27 1.27)
					(thickness 0.15)
				)
			)
		)
		(property "Manufacturer" "Bourns"
			(at 0 0 270)
			(unlocked yes)
			(layer "F.Fab")
			(hide yes)
			(effects
				(font
					(size 1 1)
					(thickness 0.15)
				)
			)
		)
		(property "MPN" "CR0402-FX-3300GLF"
			(at 0 0 270)
			(unlocked yes)
			(layer "F.Fab")
			(hide yes)
			(effects
				(font
					(size 1 1)
					(thickness 0.15)
				)
			)
		)
		(property "Val" "330R"
			(at 0 0 270)
			(unlocked yes)
			(layer "F.Fab")
			(hide yes)
			(effects
				(font
					(size 1 1)
					(thickness 0.15)
				)
			)
		)
		(property "License" "Apache-2.0"
			(at 0 0 270)
			(unlocked yes)
			(layer "F.Fab")
			(hide yes)
			(effects
				(font
					(size 1 1)
					(thickness 0.15)
				)
			)
		)
		(property "Author" "Antmicro"
			(at 0 0 270)
			(unlocked yes)
			(layer "F.Fab")
			(hide yes)
			(effects
				(font
					(size 1 1)
					(thickness 0.15)
				)
			)
		)
		(property "Tolerance" "1%"
			(at 0 0 270)
			(unlocked yes)
			(layer "F.Fab")
			(hide yes)
			(effects
				(font
					(size 1 1)
					(thickness 0.15)
				)
			)
		)
		(sheetname "/Debug FTDI + VNA/")
		(sheetfile "debug-ftdi.kicad_sch")
		(attr smd)
		(fp_rect
			(start -0.925 -0.47)
			(end 0.925 0.47)
			(stroke
				(width 0.05)
				(type default)
			)
			(fill no)
			(layer "F.CrtYd")
		)
		(fp_rect
			(start -0.5 -0.25)
			(end 0.5 0.25)
			(stroke
				(width 0.15)
				(type solid)
			)
			(fill no)
			(layer "F.Fab")
		)
		(fp_text user "License: Apache-2.0"
			(at -0.95 5.169 270)
			(layer "F.Fab")
			(effects
				(font
					(size 0.7 0.7)
					(thickness 0.15)
				)
				(justify left bottom)
			)
		)
		(fp_text user "${REFERENCE}"
			(at -0.95 3.168 270)
			(layer "F.Fab")
			(effects
				(font
					(size 0.7 0.7)
					(thickness 0.15)
				)
				(justify left bottom)
			)
		)
		(fp_text user "Author: Antmicro"
			(at -0.95 4.169 270)
			(layer "F.Fab")
			(effects
				(font
					(size 0.7 0.7)
					(thickness 0.15)
				)
				(justify left bottom)
			)
		)
		(pad "1" smd roundrect
			(at -0.48 0 270)
			(size 0.59 0.64)
			(layers "F.Cu" "F.Mask" "F.Paste")
			(roundrect_rratio 0.25)
			(net 220 "Net-(D17-C)")
			(pintype "passive")
		)
		(pad "2" smd roundrect
			(at 0.48 0 270)
			(size 0.59 0.64)
			(layers "F.Cu" "F.Mask" "F.Paste")
			(roundrect_rratio 0.25)
			(net 1 "GND")
			(pintype "passive")
		)
	)
	(footprint "antmicro-footprints:C_0805_2012Metric"
		(layer "F.Cu")
		(at 219.325001 187.669999)
		(descr "Capacitor SMD 0805")
		(tags "capacitor SMD 0805")
		(property "Reference" "C28"
			(at -4.475001 0.470001 0)
			(layer "F.SilkS")
			(effects
				(font
					(size 0.7 0.7)
					(thickness 0.15)
				)
				(justify left bottom)
			)
		)
		(property "Value" "C_22u_25V_0805"
			(at -2.055717 1.963152 0)
			(layer "F.Fab")
			(effects
				(font
					(size 0.7 0.7)
					(thickness 0.15)
				)
				(justify left bottom)
			)
		)
		(property "Datasheet" "https://product.samsungsem.com/mlcc/CL21A226MAYNNN.do"
			(at 0 0 0)
			(layer "F.Fab")
			(hide yes)
			(effects
				(font
					(size 1.27 1.27)
					(thickness 0.15)
				)
			)
		)
		(property "MPN" "CL21A226MAYNNNE"
			(at 0 0 0)
			(unlocked yes)
			(layer "F.Fab")
			(hide yes)
			(effects
				(font
					(size 1 1)
					(thickness 0.15)
				)
			)
		)
		(property "Manufacturer" "Samsung Electro-Mechanics"
			(at 0 0 0)
			(unlocked yes)
			(layer "F.Fab")
			(hide yes)
			(effects
				(font
					(size 1 1)
					(thickness 0.15)
				)
			)
		)
		(property "License" "Apache-2.0"
			(at 0 0 0)
			(unlocked yes)
			(layer "F.Fab")
			(hide yes)
			(effects
				(font
					(size 1 1)
					(thickness 0.15)
				)
			)
		)
		(property "Author" "Antmicro"
			(at 0 0 0)
			(unlocked yes)
			(layer "F.Fab")
			(hide yes)
			(effects
				(font
					(size 1 1)
					(thickness 0.15)
				)
			)
		)
		(property "Val" "22u"
			(at 0 0 0)
			(unlocked yes)
			(layer "F.Fab")
			(hide yes)
			(effects
				(font
					(size 1 1)
					(thickness 0.15)
				)
			)
		)
		(property "Voltage" "25V"
			(at 0 0 0)
			(unlocked yes)
			(layer "F.Fab")
			(hide yes)
			(effects
				(font
					(size 1 1)
					(thickness 0.15)
				)
			)
		)
		(property "Dielectric" "X5R"
			(at 0 0 0)
			(unlocked yes)
			(layer "F.Fab")
			(hide yes)
			(effects
				(font
					(size 1 1)
					(thickness 0.15)
				)
			)
		)
		(property "Public" "False"
			(at 0 0 0)
			(unlocked yes)
			(layer "F.Fab")
			(hide yes)
			(effects
				(font
					(size 1 1)
					(thickness 0.15)
				)
			)
		)
		(sheetname "/Supply/DC-DC VCCINT/")
		(sheetfile "dc-dc-vccint.kicad_sch")
		(attr smd)
		(fp_line
			(start -0.3 -0.7)
			(end 0.3 -0.7)
			(stroke
				(width 0.15)
				(type solid)
			)
			(layer "F.SilkS")
		)
		(fp_line
			(start -0.3 0.7)
			(end 0.3 0.7)
			(stroke
				(width 0.15)
				(type solid)
			)
			(layer "F.SilkS")
		)
		(fp_rect
			(start 1.95 -0.9)
			(end -1.95 0.9)
			(stroke
				(width 0.05)
				(type default)
			)
			(fill no)
			(layer "F.CrtYd")
		)
		(fp_rect
			(start -0.95 -0.675)
			(end 0.95 0.675)
			(stroke
				(width 0.15)
				(type solid)
			)
			(fill no)
			(layer "F.Fab")
		)
		(fp_text user "${REFERENCE}"
			(at -1.9 3.947 0)
			(layer "F.Fab")
			(effects
				(font
					(size 0.7 0.7)
					(thickness 0.15)
				)
				(justify left bottom)
			)
		)
		(fp_text user "Author: Antmicro"
			(at -1.9 5.947 0)
			(layer "F.Fab")
			(effects
				(font
					(size 0.7 0.7)
					(thickness 0.15)
				)
				(justify left bottom)
			)
		)
		(fp_text user "License: Apache-2.0"
			(at -1.9 4.947 0)
			(layer "F.Fab")
			(effects
				(font
					(size 0.7 0.7)
					(thickness 0.15)
				)
				(justify left bottom)
			)
		)
		(pad "1" smd roundrect
			(at -1.1 0)
			(size 1.2 1.3)
			(layers "F.Cu" "F.Mask" "F.Paste")
			(roundrect_rratio 0.25)
			(net 1 "GND")
			(pintype "passive")
		)
		(pad "2" smd roundrect
			(at 1.1 0)
			(size 1.2 1.3)
			(layers "F.Cu" "F.Mask" "F.Paste")
			(roundrect_rratio 0.25)
			(net 35 "VDC")
			(pintype "passive")
		)
	)
	(footprint "antmicro-footprints:R_0402_1005Metric"
		(layer "F.Cu")
		(at 120 170.775 90)
		(descr "Resistor SMD 0402")
		(tags "resistor SMD 0402")
		(property "Reference" "R247"
			(at 1.375 0.025 90)
			(layer "F.SilkS")
			(effects
				(font
					(size 0.7 0.7)
					(thickness 0.15)
				)
				(justify left bottom)
			)
		)
		(property "Value" "R_0R_0402"
			(at -1.011843 1.772047 90)
			(layer "F.Fab")
			(effects
				(font
					(size 0.7 0.7)
					(thickness 0.15)
				)
				(justify left bottom)
			)
		)
		(property "Datasheet" "https://industrial.panasonic.com/cdbs/www-data/pdf/RDA0000/AOA0000C301.pdf"
			(at 0 0 90)
			(layer "F.Fab")
			(hide yes)
			(effects
				(font
					(size 1.27 1.27)
					(thickness 0.15)
				)
			)
		)
		(property "MPN" "ERJ2GE0R00X"
			(at 0 0 90)
			(unlocked yes)
			(layer "F.Fab")
			(hide yes)
			(effects
				(font
					(size 1 1)
					(thickness 0.15)
				)
			)
		)
		(property "Manufacturer" "Panasonic"
			(at 0 0 90)
			(unlocked yes)
			(layer "F.Fab")
			(hide yes)
			(effects
				(font
					(size 1 1)
					(thickness 0.15)
				)
			)
		)
		(property "License" "Apache-2.0"
			(at 0 0 90)
			(unlocked yes)
			(layer "F.Fab")
			(hide yes)
			(effects
				(font
					(size 1 1)
					(thickness 0.15)
				)
			)
		)
		(property "Author" "Antmicro"
			(at 0 0 90)
			(unlocked yes)
			(layer "F.Fab")
			(hide yes)
			(effects
				(font
					(size 1 1)
					(thickness 0.15)
				)
			)
		)
		(property "Val" "0R"
			(at 0 0 90)
			(unlocked yes)
			(layer "F.Fab")
			(hide yes)
			(effects
				(font
					(size 1 1)
					(thickness 0.15)
				)
			)
		)
		(property "Tolerance" "~"
			(at 0 0 90)
			(unlocked yes)
			(layer "F.Fab")
			(hide yes)
			(effects
				(font
					(size 1 1)
					(thickness 0.15)
				)
			)
		)
		(property "Current" "1A"
			(at 0 0 90)
			(unlocked yes)
			(layer "F.Fab")
			(hide yes)
			(effects
				(font
					(size 1 1)
					(thickness 0.15)
				)
			)
		)
		(sheetname "/HDMI + SD Card/")
		(sheetfile "hdmi-sd-card.kicad_sch")
		(attr smd exclude_from_bom dnp)
		(fp_rect
			(start -0.925 -0.47)
			(end 0.925 0.47)
			(stroke
				(width 0.05)
				(type default)
			)
			(fill no)
			(layer "F.CrtYd")
		)
		(fp_rect
			(start -0.5 -0.25)
			(end 0.5 0.25)
			(stroke
				(width 0.15)
				(type solid)
			)
			(fill no)
			(layer "F.Fab")
		)
		(fp_text user "${REFERENCE}"
			(at -0.95 3.168 90)
			(layer "F.Fab")
			(effects
				(font
					(size 0.7 0.7)
					(thickness 0.15)
				)
				(justify left bottom)
			)
		)
		(fp_text user "Author: Antmicro"
			(at -0.95 4.169 90)
			(layer "F.Fab")
			(effects
				(font
					(size 0.7 0.7)
					(thickness 0.15)
				)
				(justify left bottom)
			)
		)
		(fp_text user "License: Apache-2.0"
			(at -0.95 5.169 90)
			(layer "F.Fab")
			(effects
				(font
					(size 0.7 0.7)
					(thickness 0.15)
				)
				(justify left bottom)
			)
		)
		(pad "1" smd roundrect
			(at -0.48 0 90)
			(size 0.59 0.64)
			(layers "F.Cu" "F.Mask" "F.Paste")
			(roundrect_rratio 0.25)
			(net 810 "/HDMI + SD Card/HDMI_VDD")
			(pintype "passive")
		)
		(pad "2" smd roundrect
			(at 0.48 0 90)
			(size 0.59 0.64)
			(layers "F.Cu" "F.Mask" "F.Paste")
			(roundrect_rratio 0.25)
			(net 687 "VDDQ")
			(pintype "passive")
		)
	)
	(footprint "antmicro-footprints:C_0603_1608Metric"
		(layer "F.Cu")
		(at 221.955 168.73 180)
		(descr "Capacitor SMD 0603")
		(tags "capacitor 0603")
		(property "Reference" "C219"
			(at -3.42 -3.015001 0)
			(layer "F.SilkS")
			(effects
				(font
					(size 0.7 0.7)
					(thickness 0.15)
				)
				(justify right bottom)
			)
		)
		(property "Value" "C_22u_0603"
			(at -1.42757 1.770288 0)
			(layer "F.Fab")
			(effects
				(font
					(size 0.7 0.7)
					(thickness 0.15)
				)
				(justify right bottom)
			)
		)
		(property "Datasheet" "https://www.murata.com/products/productdetail?partno=GRM188R60J226MEA0%23"
			(at 0 0 180)
			(layer "F.Fab")
			(hide yes)
			(effects
				(font
					(size 1.27 1.27)
					(thickness 0.15)
				)
			)
		)
		(property "Manufacturer" "Murata"
			(at 0 0 180)
			(unlocked yes)
			(layer "F.Fab")
			(hide yes)
			(effects
				(font
					(size 1 1)
					(thickness 0.15)
				)
			)
		)
		(property "MPN" "GRM188R60J226MEA0D"
			(at 0 0 180)
			(unlocked yes)
			(layer "F.Fab")
			(hide yes)
			(effects
				(font
					(size 1 1)
					(thickness 0.15)
				)
			)
		)
		(property "Val" "22u"
			(at 0 0 180)
			(unlocked yes)
			(layer "F.Fab")
			(hide yes)
			(effects
				(font
					(size 1 1)
					(thickness 0.15)
				)
			)
		)
		(property "License" "Apache-2.0"
			(at 0 0 180)
			(unlocked yes)
			(layer "F.Fab")
			(hide yes)
			(effects
				(font
					(size 1 1)
					(thickness 0.15)
				)
			)
		)
		(property "Author" "Antmicro"
			(at 0 0 180)
			(unlocked yes)
			(layer "F.Fab")
			(hide yes)
			(effects
				(font
					(size 1 1)
					(thickness 0.15)
				)
			)
		)
		(property "Voltage" ""
			(at 0 0 180)
			(unlocked yes)
			(layer "F.Fab")
			(hide yes)
			(effects
				(font
					(size 1 1)
					(thickness 0.15)
				)
			)
		)
		(property "Dielectric" ""
			(at 0 0 180)
			(unlocked yes)
			(layer "F.Fab")
			(hide yes)
			(effects
				(font
					(size 1 1)
					(thickness 0.15)
				)
			)
		)
		(sheetname "/Supply/DC-DC VCCINT/")
		(sheetfile "dc-dc-vccint.kicad_sch")
		(attr smd)
		(fp_line
			(start -0.15 0.4)
			(end 0.15 0.4)
			(stroke
				(width 0.15)
				(type solid)
			)
			(layer "F.SilkS")
		)
		(fp_line
			(start -0.15 -0.4)
			(end 0.15 -0.4)
			(stroke
				(width 0.15)
				(type solid)
			)
			(layer "F.SilkS")
		)
		(fp_rect
			(start -1.25 -0.65)
			(end 1.25 0.65)
			(stroke
				(width 0.05)
				(type solid)
			)
			(fill no)
			(layer "F.CrtYd")
		)
		(fp_rect
			(start -0.8 -0.4)
			(end 0.8 0.4)
			(stroke
				(width 0.15)
				(type solid)
			)
			(fill no)
			(layer "F.Fab")
		)
		(fp_text user "License: Apache-2.0"
			(at -1.682 5.895 180)
			(layer "F.Fab")
			(effects
				(font
					(size 0.7 0.7)
					(thickness 0.15)
				)
				(justify left bottom)
			)
		)
		(fp_text user "${REFERENCE}"
			(at -1.682 3.895 180)
			(layer "F.Fab")
			(effects
				(font
					(size 0.7 0.7)
					(thickness 0.15)
				)
				(justify left bottom)
			)
		)
		(fp_text user "Author: Antmicro"
			(at -1.682 4.894 180)
			(layer "F.Fab")
			(effects
				(font
					(size 0.7 0.7)
					(thickness 0.15)
				)
				(justify left bottom)
			)
		)
		(pad "1" smd roundrect
			(at -0.7 0 180)
			(size 0.8 1)
			(layers "F.Cu" "F.Mask" "F.Paste")
			(roundrect_rratio 0.2)
			(net 1 "GND")
			(pintype "passive")
		)
		(pad "2" smd roundrect
			(at 0.7 0 180)
			(size 0.8 1)
			(layers "F.Cu" "F.Mask" "F.Paste")
			(roundrect_rratio 0.2)
			(net 223 "/Supply/DC-DC VCCINT/0V85_REG0")
			(pintype "passive")
		)
	)
	(footprint "antmicro-footprints:TQFN-25_4x5mm"
		(layer "F.Cu")
		(at 219.250001 182.245001 -90)
		(property "Reference" "U4"
			(at 3.614999 -2.199999 0)
			(unlocked yes)
			(layer "F.SilkS")
			(effects
				(font
					(size 0.7 0.7)
					(thickness 0.15)
				)
				(justify left bottom)
			)
		)
		(property "Value" "MP8796B"
			(at 12.501 7.605 270)
			(unlocked yes)
			(layer "F.Fab")
			(effects
				(font
					(size 0.7 0.7)
					(thickness 0.15)
				)
				(justify left bottom)
			)
		)
		(property "Datasheet" "https://www.monolithicpower.com/en/documentview/productdocument/index/version/2/document_type/Datasheet/lang/en/sku/MP8796B/"
			(at 0 0 270)
			(layer "F.Fab")
			(hide yes)
			(effects
				(font
					(size 1.27 1.27)
					(thickness 0.15)
				)
			)
		)
		(property "MPN" "MP8796BGVT-0000-Z"
			(at 0 0 270)
			(unlocked yes)
			(layer "F.Fab")
			(hide yes)
			(effects
				(font
					(size 1 1)
					(thickness 0.15)
				)
			)
		)
		(property "Manufacturer" "Monolithic Power Systems"
			(at 0 0 270)
			(unlocked yes)
			(layer "F.Fab")
			(hide yes)
			(effects
				(font
					(size 1 1)
					(thickness 0.15)
				)
			)
		)
		(property "Author" "Antmicro"
			(at 0 0 270)
			(unlocked yes)
			(layer "F.Fab")
			(hide yes)
			(effects
				(font
					(size 1 1)
					(thickness 0.15)
				)
			)
		)
		(property "License" "Apache-2.0"
			(at 0 0 270)
			(unlocked yes)
			(layer "F.Fab")
			(hide yes)
			(effects
				(font
					(size 1 1)
					(thickness 0.15)
				)
			)
		)
		(sheetname "/Supply/DC-DC VCCINT/")
		(sheetfile "dc-dc-vccint.kicad_sch")
		(attr smd)
		(fp_line
			(start -2.1 2.2)
			(end -2.1 1.7)
			(stroke
				(width 0.15)
				(type solid)
			)
			(layer "F.SilkS")
		)
		(fp_line
			(start 2.1 2.2)
			(end 2.1 1.7)
			(stroke
				(width 0.15)
				(type solid)
			)
			(layer "F.SilkS")
		)
		(fp_line
			(start -2.1 -1.7)
			(end -2.1 -2.2)
			(stroke
				(width 0.15)
				(type solid)
			)
			(layer "F.SilkS")
		)
		(fp_line
			(start 2.1 -2.2)
			(end 2.1 -1.7)
			(stroke
				(width 0.15)
				(type solid)
			)
			(layer "F.SilkS")
		)
		(fp_circle
			(center -2.34 -2.59)
			(end -2.29 -2.59)
			(stroke
				(width 0.15)
				(type solid)
			)
			(fill yes)
			(layer "F.SilkS")
		)
		(fp_rect
			(start -2.5 -2.75)
			(end 2.55 2.76)
			(stroke
				(width 0.05)
				(type solid)
			)
			(fill no)
			(layer "F.CrtYd")
		)
		(fp_text user "Author: Antmicro"
			(at -2.67 5.79 270)
			(layer "F.Fab")
			(effects
				(font
					(size 0.7 0.7)
					(thickness 0.15)
				)
				(justify left bottom)
			)
		)
		(fp_text user "License: Apache-2.0"
			(at -2.67 8.19 270)
			(layer "F.Fab")
			(effects
				(font
					(size 0.7 0.7)
					(thickness 0.15)
				)
				(justify left bottom)
			)
		)
		(fp_text user "${REFERENCE}"
			(at -2.67 6.99 270)
			(unlocked yes)
			(layer "F.Fab")
			(effects
				(font
					(size 0.7 0.7)
					(thickness 0.15)
				)
				(justify left bottom)
			)
		)
		(pad "1" smd roundrect
			(at -1.2 -1.195 90)
			(size 2.1 0.4)
			(layers "F.Cu" "F.Mask" "F.Paste")
			(roundrect_rratio 0.25)
			(net 35 "VDC")
			(pinfunction "IN")
			(pintype "power_in")
		)
		(pad "2" smd roundrect
			(at -1.2 -0.545 90)
			(size 2.1 0.4)
			(layers "F.Cu" "F.Mask" "F.Paste")
			(roundrect_rratio 0.25)
			(net 165 "Net-(C215-Pad2)")
			(pinfunction "SW")
			(pintype "passive")
		)
		(pad "3" smd roundrect
			(at -1.2 0.555 90)
			(size 2.1 0.4)
			(layers "F.Cu" "F.Mask" "F.Paste")
			(roundrect_rratio 0.25)
			(net 165 "Net-(C215-Pad2)")
			(pinfunction "SW")
			(pintype "passive")
		)
		(pad "4" smd roundrect
			(at -1.2 1.205 90)
			(size 2.1 0.4)
			(layers "F.Cu" "F.Mask" "F.Paste")
			(roundrect_rratio 0.25)
			(net 1 "GND")
			(pinfunction "P_{GND}")
			(pintype "passive")
		)
		(pad "5" smd roundrect
			(at -1.7 2.355)
			(size 0.9 0.3)
			(layers "F.Cu" "F.Mask" "F.Paste")
			(roundrect_rratio 0.25)
			(net 222 "Net-(U4-V_{DRV})")
			(pinfunction "V_{DRV}")
			(pintype "passive")
		)
		(pad "6" smd roundrect
			(at -1.2 2.355)
			(size 0.9 0.2)
			(layers "F.Cu" "F.Mask" "F.Paste")
			(roundrect_rratio 0.25)
			(net 749 "/I^{2}C + I3C/PWR.SCL")
			(pinfunction "SCL")
			(pintype "open_collector")
		)
		(pad "7" smd roundrect
			(at -0.8 2.355)
			(size 0.9 0.2)
			(layers "F.Cu" "F.Mask" "F.Paste")
			(roundrect_rratio 0.25)
			(net 533 "/I^{2}C + I3C/PWR.SDA")
			(pinfunction "SDA")
			(pintype "open_collector")
		)
		(pad "8" smd roundrect
			(at -0.4 2.355)
			(size 0.9 0.2)
			(layers "F.Cu" "F.Mask" "F.Paste")
			(roundrect_rratio 0.25)
			(net 741 "/Supply/DC-DC VCCINT/PWR.~{ALT}1")
			(pinfunction "~{ALT}")
			(pintype "open_collector")
		)
		(pad "9" smd roundrect
			(at 0 2.355)
			(size 0.9 0.2)
			(layers "F.Cu" "F.Mask" "F.Paste")
			(roundrect_rratio 0.25)
			(net 168 "/Supply/EN1")
			(pinfunction "CTRL")
			(pintype "input")
		)
		(pad "10" smd roundrect
			(at 0.4 2.355)
			(size 0.9 0.2)
			(layers "F.Cu" "F.Mask" "F.Paste")
			(roundrect_rratio 0.25)
			(net 482 "PG1")
			(pinfunction "PG")
			(pintype "open_collector")
		)
		(pad "11" smd roundrect
			(at 0.8 2.355)
			(size 0.9 0.2)
			(layers "F.Cu" "F.Mask" "F.Paste")
			(roundrect_rratio 0.25)
			(net 721 "/Supply/DC-DC VCCINT/PASS0")
			(pinfunction "PASS")
			(pintype "output")
		)
		(pad "12" smd roundrect
			(at 1.2 2.355)
			(size 0.9 0.2)
			(layers "F.Cu" "F.Mask" "F.Paste")
			(roundrect_rratio 0.25)
			(net 724 "/Supply/DC-DC VCCINT/TAKE0")
			(pinfunction "TAKE")
			(pintype "input")
		)
		(pad "13" smd roundrect
			(at 1.7 2.355)
			(size 0.9 0.3)
			(layers "F.Cu" "F.Mask" "F.Paste")
			(roundrect_rratio 0.25)
			(net 742 "/Supply/DC-DC VCCINT/SET")
			(pinfunction "SET")
			(pintype "bidirectional")
		)
		(pad "14" smd roundrect
			(at 1.2 1.205 90)
			(size 2.1 0.4)
			(layers "F.Cu" "F.Mask" "F.Paste")
			(roundrect_rratio 0.25)
			(net 1 "GND")
			(pinfunction "P_{GND}")
			(pintype "power_in")
		)
		(pad "15" smd roundrect
			(at 1.25 0.005 90)
			(size 2.1 0.4)
			(layers "F.Cu" "F.Mask" "F.Paste")
			(roundrect_rratio 0.25)
			(net 1 "GND")
			(pinfunction "P_{GND}")
			(pintype "passive")
		)
		(pad "16" smd roundrect
			(at 1.2 -1.195 90)
			(size 2.1 0.4)
			(layers "F.Cu" "F.Mask" "F.Paste")
			(roundrect_rratio 0.25)
			(net 35 "VDC")
			(pinfunction "IN")
			(pintype "passive")
		)
		(pad "17" smd roundrect
			(at 1.7 -2.345)
			(size 0.9 0.3)
			(layers "F.Cu" "F.Mask" "F.Paste")
			(roundrect_rratio 0.25)
			(net 1 "GND")
			(pinfunction "~{PS}")
			(pintype "passive")
		)
		(pad "18" smd roundrect
			(at 1.2 -2.345)
			(size 0.9 0.2)
			(layers "F.Cu" "F.Mask" "F.Paste")
			(roundrect_rratio 0.25)
			(net 727 "Net-(U4-ADDR)")
			(pinfunction "ADDR")
			(pintype "passive")
		)
		(pad "19" smd roundrect
			(at 0.8 -2.345)
			(size 0.9 0.2)
			(layers "F.Cu" "F.Mask" "F.Paste")
			(roundrect_rratio 0.25)
			(net 743 "/Supply/DC-DC VCCINT/I_{SUM}")
			(pinfunction "I_{SUM}")
			(pintype "passive")
		)
		(pad "20" smd roundrect
			(at 0.4 -2.345)
			(size 0.9 0.2)
			(layers "F.Cu" "F.Mask" "F.Paste")
			(roundrect_rratio 0.25)
			(net 725 "Net-(U4-I_{REF})")
			(pinfunction "I_{REF}")
			(pintype "passive")
		)
		(pad "21" smd roundrect
			(at 0 -2.345)
			(size 0.9 0.2)
			(layers "F.Cu" "F.Mask" "F.Paste")
			(roundrect_rratio 0.25)
			(net 755 "/Supply/DC-DC VCCINT/VREF-")
			(pinfunction "V_{OSNS}-")
			(pintype "passive")
		)
		(pad "22" smd roundrect
			(at -0.4 -2.345)
			(size 0.9 0.2)
			(layers "F.Cu" "F.Mask" "F.Paste")
			(roundrect_rratio 0.25)
			(net 226 "/Supply/DC-DC VCCINT/V_{0SNS+}")
			(pinfunction "V_{OSNS}+")
			(pintype "passive")
		)
		(pad "23" smd roundrect
			(at -0.8 -2.345)
			(size 0.9 0.2)
			(layers "F.Cu" "F.Mask" "F.Paste")
			(roundrect_rratio 0.25)
			(net 1 "GND")
			(pinfunction "A_{GND}")
			(pintype "power_in")
		)
		(pad "24" smd roundrect
			(at -1.2 -2.345)
			(size 0.9 0.2)
			(layers "F.Cu" "F.Mask" "F.Paste")
			(roundrect_rratio 0.25)
			(net 163 "/Supply/DC-DC VCCINT/V_{CC}")
			(pinfunction "V_{CC}")
			(pintype "power_out")
		)
		(pad "25" smd roundrect
			(at -1.7 -2.345)
			(size 0.9 0.3)
			(layers "F.Cu" "F.Mask" "F.Paste")
			(roundrect_rratio 0.25)
			(net 164 "Net-(U4-BST)")
			(pinfunction "BST")
			(pintype "passive")
		)
	)
	(footprint "antmicro-footprints:C_0402_1005Metric"
		(layer "F.Cu")
		(at 115.781 174.885 -90)
		(descr "Capacitor SMD 0402")
		(tags "capacitor SMD 0402")
		(property "Reference" "C126"
			(at -3.8275 -0.445 90)
			(layer "F.SilkS")
			(effects
				(font
					(size 0.7 0.7)
					(thickness 0.15)
				)
				(justify right bottom)
			)
		)
		(property "Value" "C_10u_6.3V_0402"
			(at -1.022927 2.155213 90)
			(layer "F.Fab")
			(effects
				(font
					(size 0.7 0.7)
					(thickness 0.15)
				)
				(justify right bottom)
			)
		)
		(property "Datasheet" "https://www.murata.com/products/productdetail?partno=GRM155R60J106ME15%23"
			(at 0 0 270)
			(layer "F.Fab")
			(hide yes)
			(effects
				(font
					(size 1.27 1.27)
					(thickness 0.15)
				)
			)
		)
		(property "MPN" "GRM155R60J106ME15D"
			(at 0 0 270)
			(unlocked yes)
			(layer "F.Fab")
			(hide yes)
			(effects
				(font
					(size 1 1)
					(thickness 0.15)
				)
			)
		)
		(property "Manufacturer" "Murata"
			(at 0 0 270)
			(unlocked yes)
			(layer "F.Fab")
			(hide yes)
			(effects
				(font
					(size 1 1)
					(thickness 0.15)
				)
			)
		)
		(property "License" "Apache-2.0"
			(at 0 0 270)
			(unlocked yes)
			(layer "F.Fab")
			(hide yes)
			(effects
				(font
					(size 1 1)
					(thickness 0.15)
				)
			)
		)
		(property "Author" "Antmicro"
			(at 0 0 270)
			(unlocked yes)
			(layer "F.Fab")
			(hide yes)
			(effects
				(font
					(size 1 1)
					(thickness 0.15)
				)
			)
		)
		(property "Val" "10u"
			(at 0 0 270)
			(unlocked yes)
			(layer "F.Fab")
			(hide yes)
			(effects
				(font
					(size 1 1)
					(thickness 0.15)
				)
			)
		)
		(property "Voltage" "6.3V"
			(at 0 0 270)
			(unlocked yes)
			(layer "F.Fab")
			(hide yes)
			(effects
				(font
					(size 1 1)
					(thickness 0.15)
				)
			)
		)
		(property "Dielectric" "X5R"
			(at 0 0 270)
			(unlocked yes)
			(layer "F.Fab")
			(hide yes)
			(effects
				(font
					(size 1 1)
					(thickness 0.15)
				)
			)
		)
		(sheetname "/HDMI + SD Card/")
		(sheetfile "hdmi-sd-card.kicad_sch")
		(attr smd)
		(fp_rect
			(start -0.925 -0.47)
			(end 0.925 0.47)
			(stroke
				(width 0.05)
				(type default)
			)
			(fill no)
			(layer "F.CrtYd")
		)
		(fp_line
			(start -0.494 0.248)
			(end -0.494 -0.25)
			(stroke
				(width 0.15)
				(type solid)
			)
			(layer "F.Fab")
		)
		(fp_line
			(start 0.504 0.248)
			(end -0.494 0.248)
			(stroke
				(width 0.15)
				(type solid)
			)
			(layer "F.Fab")
		)
		(fp_line
			(start -0.494 -0.25)
			(end 0.504 -0.25)
			(stroke
				(width 0.15)
				(type solid)
			)
			(layer "F.Fab")
		)
		(fp_line
			(start 0.504 -0.25)
			(end 0.504 0.248)
			(stroke
				(width 0.15)
				(type solid)
			)
			(layer "F.Fab")
		)
		(fp_text user "${REFERENCE}"
			(at -0.939 4.599 270)
			(layer "F.Fab")
			(effects
				(font
					(size 0.7 0.7)
					(thickness 0.15)
				)
				(justify left bottom)
			)
		)
		(fp_text user "Author: Antmicro"
			(at -0.939 3.399 270)
			(layer "F.Fab")
			(effects
				(font
					(size 0.7 0.7)
					(thickness 0.15)
				)
				(justify left bottom)
			)
		)
		(fp_text user "License: Apache-2.0"
			(at -0.939 5.799 270)
			(layer "F.Fab")
			(effects
				(font
					(size 0.7 0.7)
					(thickness 0.15)
				)
				(justify left bottom)
			)
		)
		(pad "1" smd roundrect
			(at -0.48 0 270)
			(size 0.59 0.64)
			(layers "F.Cu" "F.Mask" "F.Paste")
			(roundrect_rratio 0.25)
			(net 1 "GND")
			(pintype "passive")
		)
		(pad "2" smd roundrect
			(at 0.48 0 270)
			(size 0.59 0.64)
			(layers "F.Cu" "F.Mask" "F.Paste")
			(roundrect_rratio 0.25)
			(net 8 "/HDMI + SD Card/HDMI_CONN_5V")
			(pintype "passive")
		)
	)
	(footprint "antmicro-footprints:C_0603_1608Metric"
		(layer "F.Cu")
		(at 232.65 170.104999 180)
		(descr "Capacitor SMD 0603")
		(tags "capacitor 0603")
		(property "Reference" "C221"
			(at -4.025 -0.395001 0)
			(layer "F.SilkS")
			(effects
				(font
					(size 0.7 0.7)
					(thickness 0.15)
				)
				(justify right bottom)
			)
		)
		(property "Value" "C_22u_0603"
			(at -1.42757 1.770288 0)
			(layer "F.Fab")
			(effects
				(font
					(size 0.7 0.7)
					(thickness 0.15)
				)
				(justify right bottom)
			)
		)
		(property "Datasheet" "https://www.murata.com/products/productdetail?partno=GRM188R60J226MEA0%23"
			(at 0 0 180)
			(layer "F.Fab")
			(hide yes)
			(effects
				(font
					(size 1.27 1.27)
					(thickness 0.15)
				)
			)
		)
		(property "Manufacturer" "Murata"
			(at 0 0 180)
			(unlocked yes)
			(layer "F.Fab")
			(hide yes)
			(effects
				(font
					(size 1 1)
					(thickness 0.15)
				)
			)
		)
		(property "MPN" "GRM188R60J226MEA0D"
			(at 0 0 180)
			(unlocked yes)
			(layer "F.Fab")
			(hide yes)
			(effects
				(font
					(size 1 1)
					(thickness 0.15)
				)
			)
		)
		(property "Val" "22u"
			(at 0 0 180)
			(unlocked yes)
			(layer "F.Fab")
			(hide yes)
			(effects
				(font
					(size 1 1)
					(thickness 0.15)
				)
			)
		)
		(property "License" "Apache-2.0"
			(at 0 0 180)
			(unlocked yes)
			(layer "F.Fab")
			(hide yes)
			(effects
				(font
					(size 1 1)
					(thickness 0.15)
				)
			)
		)
		(property "Author" "Antmicro"
			(at 0 0 180)
			(unlocked yes)
			(layer "F.Fab")
			(hide yes)
			(effects
				(font
					(size 1 1)
					(thickness 0.15)
				)
			)
		)
		(property "Voltage" ""
			(at 0 0 180)
			(unlocked yes)
			(layer "F.Fab")
			(hide yes)
			(effects
				(font
					(size 1 1)
					(thickness 0.15)
				)
			)
		)
		(property "Dielectric" ""
			(at 0 0 180)
			(unlocked yes)
			(layer "F.Fab")
			(hide yes)
			(effects
				(font
					(size 1 1)
					(thickness 0.15)
				)
			)
		)
		(sheetname "/Supply/DC-DC VCCINT/")
		(sheetfile "dc-dc-vccint.kicad_sch")
		(attr smd)
		(fp_line
			(start -0.15 0.4)
			(end 0.15 0.4)
			(stroke
				(width 0.15)
				(type solid)
			)
			(layer "F.SilkS")
		)
		(fp_line
			(start -0.15 -0.4)
			(end 0.15 -0.4)
			(stroke
				(width 0.15)
				(type solid)
			)
			(layer "F.SilkS")
		)
		(fp_rect
			(start -1.25 -0.65)
			(end 1.25 0.65)
			(stroke
				(width 0.05)
				(type solid)
			)
			(fill no)
			(layer "F.CrtYd")
		)
		(fp_rect
			(start -0.8 -0.4)
			(end 0.8 0.4)
			(stroke
				(width 0.15)
				(type solid)
			)
			(fill no)
			(layer "F.Fab")
		)
		(fp_text user "License: Apache-2.0"
			(at -1.682 5.895 180)
			(layer "F.Fab")
			(effects
				(font
					(size 0.7 0.7)
					(thickness 0.15)
				)
				(justify left bottom)
			)
		)
		(fp_text user "Author: Antmicro"
			(at -1.682 4.894 180)
			(layer "F.Fab")
			(effects
				(font
					(size 0.7 0.7)
					(thickness 0.15)
				)
				(justify left bottom)
			)
		)
		(fp_text user "${REFERENCE}"
			(at -1.682 3.895 180)
			(layer "F.Fab")
			(effects
				(font
					(size 0.7 0.7)
					(thickness 0.15)
				)
				(justify left bottom)
			)
		)
		(pad "1" smd roundrect
			(at -0.7 0 180)
			(size 0.8 1)
			(layers "F.Cu" "F.Mask" "F.Paste")
			(roundrect_rratio 0.2)
			(net 1 "GND")
			(pintype "passive")
		)
		(pad "2" smd roundrect
			(at 0.7 0 180)
			(size 0.8 1)
			(layers "F.Cu" "F.Mask" "F.Paste")
			(roundrect_rratio 0.2)
			(net 224 "/Supply/DC-DC VCCINT/0V85_REG1")
			(pintype "passive")
		)
	)
	(footprint "antmicro-footprints:R_0402_1005Metric"
		(layer "F.Cu")
		(at 250.95 182.078 -90)
		(descr "Resistor SMD 0402")
		(tags "resistor SMD 0402")
		(property "Reference" "R15"
			(at -1.278 2.55 90)
			(layer "F.SilkS")
			(effects
				(font
					(size 0.7 0.7)
					(thickness 0.15)
				)
				(justify right bottom)
			)
		)
		(property "Value" "R_0R_0402"
			(at -1.011843 1.772047 90)
			(layer "F.Fab")
			(effects
				(font
					(size 0.7 0.7)
					(thickness 0.15)
				)
				(justify right bottom)
			)
		)
		(property "Datasheet" "https://industrial.panasonic.com/cdbs/www-data/pdf/RDA0000/AOA0000C301.pdf"
			(at 0 0 270)
			(layer "F.Fab")
			(hide yes)
			(effects
				(font
					(size 1.27 1.27)
					(thickness 0.15)
				)
			)
		)
		(property "MPN" "ERJ2GE0R00X"
			(at 0 0 270)
			(unlocked yes)
			(layer "F.Fab")
			(hide yes)
			(effects
				(font
					(size 1 1)
					(thickness 0.15)
				)
			)
		)
		(property "Manufacturer" "Panasonic"
			(at 0 0 270)
			(unlocked yes)
			(layer "F.Fab")
			(hide yes)
			(effects
				(font
					(size 1 1)
					(thickness 0.15)
				)
			)
		)
		(property "License" "Apache-2.0"
			(at 0 0 270)
			(unlocked yes)
			(layer "F.Fab")
			(hide yes)
			(effects
				(font
					(size 1 1)
					(thickness 0.15)
				)
			)
		)
		(property "Author" "Antmicro"
			(at 0 0 270)
			(unlocked yes)
			(layer "F.Fab")
			(hide yes)
			(effects
				(font
					(size 1 1)
					(thickness 0.15)
				)
			)
		)
		(property "Val" "0R"
			(at 0 0 270)
			(unlocked yes)
			(layer "F.Fab")
			(hide yes)
			(effects
				(font
					(size 1 1)
					(thickness 0.15)
				)
			)
		)
		(property "Tolerance" "~"
			(at 0 0 270)
			(unlocked yes)
			(layer "F.Fab")
			(hide yes)
			(effects
				(font
					(size 1 1)
					(thickness 0.15)
				)
			)
		)
		(property "Current" "1A"
			(at 0 0 270)
			(unlocked yes)
			(layer "F.Fab")
			(hide yes)
			(effects
				(font
					(size 1 1)
					(thickness 0.15)
				)
			)
		)
		(sheetname "/I^{2}C + I3C/")
		(sheetfile "i2c.kicad_sch")
		(attr smd)
		(fp_rect
			(start -0.925 -0.47)
			(end 0.925 0.47)
			(stroke
				(width 0.05)
				(type default)
			)
			(fill no)
			(layer "F.CrtYd")
		)
		(fp_rect
			(start -0.5 -0.25)
			(end 0.5 0.25)
			(stroke
				(width 0.15)
				(type solid)
			)
			(fill no)
			(layer "F.Fab")
		)
		(fp_text user "${REFERENCE}"
			(at -0.95 3.168 270)
			(layer "F.Fab")
			(effects
				(font
					(size 0.7 0.7)
					(thickness 0.15)
				)
				(justify left bottom)
			)
		)
		(fp_text user "Author: Antmicro"
			(at -0.95 4.169 270)
			(layer "F.Fab")
			(effects
				(font
					(size 0.7 0.7)
					(thickness 0.15)
				)
				(justify left bottom)
			)
		)
		(fp_text user "License: Apache-2.0"
			(at -0.95 5.169 270)
			(layer "F.Fab")
			(effects
				(font
					(size 0.7 0.7)
					(thickness 0.15)
				)
				(justify left bottom)
			)
		)
		(pad "1" smd roundrect
			(at -0.48 0 270)
			(size 0.59 0.64)
			(layers "F.Cu" "F.Mask" "F.Paste")
			(roundrect_rratio 0.25)
			(net 775 "Net-(Q24-S)")
			(pintype "passive")
		)
		(pad "2" smd roundrect
			(at 0.48 0 270)
			(size 0.59 0.64)
			(layers "F.Cu" "F.Mask" "F.Paste")
			(roundrect_rratio 0.25)
			(net 797 "+1V8")
			(pintype "passive")
		)
	)
	(footprint "antmicro-footprints:C_0805_2012Metric"
		(layer "F.Cu")
		(at 230.01 185.8)
		(descr "Capacitor SMD 0805")
		(tags "capacitor SMD 0805")
		(property "Reference" "C313"
			(at 1.915 0.45 0)
			(layer "F.SilkS")
			(effects
				(font
					(size 0.7 0.7)
					(thickness 0.15)
				)
				(justify left bottom)
			)
		)
		(property "Value" "C_22u_25V_0805"
			(at -2.055717 1.963152 0)
			(layer "F.Fab")
			(effects
				(font
					(size 0.7 0.7)
					(thickness 0.15)
				)
				(justify left bottom)
			)
		)
		(property "Datasheet" "https://product.samsungsem.com/mlcc/CL21A226MAYNNN.do"
			(at 0 0 0)
			(layer "F.Fab")
			(hide yes)
			(effects
				(font
					(size 1.27 1.27)
					(thickness 0.15)
				)
			)
		)
		(property "MPN" "CL21A226MAYNNNE"
			(at 0 0 0)
			(unlocked yes)
			(layer "F.Fab")
			(hide yes)
			(effects
				(font
					(size 1 1)
					(thickness 0.15)
				)
			)
		)
		(property "Manufacturer" "Samsung Electro-Mechanics"
			(at 0 0 0)
			(unlocked yes)
			(layer "F.Fab")
			(hide yes)
			(effects
				(font
					(size 1 1)
					(thickness 0.15)
				)
			)
		)
		(property "License" "Apache-2.0"
			(at 0 0 0)
			(unlocked yes)
			(layer "F.Fab")
			(hide yes)
			(effects
				(font
					(size 1 1)
					(thickness 0.15)
				)
			)
		)
		(property "Author" "Antmicro"
			(at 0 0 0)
			(unlocked yes)
			(layer "F.Fab")
			(hide yes)
			(effects
				(font
					(size 1 1)
					(thickness 0.15)
				)
			)
		)
		(property "Val" "22u"
			(at 0 0 0)
			(unlocked yes)
			(layer "F.Fab")
			(hide yes)
			(effects
				(font
					(size 1 1)
					(thickness 0.15)
				)
			)
		)
		(property "Voltage" "25V"
			(at 0 0 0)
			(unlocked yes)
			(layer "F.Fab")
			(hide yes)
			(effects
				(font
					(size 1 1)
					(thickness 0.15)
				)
			)
		)
		(property "Dielectric" "X5R"
			(at 0 0 0)
			(unlocked yes)
			(layer "F.Fab")
			(hide yes)
			(effects
				(font
					(size 1 1)
					(thickness 0.15)
				)
			)
		)
		(property "Public" "False"
			(at 0 0 0)
			(unlocked yes)
			(layer "F.Fab")
			(hide yes)
			(effects
				(font
					(size 1 1)
					(thickness 0.15)
				)
			)
		)
		(sheetname "/Supply/DC-DC VCCINT/")
		(sheetfile "dc-dc-vccint.kicad_sch")
		(attr smd exclude_from_bom)
		(fp_line
			(start -0.3 -0.7)
			(end 0.3 -0.7)
			(stroke
				(width 0.15)
				(type solid)
			)
			(layer "F.SilkS")
		)
		(fp_line
			(start -0.3 0.7)
			(end 0.3 0.7)
			(stroke
				(width 0.15)
				(type solid)
			)
			(layer "F.SilkS")
		)
		(fp_rect
			(start 1.95 -0.9)
			(end -1.95 0.9)
			(stroke
				(width 0.05)
				(type default)
			)
			(fill no)
			(layer "F.CrtYd")
		)
		(fp_rect
			(start -0.95 -0.675)
			(end 0.95 0.675)
			(stroke
				(width 0.15)
				(type solid)
			)
			(fill no)
			(layer "F.Fab")
		)
		(fp_text user "Author: Antmicro"
			(at -1.9 5.947 0)
			(layer "F.Fab")
			(effects
				(font
					(size 0.7 0.7)
					(thickness 0.15)
				)
				(justify left bottom)
			)
		)
		(fp_text user "License: Apache-2.0"
			(at -1.9 4.947 0)
			(layer "F.Fab")
			(effects
				(font
					(size 0.7 0.7)
					(thickness 0.15)
				)
				(justify left bottom)
			)
		)
		(fp_text user "${REFERENCE}"
			(at -1.9 3.947 0)
			(layer "F.Fab")
			(effects
				(font
					(size 0.7 0.7)
					(thickness 0.15)
				)
				(justify left bottom)
			)
		)
		(pad "1" smd roundrect
			(at -1.1 0)
			(size 1.2 1.3)
			(layers "F.Cu" "F.Mask" "F.Paste")
			(roundrect_rratio 0.25)
			(net 1 "GND")
			(pintype "passive")
		)
		(pad "2" smd roundrect
			(at 1.1 0)
			(size 1.2 1.3)
			(layers "F.Cu" "F.Mask" "F.Paste")
			(roundrect_rratio 0.25)
			(net 35 "VDC")
			(pintype "passive")
		)
	)
	(footprint "antmicro-footprints:SW_KMR211NGLFS_SMD"
		(layer "F.Cu")
		(at 260.574499 144.249 90)
		(property "Reference" "SW3"
			(at -1.181 -3.664499 90)
			(layer "F.SilkS")
			(hide yes)
			(effects
				(font
					(size 0.7 0.7)
					(thickness 0.15)
				)
				(justify left bottom)
			)
		)
		(property "Value" "SW_KMR211NGLFS_SMD"
			(at 0 2.8 90)
			(layer "F.Fab")
			(effects
				(font
					(size 0.7 0.7)
					(thickness 0.15)
				)
				(justify left bottom)
			)
		)
		(property "Datasheet" "http://www.farnell.com/datasheets/2631211.pdf"
			(at 0 0 90)
			(layer "F.Fab")
			(hide yes)
			(effects
				(font
					(size 1.27 1.27)
					(thickness 0.15)
				)
			)
		)
		(property "MPN" "KMR211NGLFS"
			(at 0 0 90)
			(unlocked yes)
			(layer "F.Fab")
			(hide yes)
			(effects
				(font
					(size 1 1)
					(thickness 0.15)
				)
			)
		)
		(property "Manufacturer" "C&K"
			(at 0 0 90)
			(unlocked yes)
			(layer "F.Fab")
			(hide yes)
			(effects
				(font
					(size 1 1)
					(thickness 0.15)
				)
			)
		)
		(property "Author" "Antmicro"
			(at 0 0 90)
			(unlocked yes)
			(layer "F.Fab")
			(hide yes)
			(effects
				(font
					(size 1 1)
					(thickness 0.15)
				)
			)
		)
		(property "License" "Apache-2.0"
			(at 0 0 90)
			(unlocked yes)
			(layer "F.Fab")
			(hide yes)
			(effects
				(font
					(size 1 1)
					(thickness 0.15)
				)
			)
		)
		(sheetname "/DDR5 RDIMM/")
		(sheetfile "ddr5-rdimm.kicad_sch")
		(attr smd)
		(fp_line
			(start 2.101 -1.6)
			(end -2.1 -1.6)
			(stroke
				(width 0.15)
				(type solid)
			)
			(layer "F.SilkS")
		)
		(fp_line
			(start -2.1 -1.6)
			(end -2.1 -1.499)
			(stroke
				(width 0.15)
				(type solid)
			)
			(layer "F.SilkS")
		)
		(fp_line
			(start 2.101 -1.58)
			(end 2.101 -1.459)
			(stroke
				(width 0.15)
				(type solid)
			)
			(layer "F.SilkS")
		)
		(fp_line
			(start 2.101 1.601)
			(end 2.101 1.48)
			(stroke
				(width 0.15)
				(type solid)
			)
			(layer "F.SilkS")
		)
		(fp_line
			(start 2.101 1.601)
			(end -2.1 1.601)
			(stroke
				(width 0.15)
				(type solid)
			)
			(layer "F.SilkS")
		)
		(fp_line
			(start -2.1 1.601)
			(end -2.1 1.48)
			(stroke
				(width 0.15)
				(type solid)
			)
			(layer "F.SilkS")
		)
		(fp_rect
			(start 2.751 1.75)
			(end -2.748 -1.749)
			(stroke
				(width 0.05)
				(type solid)
			)
			(fill no)
			(layer "F.CrtYd")
		)
		(fp_line
			(start 2.101 -1.6)
			(end -2.1 -1.6)
			(stroke
				(width 0.15)
				(type solid)
			)
			(layer "F.Fab")
		)
		(fp_line
			(start -2.1 -1.6)
			(end -2.1 1.601)
			(stroke
				(width 0.15)
				(type solid)
			)
			(layer "F.Fab")
		)
		(fp_line
			(start -0.248 -0.8)
			(end 0.25 -0.8)
			(stroke
				(width 0.15)
				(type solid)
			)
			(layer "F.Fab")
		)
		(fp_line
			(start 0.25 0.802)
			(end -0.248 0.802)
			(stroke
				(width 0.15)
				(type solid)
			)
			(layer "F.Fab")
		)
		(fp_line
			(start 2.101 1.601)
			(end 2.101 -1.6)
			(stroke
				(width 0.15)
				(type solid)
			)
			(layer "F.Fab")
		)
		(fp_line
			(start -2.1 1.601)
			(end 2.101 1.601)
			(stroke
				(width 0.15)
				(type solid)
			)
			(layer "F.Fab")
		)
		(fp_arc
			(start 0.25 -0.8)
			(mid 1.051001 0.001)
			(end 0.25 0.802)
			(stroke
				(width 0.15)
				(type solid)
			)
			(layer "F.Fab")
		)
		(fp_arc
			(start -0.248 0.802)
			(mid -1.050001 0.001)
			(end -0.248 -0.8)
			(stroke
				(width 0.15)
				(type solid)
			)
			(layer "F.Fab")
		)
		(fp_text user "${REFERENCE}"
			(at -3 4.25 90)
			(layer "F.Fab")
			(effects
				(font
					(size 0.7 0.7)
					(thickness 0.15)
				)
				(justify left bottom)
			)
		)
		(fp_text user "Author: Antmicro"
			(at -3 5.5 90)
			(layer "F.Fab")
			(effects
				(font
					(size 0.7 0.7)
					(thickness 0.15)
				)
				(justify left bottom)
			)
		)
		(fp_text user "License: Apache-2.0"
			(at -3 6.75 90)
			(layer "F.Fab")
			(effects
				(font
					(size 0.7 0.7)
					(thickness 0.15)
				)
				(justify left bottom)
			)
		)
		(pad "1" smd rect
			(at -2.048 -0.8 270)
			(size 0.9 1)
			(layers "F.Cu" "F.Mask" "F.Paste")
			(net 1 "GND")
			(pinfunction "1")
			(pintype "passive")
		)
		(pad "2" smd rect
			(at 2.05 -0.8 270)
			(size 0.9 1)
			(layers "F.Cu" "F.Mask" "F.Paste")
			(net 1 "GND")
			(pinfunction "2")
			(pintype "passive")
		)
		(pad "3" smd rect
			(at -2.048 0.802 270)
			(size 0.9 1)
			(layers "F.Cu" "F.Mask" "F.Paste")
			(net 69 "HOT_SWAP_BUTTON")
			(pinfunction "3")
			(pintype "passive")
		)
		(pad "4" smd rect
			(at 2.05 0.802 270)
			(size 0.9 1)
			(layers "F.Cu" "F.Mask" "F.Paste")
			(net 69 "HOT_SWAP_BUTTON")
			(pinfunction "4")
			(pintype "passive")
		)
	)
	(footprint "antmicro-footprints:C_0402_1005Metric"
		(layer "F.Cu")
		(at 152.73 193.5 180)
		(descr "Capacitor SMD 0402")
		(tags "capacitor SMD 0402")
		(property "Reference" "C176"
			(at -3.82 -0.45 0)
			(layer "F.SilkS")
			(effects
				(font
					(size 0.7 0.7)
					(thickness 0.15)
				)
				(justify right bottom)
			)
		)
		(property "Value" "C_100n_0402"
			(at -1.022927 2.155213 0)
			(layer "F.Fab")
			(effects
				(font
					(size 0.7 0.7)
					(thickness 0.15)
				)
				(justify right bottom)
			)
		)
		(property "Datasheet" "https://www.murata.com/products/productdetail?partno=GRM155R61H104KE14%23"
			(at 0 0 180)
			(layer "F.Fab")
			(hide yes)
			(effects
				(font
					(size 1.27 1.27)
					(thickness 0.15)
				)
			)
		)
		(property "Manufacturer" "Murata"
			(at 0 0 180)
			(unlocked yes)
			(layer "F.Fab")
			(hide yes)
			(effects
				(font
					(size 1 1)
					(thickness 0.15)
				)
			)
		)
		(property "MPN" "GRM155R61H104KE14D"
			(at 0 0 180)
			(unlocked yes)
			(layer "F.Fab")
			(hide yes)
			(effects
				(font
					(size 1 1)
					(thickness 0.15)
				)
			)
		)
		(property "Val" "100n"
			(at 0 0 180)
			(unlocked yes)
			(layer "F.Fab")
			(hide yes)
			(effects
				(font
					(size 1 1)
					(thickness 0.15)
				)
			)
		)
		(property "License" "Apache-2.0"
			(at 0 0 180)
			(unlocked yes)
			(layer "F.Fab")
			(hide yes)
			(effects
				(font
					(size 1 1)
					(thickness 0.15)
				)
			)
		)
		(property "Author" "Antmicro"
			(at 0 0 180)
			(unlocked yes)
			(layer "F.Fab")
			(hide yes)
			(effects
				(font
					(size 1 1)
					(thickness 0.15)
				)
			)
		)
		(property "Voltage" "50V"
			(at 0 0 180)
			(unlocked yes)
			(layer "F.Fab")
			(hide yes)
			(effects
				(font
					(size 1 1)
					(thickness 0.15)
				)
			)
		)
		(property "Dielectric" "X5R"
			(at 0 0 180)
			(unlocked yes)
			(layer "F.Fab")
			(hide yes)
			(effects
				(font
					(size 1 1)
					(thickness 0.15)
				)
			)
		)
		(sheetname "/Supply/")
		(sheetfile "supply.kicad_sch")
		(attr smd)
		(fp_rect
			(start -0.925 -0.47)
			(end 0.925 0.47)
			(stroke
				(width 0.05)
				(type default)
			)
			(fill no)
			(layer "F.CrtYd")
		)
		(fp_line
			(start 0.504 0.248)
			(end -0.494 0.248)
			(stroke
				(width 0.15)
				(type solid)
			)
			(layer "F.Fab")
		)
		(fp_line
			(start 0.504 -0.25)
			(end 0.504 0.248)
			(stroke
				(width 0.15)
				(type solid)
			)
			(layer "F.Fab")
		)
		(fp_line
			(start -0.494 0.248)
			(end -0.494 -0.25)
			(stroke
				(width 0.15)
				(type solid)
			)
			(layer "F.Fab")
		)
		(fp_line
			(start -0.494 -0.25)
			(end 0.504 -0.25)
			(stroke
				(width 0.15)
				(type solid)
			)
			(layer "F.Fab")
		)
		(fp_text user "License: Apache-2.0"
			(at -0.939 5.799 180)
			(layer "F.Fab")
			(effects
				(font
					(size 0.7 0.7)
					(thickness 0.15)
				)
				(justify left bottom)
			)
		)
		(fp_text user "${REFERENCE}"
			(at -0.939 4.599 180)
			(layer "F.Fab")
			(effects
				(font
					(size 0.7 0.7)
					(thickness 0.15)
				)
				(justify left bottom)
			)
		)
		(fp_text user "Author: Antmicro"
			(at -0.939 3.399 180)
			(layer "F.Fab")
			(effects
				(font
					(size 0.7 0.7)
					(thickness 0.15)
				)
				(justify left bottom)
			)
		)
		(pad "1" smd roundrect
			(at -0.48 0 180)
			(size 0.59 0.64)
			(layers "F.Cu" "F.Mask" "F.Paste")
			(roundrect_rratio 0.25)
			(net 1 "GND")
			(pintype "passive")
		)
		(pad "2" smd roundrect
			(at 0.48 0 180)
			(size 0.59 0.64)
			(layers "F.Cu" "F.Mask" "F.Paste")
			(roundrect_rratio 0.25)
			(net 324 "/Supply/12V_PCIE_fused")
			(pintype "passive")
		)
	)
	(footprint "antmicro-footprints:C_0402_1005Metric"
		(layer "F.Cu")
		(at 215.659999 179.205 180)
		(descr "Capacitor SMD 0402")
		(tags "capacitor SMD 0402")
		(property "Reference" "C217"
			(at 0.929999 -0.455 0)
			(layer "F.SilkS")
			(effects
				(font
					(size 0.7 0.7)
					(thickness 0.15)
				)
				(justify right bottom)
			)
		)
		(property "Value" "C_4u7_25V_0402"
			(at -1.022927 2.155213 0)
			(layer "F.Fab")
			(effects
				(font
					(size 0.7 0.7)
					(thickness 0.15)
				)
				(justify right bottom)
			)
		)
		(property "Datasheet" "https://www.murata.com/products/productdetail?partno=GRM155C61E475ME15%23"
			(at 0 0 180)
			(layer "F.Fab")
			(hide yes)
			(effects
				(font
					(size 1.27 1.27)
					(thickness 0.15)
				)
			)
		)
		(property "MPN" "GRM155C61E475ME15J"
			(at 0 0 180)
			(unlocked yes)
			(layer "F.Fab")
			(hide yes)
			(effects
				(font
					(size 1 1)
					(thickness 0.15)
				)
			)
		)
		(property "Manufacturer" "Murata"
			(at 0 0 180)
			(unlocked yes)
			(layer "F.Fab")
			(hide yes)
			(effects
				(font
					(size 1 1)
					(thickness 0.15)
				)
			)
		)
		(property "License" "Apache-2.0"
			(at 0 0 180)
			(unlocked yes)
			(layer "F.Fab")
			(hide yes)
			(effects
				(font
					(size 1 1)
					(thickness 0.15)
				)
			)
		)
		(property "Author" "Antmicro"
			(at 0 0 180)
			(unlocked yes)
			(layer "F.Fab")
			(hide yes)
			(effects
				(font
					(size 1 1)
					(thickness 0.15)
				)
			)
		)
		(property "Val" "4u7"
			(at 0 0 180)
			(unlocked yes)
			(layer "F.Fab")
			(hide yes)
			(effects
				(font
					(size 1 1)
					(thickness 0.15)
				)
			)
		)
		(property "Voltage" "25V"
			(at 0 0 180)
			(unlocked yes)
			(layer "F.Fab")
			(hide yes)
			(effects
				(font
					(size 1 1)
					(thickness 0.15)
				)
			)
		)
		(property "Dielectric" "X5S"
			(at 0 0 180)
			(unlocked yes)
			(layer "F.Fab")
			(hide yes)
			(effects
				(font
					(size 1 1)
					(thickness 0.15)
				)
			)
		)
		(sheetname "/Supply/DC-DC VCCINT/")
		(sheetfile "dc-dc-vccint.kicad_sch")
		(attr smd)
		(fp_rect
			(start -0.925 -0.47)
			(end 0.925 0.47)
			(stroke
				(width 0.05)
				(type default)
			)
			(fill no)
			(layer "F.CrtYd")
		)
		(fp_line
			(start 0.504 0.248)
			(end -0.494 0.248)
			(stroke
				(width 0.15)
				(type solid)
			)
			(layer "F.Fab")
		)
		(fp_line
			(start 0.504 -0.25)
			(end 0.504 0.248)
			(stroke
				(width 0.15)
				(type solid)
			)
			(layer "F.Fab")
		)
		(fp_line
			(start -0.494 0.248)
			(end -0.494 -0.25)
			(stroke
				(width 0.15)
				(type solid)
			)
			(layer "F.Fab")
		)
		(fp_line
			(start -0.494 -0.25)
			(end 0.504 -0.25)
			(stroke
				(width 0.15)
				(type solid)
			)
			(layer "F.Fab")
		)
		(fp_text user "Author: Antmicro"
			(at -0.939 3.399 180)
			(layer "F.Fab")
			(effects
				(font
					(size 0.7 0.7)
					(thickness 0.15)
				)
				(justify left bottom)
			)
		)
		(fp_text user "${REFERENCE}"
			(at -0.939 4.599 180)
			(layer "F.Fab")
			(effects
				(font
					(size 0.7 0.7)
					(thickness 0.15)
				)
				(justify left bottom)
			)
		)
		(fp_text user "License: Apache-2.0"
			(at -0.939 5.799 180)
			(layer "F.Fab")
			(effects
				(font
					(size 0.7 0.7)
					(thickness 0.15)
				)
				(justify left bottom)
			)
		)
		(pad "1" smd roundrect
			(at -0.48 0 180)
			(size 0.59 0.64)
			(layers "F.Cu" "F.Mask" "F.Paste")
			(roundrect_rratio 0.25)
			(net 1 "GND")
			(pintype "passive")
		)
		(pad "2" smd roundrect
			(at 0.48 0 180)
			(size 0.59 0.64)
			(layers "F.Cu" "F.Mask" "F.Paste")
			(roundrect_rratio 0.25)
			(net 222 "Net-(U4-V_{DRV})")
			(pintype "passive")
		)
	)
	(footprint "antmicro-footprints:R_0402_1005Metric"
		(layer "F.Cu")
		(at 108.824499 141.649 180)
		(descr "Resistor SMD 0402")
		(tags "resistor SMD 0402")
		(property "Reference" "R68"
			(at -3.175501 -0.626 0)
			(layer "F.SilkS")
			(effects
				(font
					(size 0.7 0.7)
					(thickness 0.15)
				)
				(justify right bottom)
			)
		)
		(property "Value" "R_5k11_0402"
			(at -1.011843 1.772047 0)
			(layer "F.Fab")
			(effects
				(font
					(size 0.7 0.7)
					(thickness 0.15)
				)
				(justify right bottom)
			)
		)
		(property "Datasheet" "https://www.bourns.com/docs/product-datasheets/cr.pdf"
			(at 0 0 180)
			(layer "F.Fab")
			(hide yes)
			(effects
				(font
					(size 1.27 1.27)
					(thickness 0.15)
				)
			)
		)
		(property "Manufacturer" "Bourns"
			(at 0 0 180)
			(unlocked yes)
			(layer "F.Fab")
			(hide yes)
			(effects
				(font
					(size 1 1)
					(thickness 0.15)
				)
			)
		)
		(property "MPN" "CR0402-FX-5111GLF"
			(at 0 0 180)
			(unlocked yes)
			(layer "F.Fab")
			(hide yes)
			(effects
				(font
					(size 1 1)
					(thickness 0.15)
				)
			)
		)
		(property "Val" "5k11"
			(at 0 0 180)
			(unlocked yes)
			(layer "F.Fab")
			(hide yes)
			(effects
				(font
					(size 1 1)
					(thickness 0.15)
				)
			)
		)
		(property "License" "Apache-2.0"
			(at 0 0 180)
			(unlocked yes)
			(layer "F.Fab")
			(hide yes)
			(effects
				(font
					(size 1 1)
					(thickness 0.15)
				)
			)
		)
		(property "Author" "Antmicro"
			(at 0 0 180)
			(unlocked yes)
			(layer "F.Fab")
			(hide yes)
			(effects
				(font
					(size 1 1)
					(thickness 0.15)
				)
			)
		)
		(property "Tolerance" "1%"
			(at 0 0 180)
			(unlocked yes)
			(layer "F.Fab")
			(hide yes)
			(effects
				(font
					(size 1 1)
					(thickness 0.15)
				)
			)
		)
		(sheetname "/Debug FTDI + VNA/")
		(sheetfile "debug-ftdi.kicad_sch")
		(attr smd)
		(fp_rect
			(start -0.925 -0.47)
			(end 0.925 0.47)
			(stroke
				(width 0.05)
				(type default)
			)
			(fill no)
			(layer "F.CrtYd")
		)
		(fp_rect
			(start -0.5 -0.25)
			(end 0.5 0.25)
			(stroke
				(width 0.15)
				(type solid)
			)
			(fill no)
			(layer "F.Fab")
		)
		(fp_text user "Author: Antmicro"
			(at -0.95 4.169 180)
			(layer "F.Fab")
			(effects
				(font
					(size 0.7 0.7)
					(thickness 0.15)
				)
				(justify left bottom)
			)
		)
		(fp_text user "License: Apache-2.0"
			(at -0.95 5.169 180)
			(layer "F.Fab")
			(effects
				(font
					(size 0.7 0.7)
					(thickness 0.15)
				)
				(justify left bottom)
			)
		)
		(fp_text user "${REFERENCE}"
			(at -0.95 3.168 180)
			(layer "F.Fab")
			(effects
				(font
					(size 0.7 0.7)
					(thickness 0.15)
				)
				(justify left bottom)
			)
		)
		(pad "1" smd roundrect
			(at -0.48 0 180)
			(size 0.59 0.64)
			(layers "F.Cu" "F.Mask" "F.Paste")
			(roundrect_rratio 0.25)
			(net 1 "GND")
			(pintype "passive")
		)
		(pad "2" smd roundrect
			(at 0.48 0 180)
			(size 0.59 0.64)
			(layers "F.Cu" "F.Mask" "F.Paste")
			(roundrect_rratio 0.25)
			(net 363 "/Debug FTDI + VNA/CC1")
			(pintype "passive")
		)
	)
	(footprint "antmicro-footprints:VSSOP-8_2.3x2mm_P0.5mm"
		(layer "F.Cu")
		(at 247.257 185.507 180)
		(property "Reference" "U49"
			(at -0.218 1.433 0)
			(layer "F.SilkS")
			(effects
				(font
					(size 0.7 0.7)
					(thickness 0.15)
				)
				(justify right bottom)
			)
		)
		(property "Value" "TCA39306_VSSOP"
			(at 0 2.258 0)
			(layer "F.Fab")
			(effects
				(font
					(size 0.7 0.7)
					(thickness 0.15)
				)
				(justify right bottom)
			)
		)
		(property "Datasheet" "https://www.ti.com/lit/ds/symlink/tca39306.pdf?ts=1630428611843&ref_url=https%253A%252F%252Fwww.ti.com%252Fproduct%252FTCA39306"
			(at 0 0 180)
			(layer "F.Fab")
			(hide yes)
			(effects
				(font
					(size 1.27 1.27)
					(thickness 0.15)
				)
			)
		)
		(property "MPN" "TCA39306DCUR"
			(at 0 0 180)
			(unlocked yes)
			(layer "F.Fab")
			(hide yes)
			(effects
				(font
					(size 1 1)
					(thickness 0.15)
				)
			)
		)
		(property "Manufacturer" "Texas Instruments"
			(at 0 0 180)
			(unlocked yes)
			(layer "F.Fab")
			(hide yes)
			(effects
				(font
					(size 1 1)
					(thickness 0.15)
				)
			)
		)
		(property "Author" "Antmicro"
			(at 0 0 180)
			(unlocked yes)
			(layer "F.Fab")
			(hide yes)
			(effects
				(font
					(size 1 1)
					(thickness 0.15)
				)
			)
		)
		(property "License" "Apache-2.0"
			(at 0 0 180)
			(unlocked yes)
			(layer "F.Fab")
			(hide yes)
			(effects
				(font
					(size 1 1)
					(thickness 0.15)
				)
			)
		)
		(sheetname "/I^{2}C + I3C/")
		(sheetfile "i2c.kicad_sch")
		(attr smd)
		(fp_line
			(start 0.825 1.007)
			(end -0.82 1.007)
			(stroke
				(width 0.15)
				(type solid)
			)
			(layer "F.SilkS")
		)
		(fp_line
			(start -0.82 -0.992)
			(end 0.825 -0.992)
			(stroke
				(width 0.15)
				(type solid)
			)
			(layer "F.SilkS")
		)
		(fp_circle
			(center -1.402 -1.192)
			(end -1.352 -1.192)
			(stroke
				(width 0.15)
				(type solid)
			)
			(fill yes)
			(layer "F.SilkS")
		)
		(fp_rect
			(start 1.8 1.35)
			(end -1.8 -1.35)
			(stroke
				(width 0.05)
				(type solid)
			)
			(fill no)
			(layer "F.CrtYd")
		)
		(fp_line
			(start -0.7 -0.99)
			(end -1.14 -0.55)
			(stroke
				(width 0.15)
				(type solid)
			)
			(layer "F.Fab")
		)
		(fp_rect
			(start -1.147 -0.992)
			(end 1.151 1.007)
			(stroke
				(width 0.15)
				(type solid)
			)
			(fill no)
			(layer "F.Fab")
		)
		(fp_text user "License: Apache-2.0"
			(at -1.8 6.408 180)
			(layer "F.Fab")
			(effects
				(font
					(size 0.7 0.7)
					(thickness 0.15)
				)
				(justify left bottom)
			)
		)
		(fp_text user "${REFERENCE}"
			(at -1.8 4.006 180)
			(layer "F.Fab")
			(effects
				(font
					(size 0.7 0.7)
					(thickness 0.15)
				)
				(justify left bottom)
			)
		)
		(fp_text user "Author: Antmicro"
			(at -1.8 5.208 180)
			(layer "F.Fab")
			(effects
				(font
					(size 0.7 0.7)
					(thickness 0.15)
				)
				(justify left bottom)
			)
		)
		(pad "1" smd rect
			(at -1.372 -0.742 180)
			(size 0.75 0.4)
			(layers "F.Cu" "F.Mask" "F.Paste")
			(net 1 "GND")
			(pinfunction "GND")
			(pintype "power_in")
		)
		(pad "2" smd rect
			(at -1.372 -0.244 180)
			(size 0.75 0.3)
			(layers "F.Cu" "F.Mask" "F.Paste")
			(net 775 "Net-(Q24-S)")
			(pinfunction "Vref1")
			(pintype "power_in")
		)
		(pad "3" smd rect
			(at -1.372 0.256 180)
			(size 0.75 0.3)
			(layers "F.Cu" "F.Mask" "F.Paste")
			(net 369 "/I^{2}C + I3C/I3C_EXT.SCL")
			(pinfunction "SCL1")
			(pintype "bidirectional")
		)
		(pad "4" smd rect
			(at -1.372 0.757 180)
			(size 0.75 0.4)
			(layers "F.Cu" "F.Mask" "F.Paste")
			(net 368 "/I^{2}C + I3C/I3C_EXT.SDA")
			(pinfunction "SDA1")
			(pintype "bidirectional")
		)
		(pad "5" smd rect
			(at 1.377 0.757 180)
			(size 0.75 0.4)
			(layers "F.Cu" "F.Mask" "F.Paste")
			(net 528 "/FPGA banks HD/FPGA_I3C.SDA")
			(pinfunction "SDA2")
			(pintype "bidirectional")
		)
		(pad "6" smd rect
			(at 1.377 0.256 180)
			(size 0.75 0.3)
			(layers "F.Cu" "F.Mask" "F.Paste")
			(net 771 "/FPGA banks HD/FPGA_I3C.SCL")
			(pinfunction "SCL2")
			(pintype "bidirectional")
		)
		(pad "7" smd rect
			(at 1.377 -0.244 180)
			(size 0.75 0.3)
			(layers "F.Cu" "F.Mask" "F.Paste")
			(net 774 "Net-(U49-EN)")
			(pinfunction "Vref2")
			(pintype "power_in")
		)
		(pad "8" smd rect
			(at 1.377 -0.742 180)
			(size 0.75 0.4)
			(layers "F.Cu" "F.Mask" "F.Paste")
			(net 774 "Net-(U49-EN)")
			(pinfunction "EN")
			(pintype "input")
		)
	)
	(footprint "antmicro-footprints:C_0805_2012Metric"
		(layer "F.Cu")
		(at 219.325 185.8)
		(descr "Capacitor SMD 0805")
		(tags "capacitor SMD 0805")
		(property "Reference" "C21"
			(at -4.475001 0.470001 0)
			(layer "F.SilkS")
			(effects
				(font
					(size 0.7 0.7)
					(thickness 0.15)
				)
				(justify left bottom)
			)
		)
		(property "Value" "C_22u_25V_0805"
			(at -2.055717 1.963152 0)
			(layer "F.Fab")
			(effects
				(font
					(size 0.7 0.7)
					(thickness 0.15)
				)
				(justify left bottom)
			)
		)
		(property "Datasheet" "https://product.samsungsem.com/mlcc/CL21A226MAYNNN.do"
			(at 0 0 0)
			(layer "F.Fab")
			(hide yes)
			(effects
				(font
					(size 1.27 1.27)
					(thickness 0.15)
				)
			)
		)
		(property "MPN" "CL21A226MAYNNNE"
			(at 0 0 0)
			(unlocked yes)
			(layer "F.Fab")
			(hide yes)
			(effects
				(font
					(size 1 1)
					(thickness 0.15)
				)
			)
		)
		(property "Manufacturer" "Samsung Electro-Mechanics"
			(at 0 0 0)
			(unlocked yes)
			(layer "F.Fab")
			(hide yes)
			(effects
				(font
					(size 1 1)
					(thickness 0.15)
				)
			)
		)
		(property "License" "Apache-2.0"
			(at 0 0 0)
			(unlocked yes)
			(layer "F.Fab")
			(hide yes)
			(effects
				(font
					(size 1 1)
					(thickness 0.15)
				)
			)
		)
		(property "Author" "Antmicro"
			(at 0 0 0)
			(unlocked yes)
			(layer "F.Fab")
			(hide yes)
			(effects
				(font
					(size 1 1)
					(thickness 0.15)
				)
			)
		)
		(property "Val" "22u"
			(at 0 0 0)
			(unlocked yes)
			(layer "F.Fab")
			(hide yes)
			(effects
				(font
					(size 1 1)
					(thickness 0.15)
				)
			)
		)
		(property "Voltage" "25V"
			(at 0 0 0)
			(unlocked yes)
			(layer "F.Fab")
			(hide yes)
			(effects
				(font
					(size 1 1)
					(thickness 0.15)
				)
			)
		)
		(property "Dielectric" "X5R"
			(at 0 0 0)
			(unlocked yes)
			(layer "F.Fab")
			(hide yes)
			(effects
				(font
					(size 1 1)
					(thickness 0.15)
				)
			)
		)
		(property "Public" "False"
			(at 0 0 0)
			(unlocked yes)
			(layer "F.Fab")
			(hide yes)
			(effects
				(font
					(size 1 1)
					(thickness 0.15)
				)
			)
		)
		(sheetname "/Supply/DC-DC VCCINT/")
		(sheetfile "dc-dc-vccint.kicad_sch")
		(attr smd)
		(fp_line
			(start -0.3 -0.7)
			(end 0.3 -0.7)
			(stroke
				(width 0.15)
				(type solid)
			)
			(layer "F.SilkS")
		)
		(fp_line
			(start -0.3 0.7)
			(end 0.3 0.7)
			(stroke
				(width 0.15)
				(type solid)
			)
			(layer "F.SilkS")
		)
		(fp_rect
			(start 1.95 -0.9)
			(end -1.95 0.9)
			(stroke
				(width 0.05)
				(type default)
			)
			(fill no)
			(layer "F.CrtYd")
		)
		(fp_rect
			(start -0.95 -0.675)
			(end 0.95 0.675)
			(stroke
				(width 0.15)
				(type solid)
			)
			(fill no)
			(layer "F.Fab")
		)
		(fp_text user "${REFERENCE}"
			(at -1.9 3.947 0)
			(layer "F.Fab")
			(effects
				(font
					(size 0.7 0.7)
					(thickness 0.15)
				)
				(justify left bottom)
			)
		)
		(fp_text user "License: Apache-2.0"
			(at -1.9 4.947 0)
			(layer "F.Fab")
			(effects
				(font
					(size 0.7 0.7)
					(thickness 0.15)
				)
				(justify left bottom)
			)
		)
		(fp_text user "Author: Antmicro"
			(at -1.9 5.947 0)
			(layer "F.Fab")
			(effects
				(font
					(size 0.7 0.7)
					(thickness 0.15)
				)
				(justify left bottom)
			)
		)
		(pad "1" smd roundrect
			(at -1.1 0)
			(size 1.2 1.3)
			(layers "F.Cu" "F.Mask" "F.Paste")
			(roundrect_rratio 0.25)
			(net 1 "GND")
			(pintype "passive")
		)
		(pad "2" smd roundrect
			(at 1.1 0)
			(size 1.2 1.3)
			(layers "F.Cu" "F.Mask" "F.Paste")
			(roundrect_rratio 0.25)
			(net 35 "VDC")
			(pintype "passive")
		)
	)
	(footprint "antmicro-footprints:SC70-3"
		(layer "F.Cu")
		(at 118.1 115.1 90)
		(property "Reference" "Q3"
			(at -0.425 -0.775 180)
			(layer "F.SilkS")
			(effects
				(font
					(size 0.7 0.7)
					(thickness 0.15)
				)
				(justify left bottom)
			)
		)
		(property "Value" "BSS138PW"
			(at 0 2.3 90)
			(layer "F.Fab")
			(effects
				(font
					(size 0.7 0.7)
					(thickness 0.15)
				)
				(justify left bottom)
			)
		)
		(property "Datasheet" "https://assets.nexperia.com/documents/data-sheet/BSS138PW.pdf"
			(at 0 0 90)
			(layer "F.Fab")
			(hide yes)
			(effects
				(font
					(size 1.27 1.27)
					(thickness 0.15)
				)
			)
		)
		(property "MPN" "BSS138PW"
			(at 0 0 90)
			(unlocked yes)
			(layer "F.Fab")
			(hide yes)
			(effects
				(font
					(size 1 1)
					(thickness 0.15)
				)
			)
		)
		(property "Manufacturer" "Nexperia"
			(at 0 0 90)
			(unlocked yes)
			(layer "F.Fab")
			(hide yes)
			(effects
				(font
					(size 1 1)
					(thickness 0.15)
				)
			)
		)
		(property "Author" "Antmicro"
			(at 0 0 90)
			(unlocked yes)
			(layer "F.Fab")
			(hide yes)
			(effects
				(font
					(size 1 1)
					(thickness 0.15)
				)
			)
		)
		(property "License" "Apache-2.0"
			(at 0 0 90)
			(unlocked yes)
			(layer "F.Fab")
			(hide yes)
			(effects
				(font
					(size 1 1)
					(thickness 0.15)
				)
			)
		)
		(sheetname "/FPGA Config/")
		(sheetfile "fpga-config.kicad_sch")
		(attr smd)
		(fp_line
			(start -0.3 -1)
			(end 0.627 -0.999)
			(stroke
				(width 0.15)
				(type solid)
			)
			(layer "F.SilkS")
		)
		(fp_line
			(start 0.627 -0.6)
			(end 0.627 -0.999)
			(stroke
				(width 0.15)
				(type solid)
			)
			(layer "F.SilkS")
		)
		(fp_line
			(start 0.627 0.6)
			(end 0.627 1.001)
			(stroke
				(width 0.15)
				(type solid)
			)
			(layer "F.SilkS")
		)
		(fp_line
			(start -0.3 1)
			(end 0.627 1.001)
			(stroke
				(width 0.15)
				(type solid)
			)
			(layer "F.SilkS")
		)
		(fp_line
			(start 0.9 -1.3)
			(end 0.9 -0.4)
			(stroke
				(width 0.05)
				(type solid)
			)
			(layer "F.CrtYd")
		)
		(fp_line
			(start -0.9 -1.3)
			(end 0.9 -1.3)
			(stroke
				(width 0.05)
				(type solid)
			)
			(layer "F.CrtYd")
		)
		(fp_line
			(start -0.9 -1.3)
			(end -0.9 -1)
			(stroke
				(width 0.05)
				(type solid)
			)
			(layer "F.CrtYd")
		)
		(fp_line
			(start -0.9 -1)
			(end -1.4 -1)
			(stroke
				(width 0.05)
				(type solid)
			)
			(layer "F.CrtYd")
		)
		(fp_line
			(start 1.4 -0.4)
			(end 1.4 0.4)
			(stroke
				(width 0.05)
				(type solid)
			)
			(layer "F.CrtYd")
		)
		(fp_line
			(start 0.9 -0.4)
			(end 1.4 -0.4)
			(stroke
				(width 0.05)
				(type solid)
			)
			(layer "F.CrtYd")
		)
		(fp_line
			(start 1.4 0.4)
			(end 0.9 0.4)
			(stroke
				(width 0.05)
				(type solid)
			)
			(layer "F.CrtYd")
		)
		(fp_line
			(start 0.9 0.4)
			(end 0.9 1.3)
			(stroke
				(width 0.05)
				(type solid)
			)
			(layer "F.CrtYd")
		)
		(fp_line
			(start -0.9 1)
			(end -1.4 1)
			(stroke
				(width 0.05)
				(type solid)
			)
			(layer "F.CrtYd")
		)
		(fp_line
			(start -1.4 1)
			(end -1.4 -1)
			(stroke
				(width 0.05)
				(type solid)
			)
			(layer "F.CrtYd")
		)
		(fp_line
			(start 0.9 1.3)
			(end -0.9 1.3)
			(stroke
				(width 0.05)
				(type solid)
			)
			(layer "F.CrtYd")
		)
		(fp_line
			(start -0.9 1.3)
			(end -0.9 1)
			(stroke
				(width 0.05)
				(type solid)
			)
			(layer "F.CrtYd")
		)
		(fp_rect
			(start -0.623 -0.999)
			(end 0.627 1.001)
			(stroke
				(width 0.15)
				(type solid)
			)
			(fill no)
			(layer "F.Fab")
		)
		(fp_text user "License: Apache-2.0"
			(at -1.45 6.782 90)
			(layer "F.Fab")
			(effects
				(font
					(size 0.7 0.7)
					(thickness 0.15)
				)
				(justify left bottom)
			)
		)
		(fp_text user "${REFERENCE}"
			(at -1.45 4.783 90)
			(layer "F.Fab")
			(effects
				(font
					(size 0.7 0.7)
					(thickness 0.15)
				)
				(justify left bottom)
			)
		)
		(fp_text user "Author: Antmicro"
			(at -1.45 5.782 90)
			(layer "F.Fab")
			(effects
				(font
					(size 0.7 0.7)
					(thickness 0.15)
				)
				(justify left bottom)
			)
		)
		(pad "1" smd rect
			(at -1.051 -0.65 180)
			(size 0.6 0.6)
			(layers "F.Cu" "F.Mask" "F.Paste")
			(net 340 "/FPGA Config/DONE")
			(pinfunction "G")
			(pintype "passive")
		)
		(pad "2" smd rect
			(at -1.051 0.65 180)
			(size 0.6 0.6)
			(layers "F.Cu" "F.Mask" "F.Paste")
			(net 1 "GND")
			(pinfunction "S")
			(pintype "passive")
		)
		(pad "3" smd rect
			(at 1.05 0 180)
			(size 0.6 0.6)
			(layers "F.Cu" "F.Mask" "F.Paste")
			(net 271 "Net-(Q3-D)")
			(pinfunction "D")
			(pintype "passive")
		)
	)
	(footprint "antmicro-footprints:L_0402_1005Metric"
		(layer "F.Cu")
		(at 121.025 150.61 180)
		(descr "Inductor SMD 0402")
		(tags "Inductor SMD 0402")
		(property "Reference" "L5"
			(at -5.375 -0.435 0)
			(layer "F.SilkS")
			(effects
				(font
					(size 0.7 0.7)
					(thickness 0.15)
				)
				(justify right bottom)
			)
		)
		(property "Value" "L_20n_0.35A_0402"
			(at 0 1.4 0)
			(layer "F.Fab")
			(effects
				(font
					(size 0.7 0.7)
					(thickness 0.15)
				)
				(justify right bottom)
			)
		)
		(property "Datasheet" "https://product.tdk.com/system/files/dam/doc/product/inductor/inductor/smd/catalog/inductor_automotive_high-frequency_mlg1005s_en.pdf?ref_disty=mouser"
			(at 0 0 180)
			(layer "F.Fab")
			(hide yes)
			(effects
				(font
					(size 1.27 1.27)
					(thickness 0.15)
				)
			)
		)
		(property "Val" "20n/0.35A"
			(at 0 0 180)
			(unlocked yes)
			(layer "F.Fab")
			(hide yes)
			(effects
				(font
					(size 1 1)
					(thickness 0.15)
				)
			)
		)
		(property "Manufacturer" "TDK"
			(at 0 0 180)
			(unlocked yes)
			(layer "F.Fab")
			(hide yes)
			(effects
				(font
					(size 1 1)
					(thickness 0.15)
				)
			)
		)
		(property "MPN" "MLG1005S20NJTD25"
			(at 0 0 180)
			(unlocked yes)
			(layer "F.Fab")
			(hide yes)
			(effects
				(font
					(size 1 1)
					(thickness 0.15)
				)
			)
		)
		(property "ISat" ""
			(at 0 0 180)
			(unlocked yes)
			(layer "F.Fab")
			(hide yes)
			(effects
				(font
					(size 1 1)
					(thickness 0.15)
				)
			)
		)
		(property "IMax" "0.35 A"
			(at 0 0 180)
			(unlocked yes)
			(layer "F.Fab")
			(hide yes)
			(effects
				(font
					(size 1 1)
					(thickness 0.15)
				)
			)
		)
		(property "Size" "1.0x0.5"
			(at 0 0 180)
			(unlocked yes)
			(layer "F.Fab")
			(hide yes)
			(effects
				(font
					(size 1 1)
					(thickness 0.15)
				)
			)
		)
		(property "Author" "Antmicro"
			(at 0 0 180)
			(unlocked yes)
			(layer "F.Fab")
			(hide yes)
			(effects
				(font
					(size 1 1)
					(thickness 0.15)
				)
			)
		)
		(property "License" "Apache-2.0"
			(at 0 0 180)
			(unlocked yes)
			(layer "F.Fab")
			(hide yes)
			(effects
				(font
					(size 1 1)
					(thickness 0.15)
				)
			)
		)
		(sheetname "/HDMI + SD Card/")
		(sheetfile "hdmi-sd-card.kicad_sch")
		(attr smd)
		(fp_rect
			(start -0.925 -0.47)
			(end 0.925 0.47)
			(stroke
				(width 0.05)
				(type default)
			)
			(fill no)
			(layer "F.CrtYd")
		)
		(fp_rect
			(start -0.499 -0.249)
			(end 0.499 0.249)
			(stroke
				(width 0.15)
				(type solid)
			)
			(fill no)
			(layer "F.Fab")
		)
		(fp_text user "Author: Antmicro"
			(at -0.932 4.17 180)
			(layer "F.Fab")
			(effects
				(font
					(size 0.7 0.7)
					(thickness 0.15)
				)
				(justify left bottom)
			)
		)
		(fp_text user "License: Apache-2.0"
			(at -0.932 5.17 180)
			(layer "F.Fab")
			(effects
				(font
					(size 0.7 0.7)
					(thickness 0.15)
				)
				(justify left bottom)
			)
		)
		(fp_text user "${REFERENCE}"
			(at -0.932 3.168 180)
			(layer "F.Fab")
			(effects
				(font
					(size 0.7 0.7)
					(thickness 0.15)
				)
				(justify left bottom)
			)
		)
		(pad "1" smd roundrect
			(at -0.48 0 180)
			(size 0.59 0.64)
			(layers "F.Cu" "F.Mask" "F.Paste")
			(roundrect_rratio 0.25)
			(net 346 "/FPGA MGT Interface/HDMI_IN.D1_N")
			(pintype "passive")
		)
		(pad "2" smd roundrect
			(at 0.48 0 180)
			(size 0.59 0.64)
			(layers "F.Cu" "F.Mask" "F.Paste")
			(roundrect_rratio 0.25)
			(net 675 "Net-(L5-Pad2)")
			(pintype "passive")
		)
	)
	(footprint "antmicro-footprints:VQFN-48_7x7mm_P0.5mm_EP4.1x4.1mm"
		(layer "F.Cu")
		(at 124.326 181.303 180)
		(property "Reference" "U38"
			(at 6.501 -4.347 0)
			(unlocked yes)
			(layer "F.SilkS")
			(effects
				(font
					(size 0.7 0.7)
					(thickness 0.15)
				)
				(justify left bottom)
			)
		)
		(property "Value" "SN65DP159RGZR"
			(at 0 5.3 180)
			(unlocked yes)
			(layer "F.Fab")
			(effects
				(font
					(size 0.7 0.7)
					(thickness 0.15)
				)
				(justify left bottom)
			)
		)
		(property "Datasheet" "https://www.ti.com/lit/ds/symlink/sn75dp159.pdf?ts=1728245191743&ref_url=https%253A%252F%252Fwww.mouser.de%252F"
			(at 0 0 180)
			(layer "F.Fab")
			(hide yes)
			(effects
				(font
					(size 1.27 1.27)
					(thickness 0.15)
				)
			)
		)
		(property "MPN" "SN65DP159RGZR "
			(at 0 0 180)
			(unlocked yes)
			(layer "F.Fab")
			(hide yes)
			(effects
				(font
					(size 1 1)
					(thickness 0.15)
				)
			)
		)
		(property "Manufacturer" "Texas Instruments"
			(at 0 0 180)
			(unlocked yes)
			(layer "F.Fab")
			(hide yes)
			(effects
				(font
					(size 1 1)
					(thickness 0.15)
				)
			)
		)
		(property "Author" "Antmicro"
			(at 0 0 180)
			(unlocked yes)
			(layer "F.Fab")
			(hide yes)
			(effects
				(font
					(size 1 1)
					(thickness 0.15)
				)
			)
		)
		(property "License" "Apache-2.0"
			(at 0 0 180)
			(unlocked yes)
			(layer "F.Fab")
			(hide yes)
			(effects
				(font
					(size 1 1)
					(thickness 0.15)
				)
			)
		)
		(sheetname "/HDMI + SD Card/")
		(sheetfile "hdmi-sd-card.kicad_sch")
		(attr smd)
		(fp_line
			(start 3.956 3.956)
			(end 3.956 3.218)
			(stroke
				(width 0.15)
				(type solid)
			)
			(layer "F.SilkS")
		)
		(fp_line
			(start 3.956 3.956)
			(end 3.219 3.956)
			(stroke
				(width 0.15)
				(type solid)
			)
			(layer "F.SilkS")
		)
		(fp_line
			(start 3.956 -3.218)
			(end 3.956 -3.956)
			(stroke
				(width 0.15)
				(type solid)
			)
			(layer "F.SilkS")
		)
		(fp_line
			(start 3.956 -3.956)
			(end 3.219 -3.956)
			(stroke
				(width 0.15)
				(type solid)
			)
			(layer "F.SilkS")
		)
		(fp_line
			(start -3.219 3.956)
			(end -3.956 3.956)
			(stroke
				(width 0.15)
				(type solid)
			)
			(layer "F.SilkS")
		)
		(fp_line
			(start -3.219 -3.956)
			(end -3.956 -3.956)
			(stroke
				(width 0.15)
				(type solid)
			)
			(layer "F.SilkS")
		)
		(fp_line
			(start -3.956 3.956)
			(end -3.956 3.218)
			(stroke
				(width 0.15)
				(type solid)
			)
			(layer "F.SilkS")
		)
		(fp_line
			(start -3.956 -3.218)
			(end -3.956 -3.956)
			(stroke
				(width 0.15)
				(type solid)
			)
			(layer "F.SilkS")
		)
		(fp_circle
			(center -4.18 -3.05)
			(end -4.13 -3.05)
			(stroke
				(width 0.15)
				(type solid)
			)
			(fill yes)
			(layer "F.SilkS")
		)
		(fp_rect
			(start -4.3 -4.3)
			(end 4.3 4.3)
			(stroke
				(width 0.05)
				(type solid)
			)
			(fill no)
			(layer "F.CrtYd")
		)
		(fp_line
			(start 3.575 3.575)
			(end 3.575 -3.575)
			(stroke
				(width 0.15)
				(type solid)
			)
			(layer "B.Fab")
		)
		(fp_line
			(start 3.575 3.575)
			(end -3.575 3.575)
			(stroke
				(width 0.15)
				(type solid)
			)
			(layer "B.Fab")
		)
		(fp_line
			(start 3.575 -3.575)
			(end -3.575 -3.575)
			(stroke
				(width 0.15)
				(type solid)
			)
			(layer "B.Fab")
		)
		(fp_line
			(start -3.575 3.575)
			(end -3.575 -3.575)
			(stroke
				(width 0.15)
				(type solid)
			)
			(layer "B.Fab")
		)
		(fp_line
			(start -3.575 -2.305)
			(end -2.305 -3.575)
			(stroke
				(width 0.15)
				(type solid)
			)
			(layer "B.Fab")
		)
		(fp_text user "License: Apache-2.0"
			(at -5.13 9.18 180)
			(layer "F.Fab")
			(effects
				(font
					(size 0.7 0.7)
					(thickness 0.15)
				)
				(justify left bottom)
			)
		)
		(fp_text user "${REFERENCE}"
			(at -5.13 6.78 180)
			(layer "F.Fab")
			(effects
				(font
					(size 0.7 0.7)
					(thickness 0.15)
				)
				(justify left bottom)
			)
		)
		(fp_text user "Author: Antmicro"
			(at -5.13 7.98 180)
			(layer "F.Fab")
			(effects
				(font
					(size 0.7 0.7)
					(thickness 0.15)
				)
				(justify left bottom)
			)
		)
		(pad "1" smd roundrect
			(at -3.475 -2.75 90)
			(size 0.28 0.85)
			(layers "F.Cu" "F.Mask" "F.Paste")
			(roundrect_rratio 0.1785714286)
			(net 707 "/HDMI + SD Card/SWAP{slash}POL")
			(pinfunction "SWAP/POL")
			(pintype "input")
		)
		(pad "2" smd roundrect
			(at -3.475 -2.25 90)
			(size 0.28 0.85)
			(layers "F.Cu" "F.Mask" "F.Paste")
			(roundrect_rratio 0.1785714286)
			(net 294 "/FPGA MGT Interface/HDMI_OUT.D2_P")
			(pinfunction "IN_D2_P")
			(pintype "input")
		)
		(pad "3" smd roundrect
			(at -3.475 -1.75 90)
			(size 0.28 0.85)
			(layers "F.Cu" "F.Mask" "F.Paste")
			(roundrect_rratio 0.1785714286)
			(net 295 "/FPGA MGT Interface/HDMI_OUT.D2_N")
			(pinfunction "IN_D2_N")
			(pintype "input")
		)
		(pad "4" smd roundrect
			(at -3.475 -1.25 90)
			(size 0.28 0.85)
			(layers "F.Cu" "F.Mask" "F.Paste")
			(roundrect_rratio 0.1785714286)
			(net 549 "HDMI_OUT_HPD")
			(pinfunction "HPD_SRC")
			(pintype "output")
		)
		(pad "5" smd roundrect
			(at -3.475 -0.75 90)
			(size 0.28 0.85)
			(layers "F.Cu" "F.Mask" "F.Paste")
			(roundrect_rratio 0.1785714286)
			(net 267 "/FPGA MGT Interface/HDMI_OUT.D1_P")
			(pinfunction "IN_D1_P")
			(pintype "input")
		)
		(pad "6" smd roundrect
			(at -3.475 -0.25 90)
			(size 0.28 0.85)
			(layers "F.Cu" "F.Mask" "F.Paste")
			(roundrect_rratio 0.1785714286)
			(net 290 "/FPGA MGT Interface/HDMI_OUT.D1_N")
			(pinfunction "IN_D1_N")
			(pintype "input")
		)
		(pad "7" smd roundrect
			(at -3.475 0.25 90)
			(size 0.28 0.85)
			(layers "F.Cu" "F.Mask" "F.Paste")
			(roundrect_rratio 0.1785714286)
			(net 1 "GND")
			(pinfunction "GND")
			(pintype "power_in")
		)
		(pad "8" smd roundrect
			(at -3.475 0.75 90)
			(size 0.28 0.85)
			(layers "F.Cu" "F.Mask" "F.Paste")
			(roundrect_rratio 0.1785714286)
			(net 246 "/FPGA MGT Interface/HDMI_OUT.D0_P")
			(pinfunction "IN_D0_P")
			(pintype "input")
		)
		(pad "9" smd roundrect
			(at -3.475 1.25 90)
			(size 0.28 0.85)
			(layers "F.Cu" "F.Mask" "F.Paste")
			(roundrect_rratio 0.1785714286)
			(net 248 "/FPGA MGT Interface/HDMI_OUT.D0_N")
			(pinfunction "IN_D0_N")
			(pintype "input")
		)
		(pad "10" smd roundrect
			(at -3.475 1.75 90)
			(size 0.28 0.85)
			(layers "F.Cu" "F.Mask" "F.Paste")
			(roundrect_rratio 0.1785714286)
			(net 710 "/HDMI + SD Card/I2C_EN{slash}PIN")
			(pinfunction "I2C_EN/PIN")
			(pintype "input")
		)
		(pad "11" smd roundrect
			(at -3.475 2.25 90)
			(size 0.28 0.85)
			(layers "F.Cu" "F.Mask" "F.Paste")
			(roundrect_rratio 0.1785714286)
			(net 381 "/FPGA MGT Interface/HDMI_OUT.CLK_P")
			(pinfunction "IN_CLK_P")
			(pintype "input")
		)
		(pad "12" smd roundrect
			(at -3.475 2.75 90)
			(size 0.28 0.85)
			(layers "F.Cu" "F.Mask" "F.Paste")
			(roundrect_rratio 0.1785714286)
			(net 383 "/FPGA MGT Interface/HDMI_OUT.CLK_N")
			(pinfunction "IN_CLK_N")
			(pintype "input")
		)
		(pad "13" smd roundrect
			(at -2.75 3.475)
			(size 0.28 0.85)
			(layers "F.Cu" "F.Mask" "F.Paste")
			(roundrect_rratio 0.1785714286)
			(net 151 "+3V3")
			(pinfunction "VCC")
			(pintype "power_in")
		)
		(pad "14" smd roundrect
			(at -2.25 3.475)
			(size 0.28 0.85)
			(layers "F.Cu" "F.Mask" "F.Paste")
			(roundrect_rratio 0.1785714286)
			(net 810 "/HDMI + SD Card/HDMI_VDD")
			(pinfunction "VDD")
			(pintype "power_in")
		)
		(pad "15" smd roundrect
			(at -1.75 3.475)
			(size 0.28 0.85)
			(layers "F.Cu" "F.Mask" "F.Paste")
			(roundrect_rratio 0.1785714286)
			(net 769 "/FPGA MGT Interface/HDMI_CTL.SDA")
			(pinfunction "SDA_CTL")
			(pintype "bidirectional")
		)
		(pad "16" smd roundrect
			(at -1.25 3.475)
			(size 0.28 0.85)
			(layers "F.Cu" "F.Mask" "F.Paste")
			(roundrect_rratio 0.1785714286)
			(net 768 "/FPGA MGT Interface/HDMI_CTL.SCL")
			(pinfunction "SCL_CTL")
			(pintype "bidirectional")
		)
		(pad "17" smd roundrect
			(at -0.75 3.475)
			(size 0.28 0.85)
			(layers "F.Cu" "F.Mask" "F.Paste")
			(roundrect_rratio 0.1785714286)
			(net 757 "unconnected-(U38-NC-Pad17)")
			(pinfunction "NC")
			(pintype "no_connect")
		)
		(pad "18" smd roundrect
			(at -0.25 3.475)
			(size 0.28 0.85)
			(layers "F.Cu" "F.Mask" "F.Paste")
			(roundrect_rratio 0.1785714286)
			(net 758 "unconnected-(U38-CEC_EN-Pad18)")
			(pinfunction "CEC_EN")
			(pintype "output+no_connect")
		)
		(pad "19" smd roundrect
			(at 0.25 3.475)
			(size 0.28 0.85)
			(layers "F.Cu" "F.Mask" "F.Paste")
			(roundrect_rratio 0.1785714286)
			(net 1 "GND")
			(pinfunction "GND")
			(pintype "passive")
		)
		(pad "20" smd roundrect
			(at 0.75 3.475)
			(size 0.28 0.85)
			(layers "F.Cu" "F.Mask" "F.Paste")
			(roundrect_rratio 0.1785714286)
			(net 736 "/HDMI + SD Card/PRE_SEL")
			(pinfunction "PRE_SEL")
			(pintype "input")
		)
		(pad "21" smd roundrect
			(at 1.25 3.475)
			(size 0.28 0.85)
			(layers "F.Cu" "F.Mask" "F.Paste")
			(roundrect_rratio 0.1785714286)
			(net 737 "/HDMI + SD Card/EQ_SEL")
			(pinfunction "EQ_SEL/A0")
			(pintype "input")
		)
		(pad "22" smd roundrect
			(at 1.75 3.475)
			(size 0.28 0.85)
			(layers "F.Cu" "F.Mask" "F.Paste")
			(roundrect_rratio 0.1785714286)
			(net 709 "Net-(U38-VSADJ)")
			(pinfunction "VSADJ")
			(pintype "input")
		)
		(pad "23" smd roundrect
			(at 2.25 3.475)
			(size 0.28 0.85)
			(layers "F.Cu" "F.Mask" "F.Paste")
			(roundrect_rratio 0.1785714286)
			(net 810 "/HDMI + SD Card/HDMI_VDD")
			(pinfunction "VDD")
			(pintype "passive")
		)
		(pad "24" smd roundrect
			(at 2.75 3.475)
			(size 0.28 0.85)
			(layers "F.Cu" "F.Mask" "F.Paste")
			(roundrect_rratio 0.1785714286)
			(net 810 "/HDMI + SD Card/HDMI_VDD")
			(pinfunction "VDD")
			(pintype "passive")
		)
		(pad "25" smd roundrect
			(at 3.475 2.75 90)
			(size 0.28 0.85)
			(layers "F.Cu" "F.Mask" "F.Paste")
			(roundrect_rratio 0.1785714286)
			(net 661 "/HDMI + SD Card/HDMI_OUT_CONN_CLK_N")
			(pinfunction "OUT_CLK_N")
			(pintype "output")
		)
		(pad "26" smd roundrect
			(at 3.475 2.25 90)
			(size 0.28 0.85)
			(layers "F.Cu" "F.Mask" "F.Paste")
			(roundrect_rratio 0.1785714286)
			(net 660 "/HDMI + SD Card/HDMI_OUT_CONN_CLK_P")
			(pinfunction "OUT_CLK_P")
			(pintype "output")
		)
		(pad "27" smd roundrect
			(at 3.475 1.75 90)
			(size 0.28 0.85)
			(layers "F.Cu" "F.Mask" "F.Paste")
			(roundrect_rratio 0.1785714286)
			(net 738 "/HDMI + SD Card/~{HDMI_SEL}")
			(pinfunction "~{HDMI_SEL}/A1")
			(pintype "input")
		)
		(pad "28" smd roundrect
			(at 3.475 1.25 90)
			(size 0.28 0.85)
			(layers "F.Cu" "F.Mask" "F.Paste")
			(roundrect_rratio 0.1785714286)
			(net 659 "/HDMI + SD Card/HDMI_OUT_CONN_D0_N")
			(pinfunction "OUT_D0_N")
			(pintype "output")
		)
		(pad "29" smd roundrect
			(at 3.475 0.75 90)
			(size 0.28 0.85)
			(layers "F.Cu" "F.Mask" "F.Paste")
			(roundrect_rratio 0.1785714286)
			(net 658 "/HDMI + SD Card/HDMI_OUT_CONN_D0_P")
			(pinfunction "OUT_D0_P")
			(pintype "output")
		)
		(pad "30" smd roundrect
			(at 3.475 0.25 90)
			(size 0.28 0.85)
			(layers "F.Cu" "F.Mask" "F.Paste")
			(roundrect_rratio 0.1785714286)
			(net 1 "GND")
			(pinfunction "GND")
			(pintype "passive")
		)
		(pad "31" smd roundrect
			(at 3.475 -0.25 90)
			(size 0.28 0.85)
			(layers "F.Cu" "F.Mask" "F.Paste")
			(roundrect_rratio 0.1785714286)
			(net 657 "/HDMI + SD Card/HDMI_OUT_CONN_D1_N")
			(pinfunction "OUT_D1_N")
			(pintype "output")
		)
		(pad "32" smd roundrect
			(at 3.475 -0.75 90)
			(size 0.28 0.85)
			(layers "F.Cu" "F.Mask" "F.Paste")
			(roundrect_rratio 0.1785714286)
			(net 656 "/HDMI + SD Card/HDMI_OUT_CONN_D1_P")
			(pinfunction "OUT_D1_P")
			(pintype "output")
		)
		(pad "33" smd roundrect
			(at 3.475 -1.25 90)
			(size 0.28 0.85)
			(layers "F.Cu" "F.Mask" "F.Paste")
			(roundrect_rratio 0.1785714286)
			(net 530 "Net-(U38-HPD_SNK)")
			(pinfunction "HPD_SNK")
			(pintype "input")
		)
		(pad "34" smd roundrect
			(at 3.475 -1.75 90)
			(size 0.28 0.85)
			(layers "F.Cu" "F.Mask" "F.Paste")
			(roundrect_rratio 0.1785714286)
			(net 655 "/HDMI + SD Card/HDMI_OUT_CONN_D2_N")
			(pinfunction "OUT_D2_N")
			(pintype "output")
		)
		(pad "35" smd roundrect
			(at 3.475 -2.25 90)
			(size 0.28 0.85)
			(layers "F.Cu" "F.Mask" "F.Paste")
			(roundrect_rratio 0.1785714286)
			(net 654 "/HDMI + SD Card/HDMI_OUT_CONN_D2_P")
			(pinfunction "OUT_D2_P")
			(pintype "output")
		)
		(pad "36" smd roundrect
			(at 3.475 -2.75 90)
			(size 0.28 0.85)
			(layers "F.Cu" "F.Mask" "F.Paste")
			(roundrect_rratio 0.1785714286)
			(net 739 "/HDMI + SD Card/TX_TERM_CTL")
			(pinfunction "TX_TERM_CTL")
			(pintype "input")
		)
		(pad "37" smd roundrect
			(at 2.75 -3.475)
			(size 0.28 0.85)
			(layers "F.Cu" "F.Mask" "F.Paste")
			(roundrect_rratio 0.1785714286)
			(net 810 "/HDMI + SD Card/HDMI_VDD")
			(pinfunction "VDD")
			(pintype "passive")
		)
		(pad "38" smd roundrect
			(at 2.25 -3.475)
			(size 0.28 0.85)
			(layers "F.Cu" "F.Mask" "F.Paste")
			(roundrect_rratio 0.1785714286)
			(net 467 "/HDMI + SD Card/HDMI_OUT_C.SCL")
			(pinfunction "SCL_SNK")
			(pintype "bidirectional")
		)
		(pad "39" smd roundrect
			(at 1.75 -3.475)
			(size 0.28 0.85)
			(layers "F.Cu" "F.Mask" "F.Paste")
			(roundrect_rratio 0.1785714286)
			(net 468 "/HDMI + SD Card/HDMI_OUT_C.SDA")
			(pinfunction "SDA_SNK")
			(pintype "bidirectional")
		)
		(pad "40" smd roundrect
			(at 1.25 -3.475)
			(size 0.28 0.85)
			(layers "F.Cu" "F.Mask" "F.Paste")
			(roundrect_rratio 0.1785714286)
			(net 740 "/HDMI + SD Card/SLEW_CTL")
			(pinfunction "SLEW_CTL")
			(pintype "input")
		)
		(pad "41" smd roundrect
			(at 0.75 -3.475)
			(size 0.28 0.85)
			(layers "F.Cu" "F.Mask" "F.Paste")
			(roundrect_rratio 0.1785714286)
			(net 1 "GND")
			(pinfunction "GND")
			(pintype "passive")
		)
		(pad "42" smd roundrect
			(at 0.25 -3.475)
			(size 0.28 0.85)
			(layers "F.Cu" "F.Mask" "F.Paste")
			(roundrect_rratio 0.1785714286)
			(net 385 "HDMI_OE")
			(pinfunction "OE")
			(pintype "input")
		)
		(pad "43" smd roundrect
			(at -0.25 -3.475)
			(size 0.28 0.85)
			(layers "F.Cu" "F.Mask" "F.Paste")
			(roundrect_rratio 0.1785714286)
			(net 151 "+3V3")
			(pinfunction "VCC")
			(pintype "passive")
		)
		(pad "44" smd roundrect
			(at -0.75 -3.475)
			(size 0.28 0.85)
			(layers "F.Cu" "F.Mask" "F.Paste")
			(roundrect_rratio 0.1785714286)
			(net 759 "unconnected-(U38-AUX_SRC_N-Pad44)")
			(pinfunction "AUX_SRC_N")
			(pintype "bidirectional+no_connect")
		)
		(pad "45" smd roundrect
			(at -1.25 -3.475)
			(size 0.28 0.85)
			(layers "F.Cu" "F.Mask" "F.Paste")
			(roundrect_rratio 0.1785714286)
			(net 760 "unconnected-(U38-AUX_SRC_P-Pad45)")
			(pinfunction "AUX_SRC_P")
			(pintype "bidirectional+no_connect")
		)
		(pad "46" smd roundrect
			(at -1.75 -3.475)
			(size 0.28 0.85)
			(layers "F.Cu" "F.Mask" "F.Paste")
			(roundrect_rratio 0.1785714286)
			(net 554 "/FPGA banks HD/HDMI_OUT_I2C.SCL")
			(pinfunction "SCL_SRC")
			(pintype "bidirectional")
		)
		(pad "47" smd roundrect
			(at -2.25 -3.475)
			(size 0.28 0.85)
			(layers "F.Cu" "F.Mask" "F.Paste")
			(roundrect_rratio 0.1785714286)
			(net 644 "/FPGA banks HD/HDMI_OUT_I2C.SDA")
			(pinfunction "SDA_SRC")
			(pintype "bidirectional")
		)
		(pad "48" smd roundrect
			(at -2.75 -3.475)
			(size 0.28 0.85)
			(layers "F.Cu" "F.Mask" "F.Paste")
			(roundrect_rratio 0.1785714286)
			(net 810 "/HDMI + SD Card/HDMI_VDD")
			(pinfunction "VDD")
			(pintype "passive")
		)
		(pad "49" smd roundrect
			(at 0 0 180)
			(size 4.1 4.1)
			(layers "F.Cu" "F.Mask" "F.Paste")
			(roundrect_rratio 0.01219512195)
			(net 1 "GND")
			(pinfunction "GND")
			(pintype "passive")
			(solder_paste_margin_ratio -0.1)
		)
	)
	(footprint "antmicro-footprints:C_0402_1005Metric"
		(layer "F.Cu")
		(at 128.306 176.022 -90)
		(descr "Capacitor SMD 0402")
		(tags "capacitor SMD 0402")
		(property "Reference" "C277"
			(at -4.05 -0.49 90)
			(layer "F.SilkS")
			(effects
				(font
					(size 0.7 0.7)
					(thickness 0.15)
				)
				(justify right bottom)
			)
		)
		(property "Value" "C_10u_10V_0402"
			(at -1.022927 2.155213 90)
			(layer "F.Fab")
			(effects
				(font
					(size 0.7 0.7)
					(thickness 0.15)
				)
				(justify right bottom)
			)
		)
		(property "Datasheet" "https://www.murata.com/products/productdetail?partno=GRM155R61A106ME11%23"
			(at 0 0 270)
			(layer "F.Fab")
			(hide yes)
			(effects
				(font
					(size 1.27 1.27)
					(thickness 0.15)
				)
			)
		)
		(property "MPN" "GRM155R61A106ME11D"
			(at 0 0 270)
			(unlocked yes)
			(layer "F.Fab")
			(hide yes)
			(effects
				(font
					(size 1 1)
					(thickness 0.15)
				)
			)
		)
		(property "Manufacturer" "Murata"
			(at 0 0 270)
			(unlocked yes)
			(layer "F.Fab")
			(hide yes)
			(effects
				(font
					(size 1 1)
					(thickness 0.15)
				)
			)
		)
		(property "License" "Apache-2.0"
			(at 0 0 270)
			(unlocked yes)
			(layer "F.Fab")
			(hide yes)
			(effects
				(font
					(size 1 1)
					(thickness 0.15)
				)
			)
		)
		(property "Author" "Antmicro"
			(at 0 0 270)
			(unlocked yes)
			(layer "F.Fab")
			(hide yes)
			(effects
				(font
					(size 1 1)
					(thickness 0.15)
				)
			)
		)
		(property "Val" "10u"
			(at 0 0 270)
			(unlocked yes)
			(layer "F.Fab")
			(hide yes)
			(effects
				(font
					(size 1 1)
					(thickness 0.15)
				)
			)
		)
		(property "Voltage" "10V"
			(at 0 0 270)
			(unlocked yes)
			(layer "F.Fab")
			(hide yes)
			(effects
				(font
					(size 1 1)
					(thickness 0.15)
				)
			)
		)
		(property "Dielectric" "X5R"
			(at 0 0 270)
			(unlocked yes)
			(layer "F.Fab")
			(hide yes)
			(effects
				(font
					(size 1 1)
					(thickness 0.15)
				)
			)
		)
		(property "Public" ""
			(at 0 0 270)
			(unlocked yes)
			(layer "F.Fab")
			(hide yes)
			(effects
				(font
					(size 1 1)
					(thickness 0.15)
				)
			)
		)
		(sheetname "/HDMI + SD Card/")
		(sheetfile "hdmi-sd-card.kicad_sch")
		(attr smd)
		(fp_rect
			(start -0.925 -0.47)
			(end 0.925 0.47)
			(stroke
				(width 0.05)
				(type default)
			)
			(fill no)
			(layer "F.CrtYd")
		)
		(fp_line
			(start -0.494 0.248)
			(end -0.494 -0.25)
			(stroke
				(width 0.15)
				(type solid)
			)
			(layer "F.Fab")
		)
		(fp_line
			(start 0.504 0.248)
			(end -0.494 0.248)
			(stroke
				(width 0.15)
				(type solid)
			)
			(layer "F.Fab")
		)
		(fp_line
			(start -0.494 -0.25)
			(end 0.504 -0.25)
			(stroke
				(width 0.15)
				(type solid)
			)
			(layer "F.Fab")
		)
		(fp_line
			(start 0.504 -0.25)
			(end 0.504 0.248)
			(stroke
				(width 0.15)
				(type solid)
			)
			(layer "F.Fab")
		)
		(fp_text user "${REFERENCE}"
			(at -0.939 4.599 270)
			(layer "F.Fab")
			(effects
				(font
					(size 0.7 0.7)
					(thickness 0.15)
				)
				(justify left bottom)
			)
		)
		(fp_text user "License: Apache-2.0"
			(at -0.939 5.799 270)
			(layer "F.Fab")
			(effects
				(font
					(size 0.7 0.7)
					(thickness 0.15)
				)
				(justify left bottom)
			)
		)
		(fp_text user "Author: Antmicro"
			(at -0.939 3.399 270)
			(layer "F.Fab")
			(effects
				(font
					(size 0.7 0.7)
					(thickness 0.15)
				)
				(justify left bottom)
			)
		)
		(pad "1" smd roundrect
			(at -0.48 0 270)
			(size 0.59 0.64)
			(layers "F.Cu" "F.Mask" "F.Paste")
			(roundrect_rratio 0.25)
			(net 1 "GND")
			(pintype "passive")
		)
		(pad "2" smd roundrect
			(at 0.48 0 270)
			(size 0.59 0.64)
			(layers "F.Cu" "F.Mask" "F.Paste")
			(roundrect_rratio 0.25)
			(net 151 "+3V3")
			(pintype "passive")
		)
	)
	(footprint "antmicro-footprints:SOT-23-5"
		(layer "F.Cu")
		(at 239.274499 164.4)
		(property "Reference" "U29"
			(at -1.047499 3.025 0)
			(layer "F.SilkS")
			(effects
				(font
					(size 0.7 0.7)
					(thickness 0.15)
				)
				(justify left bottom)
			)
		)
		(property "Value" "AT24CS01_SOT23"
			(at 0.002 2.799 0)
			(layer "F.Fab")
			(effects
				(font
					(size 0.7 0.7)
					(thickness 0.15)
				)
				(justify left bottom)
			)
		)
		(property "Datasheet" "http://ww1.microchip.com/downloads/en/devicedoc/Atmel-8815-SEEPROM-AT24CS01-02-Datasheet.pdf"
			(at 0 0 0)
			(layer "F.Fab")
			(hide yes)
			(effects
				(font
					(size 1.27 1.27)
					(thickness 0.15)
				)
			)
		)
		(property "Manufacturer" "Atmel"
			(at 0 0 0)
			(unlocked yes)
			(layer "F.Fab")
			(hide yes)
			(effects
				(font
					(size 1 1)
					(thickness 0.15)
				)
			)
		)
		(property "MPN" "AT24CS01-ST"
			(at 0 0 0)
			(unlocked yes)
			(layer "F.Fab")
			(hide yes)
			(effects
				(font
					(size 1 1)
					(thickness 0.15)
				)
			)
		)
		(property "Author" "Antmicro"
			(at 0 0 0)
			(unlocked yes)
			(layer "F.Fab")
			(hide yes)
			(effects
				(font
					(size 1 1)
					(thickness 0.15)
				)
			)
		)
		(property "License" "Apache-2.0"
			(at 0 0 0)
			(unlocked yes)
			(layer "F.Fab")
			(hide yes)
			(effects
				(font
					(size 1 1)
					(thickness 0.15)
				)
			)
		)
		(sheetname "/Supply/")
		(sheetfile "supply.kicad_sch")
		(attr smd)
		(fp_line
			(start -0.85 1.6)
			(end -0.85 1.301)
			(stroke
				(width 0.15)
				(type solid)
			)
			(layer "F.SilkS")
		)
		(fp_line
			(start -0.8 -1.6)
			(end -0.8 -1.3)
			(stroke
				(width 0.15)
				(type solid)
			)
			(layer "F.SilkS")
		)
		(fp_line
			(start -0.8 -1.6)
			(end -0.5 -1.6)
			(stroke
				(width 0.15)
				(type solid)
			)
			(layer "F.SilkS")
		)
		(fp_line
			(start -0.55 1.6)
			(end -0.85 1.6)
			(stroke
				(width 0.15)
				(type solid)
			)
			(layer "F.SilkS")
		)
		(fp_line
			(start 0.8 -1.6)
			(end 0.5 -1.6)
			(stroke
				(width 0.15)
				(type solid)
			)
			(layer "F.SilkS")
		)
		(fp_line
			(start 0.8 -1.3)
			(end 0.8 -1.6)
			(stroke
				(width 0.15)
				(type solid)
			)
			(layer "F.SilkS")
		)
		(fp_line
			(start 0.8 0.55)
			(end 0.8 -0.55)
			(stroke
				(width 0.15)
				(type solid)
			)
			(layer "F.SilkS")
		)
		(fp_line
			(start 0.8 1.3)
			(end 0.8 1.599)
			(stroke
				(width 0.15)
				(type solid)
			)
			(layer "F.SilkS")
		)
		(fp_line
			(start 0.8 1.599)
			(end 0.549 1.599)
			(stroke
				(width 0.15)
				(type solid)
			)
			(layer "F.SilkS")
		)
		(fp_circle
			(center -1.25 -1.5)
			(end -1.2 -1.5)
			(stroke
				(width 0.15)
				(type solid)
			)
			(fill yes)
			(layer "F.SilkS")
		)
		(fp_rect
			(start 1.9 -1.76)
			(end -1.9 1.75)
			(stroke
				(width 0.05)
				(type solid)
			)
			(fill no)
			(layer "F.CrtYd")
		)
		(fp_line
			(start -0.398 -1.526)
			(end -0.874 -1.05)
			(stroke
				(width 0.15)
				(type solid)
			)
			(layer "F.Fab")
		)
		(fp_rect
			(start 0.874 1.523)
			(end -0.873 -1.525)
			(stroke
				(width 0.15)
				(type solid)
			)
			(fill no)
			(layer "F.Fab")
		)
		(fp_text user "${REFERENCE}"
			(at -1.898 4.299 0)
			(layer "F.Fab")
			(effects
				(font
					(size 0.7 0.7)
					(thickness 0.15)
				)
				(justify left bottom)
			)
		)
		(fp_text user "License: Apache-2.0"
			(at -1.898 6.7 0)
			(layer "F.Fab")
			(effects
				(font
					(size 0.7 0.7)
					(thickness 0.15)
				)
				(justify left bottom)
			)
		)
		(fp_text user "Author: Antmicro"
			(at -1.898 5.499 0)
			(layer "F.Fab")
			(effects
				(font
					(size 0.7 0.7)
					(thickness 0.15)
				)
				(justify left bottom)
			)
		)
		(pad "1" smd rect
			(at -1.351 -0.951 270)
			(size 0.55 1)
			(layers "F.Cu" "F.Mask" "F.Paste")
			(net 749 "/I^{2}C + I3C/PWR.SCL")
			(pinfunction "SCL")
			(pintype "passive")
		)
		(pad "2" smd rect
			(at -1.351 0 270)
			(size 0.55 1)
			(layers "F.Cu" "F.Mask" "F.Paste")
			(net 1 "GND")
			(pinfunction "GND")
			(pintype "passive")
		)
		(pad "3" smd rect
			(at -1.351 0.949 270)
			(size 0.55 1)
			(layers "F.Cu" "F.Mask" "F.Paste")
			(net 533 "/I^{2}C + I3C/PWR.SDA")
			(pinfunction "SDA")
			(pintype "passive")
		)
		(pad "4" smd rect
			(at 1.35 0.949 270)
			(size 0.55 1)
			(layers "F.Cu" "F.Mask" "F.Paste")
			(net 38 "+3V3_AON")
			(pinfunction "VCC")
			(pintype "passive")
		)
		(pad "5" smd rect
			(at 1.35 -0.951 270)
			(size 0.55 1)
			(layers "F.Cu" "F.Mask" "F.Paste")
			(net 1 "GND")
			(pinfunction "WP")
			(pintype "passive")
		)
	)
	(footprint "antmicro-footprints:R_0402_1005Metric"
		(layer "F.Cu")
		(at 158.25 166.124999)
		(descr "Resistor SMD 0402")
		(tags "resistor SMD 0402")
		(property "Reference" "R74"
			(at -1.02 1.515001 0)
			(layer "F.SilkS")
			(effects
				(font
					(size 0.7 0.7)
					(thickness 0.15)
				)
				(justify left bottom)
			)
		)
		(property "Value" "R_4k7_0402"
			(at -1.011843 1.772047 0)
			(layer "F.Fab")
			(effects
				(font
					(size 0.7 0.7)
					(thickness 0.15)
				)
				(justify left bottom)
			)
		)
		(property "Datasheet" "https://www.bourns.com/docs/product-datasheets/cr.pdf"
			(at 0 0 0)
			(layer "F.Fab")
			(hide yes)
			(effects
				(font
					(size 1.27 1.27)
					(thickness 0.15)
				)
			)
		)
		(property "MPN" "CR0402-FX-4701GLF"
			(at 0 0 0)
			(unlocked yes)
			(layer "F.Fab")
			(hide yes)
			(effects
				(font
					(size 1 1)
					(thickness 0.15)
				)
			)
		)
		(property "Manufacturer" "Bourns"
			(at 0 0 0)
			(unlocked yes)
			(layer "F.Fab")
			(hide yes)
			(effects
				(font
					(size 1 1)
					(thickness 0.15)
				)
			)
		)
		(property "License" "Apache-2.0"
			(at 0 0 0)
			(unlocked yes)
			(layer "F.Fab")
			(hide yes)
			(effects
				(font
					(size 1 1)
					(thickness 0.15)
				)
			)
		)
		(property "Author" "Antmicro"
			(at 0 0 0)
			(unlocked yes)
			(layer "F.Fab")
			(hide yes)
			(effects
				(font
					(size 1 1)
					(thickness 0.15)
				)
			)
		)
		(property "Val" "4k7"
			(at 0 0 0)
			(unlocked yes)
			(layer "F.Fab")
			(hide yes)
			(effects
				(font
					(size 1 1)
					(thickness 0.15)
				)
			)
		)
		(property "Tolerance" "1%"
			(at 0 0 0)
			(unlocked yes)
			(layer "F.Fab")
			(hide yes)
			(effects
				(font
					(size 1 1)
					(thickness 0.15)
				)
			)
		)
		(sheetname "/FPGA MGT Interface/")
		(sheetfile "fpga-mgt.kicad_sch")
		(attr smd)
		(fp_rect
			(start -0.925 -0.47)
			(end 0.925 0.47)
			(stroke
				(width 0.05)
				(type default)
			)
			(fill no)
			(layer "F.CrtYd")
		)
		(fp_rect
			(start -0.5 -0.25)
			(end 0.5 0.25)
			(stroke
				(width 0.15)
				(type solid)
			)
			(fill no)
			(layer "F.Fab")
		)
		(fp_text user "${REFERENCE}"
			(at -0.95 3.168 0)
			(layer "F.Fab")
			(effects
				(font
					(size 0.7 0.7)
					(thickness 0.15)
				)
				(justify left bottom)
			)
		)
		(fp_text user "License: Apache-2.0"
			(at -0.95 5.169 0)
			(layer "F.Fab")
			(effects
				(font
					(size 0.7 0.7)
					(thickness 0.15)
				)
				(justify left bottom)
			)
		)
		(fp_text user "Author: Antmicro"
			(at -0.95 4.169 0)
			(layer "F.Fab")
			(effects
				(font
					(size 0.7 0.7)
					(thickness 0.15)
				)
				(justify left bottom)
			)
		)
		(pad "1" smd roundrect
			(at -0.48 0)
			(size 0.59 0.64)
			(layers "F.Cu" "F.Mask" "F.Paste")
			(roundrect_rratio 0.25)
			(net 1 "GND")
			(pintype "passive")
		)
		(pad "2" smd roundrect
			(at 0.48 0)
			(size 0.59 0.64)
			(layers "F.Cu" "F.Mask" "F.Paste")
			(roundrect_rratio 0.25)
			(net 708 "Net-(U39-CS)")
			(pintype "passive")
		)
	)
	(footprint "antmicro-footprints:C_0402_1005Metric"
		(layer "F.Cu")
		(at 233.465001 178.791 90)
		(descr "Capacitor SMD 0402")
		(tags "capacitor SMD 0402")
		(property "Reference" "C216"
			(at -2.065 1.764999 90)
			(layer "F.SilkS")
			(effects
				(font
					(size 0.7 0.7)
					(thickness 0.15)
				)
				(justify left bottom)
			)
		)
		(property "Value" "C_220n_16V_0402"
			(at -1.022927 2.155213 90)
			(layer "F.Fab")
			(effects
				(font
					(size 0.7 0.7)
					(thickness 0.15)
				)
				(justify left bottom)
			)
		)
		(property "Datasheet" "https://www.murata.com/products/productdetail?partno=GRM155R71C224KA12%23"
			(at 0 0 90)
			(layer "F.Fab")
			(hide yes)
			(effects
				(font
					(size 1.27 1.27)
					(thickness 0.15)
				)
			)
		)
		(property "MPN" "GRM155R71C224KA12D"
			(at 0 0 90)
			(unlocked yes)
			(layer "F.Fab")
			(hide yes)
			(effects
				(font
					(size 1 1)
					(thickness 0.15)
				)
			)
		)
		(property "Manufacturer" "Murata"
			(at 0 0 90)
			(unlocked yes)
			(layer "F.Fab")
			(hide yes)
			(effects
				(font
					(size 1 1)
					(thickness 0.15)
				)
			)
		)
		(property "License" "Apache-2.0"
			(at 0 0 90)
			(unlocked yes)
			(layer "F.Fab")
			(hide yes)
			(effects
				(font
					(size 1 1)
					(thickness 0.15)
				)
			)
		)
		(property "Author" "Antmicro"
			(at 0 0 90)
			(unlocked yes)
			(layer "F.Fab")
			(hide yes)
			(effects
				(font
					(size 1 1)
					(thickness 0.15)
				)
			)
		)
		(property "Val" "220n"
			(at 0 0 90)
			(unlocked yes)
			(layer "F.Fab")
			(hide yes)
			(effects
				(font
					(size 1 1)
					(thickness 0.15)
				)
			)
		)
		(property "Voltage" "16V"
			(at 0 0 90)
			(unlocked yes)
			(layer "F.Fab")
			(hide yes)
			(effects
				(font
					(size 1 1)
					(thickness 0.15)
				)
			)
		)
		(property "Dielectric" "X7R"
			(at 0 0 90)
			(unlocked yes)
			(layer "F.Fab")
			(hide yes)
			(effects
				(font
					(size 1 1)
					(thickness 0.15)
				)
			)
		)
		(sheetname "/Supply/DC-DC VCCINT/")
		(sheetfile "dc-dc-vccint.kicad_sch")
		(attr smd)
		(fp_rect
			(start -0.925 -0.47)
			(end 0.925 0.47)
			(stroke
				(width 0.05)
				(type default)
			)
			(fill no)
			(layer "F.CrtYd")
		)
		(fp_line
			(start 0.504 -0.25)
			(end 0.504 0.248)
			(stroke
				(width 0.15)
				(type solid)
			)
			(layer "F.Fab")
		)
		(fp_line
			(start -0.494 -0.25)
			(end 0.504 -0.25)
			(stroke
				(width 0.15)
				(type solid)
			)
			(layer "F.Fab")
		)
		(fp_line
			(start 0.504 0.248)
			(end -0.494 0.248)
			(stroke
				(width 0.15)
				(type solid)
			)
			(layer "F.Fab")
		)
		(fp_line
			(start -0.494 0.248)
			(end -0.494 -0.25)
			(stroke
				(width 0.15)
				(type solid)
			)
			(layer "F.Fab")
		)
		(fp_text user "Author: Antmicro"
			(at -0.939 3.399 90)
			(layer "F.Fab")
			(effects
				(font
					(size 0.7 0.7)
					(thickness 0.15)
				)
				(justify left bottom)
			)
		)
		(fp_text user "License: Apache-2.0"
			(at -0.939 5.799 90)
			(layer "F.Fab")
			(effects
				(font
					(size 0.7 0.7)
					(thickness 0.15)
				)
				(justify left bottom)
			)
		)
		(fp_text user "${REFERENCE}"
			(at -0.939 4.599 90)
			(layer "F.Fab")
			(effects
				(font
					(size 0.7 0.7)
					(thickness 0.15)
				)
				(justify left bottom)
			)
		)
		(pad "1" smd roundrect
			(at -0.48 0 90)
			(size 0.59 0.64)
			(layers "F.Cu" "F.Mask" "F.Paste")
			(roundrect_rratio 0.25)
			(net 167 "Net-(U36-BST)")
			(pintype "passive")
		)
		(pad "2" smd roundrect
			(at 0.48 0 90)
			(size 0.59 0.64)
			(layers "F.Cu" "F.Mask" "F.Paste")
			(roundrect_rratio 0.25)
			(net 207 "Net-(C216-Pad2)")
			(pintype "passive")
		)
	)
	(footprint "antmicro-footprints:R_0805_2012Metric"
		(layer "F.Cu")
		(at 246.299499 167.948 180)
		(property "Reference" "R142"
			(at 0.899499 -1.852 180)
			(layer "F.SilkS")
			(effects
				(font
					(size 0.7 0.7)
					(thickness 0.15)
				)
				(justify left bottom)
			)
		)
		(property "Value" "R_0R002_0805"
			(at 0 1.8 180)
			(layer "F.Fab")
			(effects
				(font
					(size 0.7 0.7)
					(thickness 0.15)
				)
				(justify left bottom)
			)
		)
		(property "Datasheet" "https://www2.mouser.com/datasheet/2/447/PYu_PA0100_2512_51_RoHS_2-2604383.pdf"
			(at 0 0 180)
			(layer "F.Fab")
			(hide yes)
			(effects
				(font
					(size 1.27 1.27)
					(thickness 0.15)
				)
			)
		)
		(property "MPN" "PA0805FRE470R002L"
			(at 0 0 180)
			(unlocked yes)
			(layer "F.Fab")
			(hide yes)
			(effects
				(font
					(size 1 1)
					(thickness 0.15)
				)
			)
		)
		(property "Manufacturer" "YAGEO"
			(at 0 0 180)
			(unlocked yes)
			(layer "F.Fab")
			(hide yes)
			(effects
				(font
					(size 1 1)
					(thickness 0.15)
				)
			)
		)
		(property "License" "Apache-2.0"
			(at 0 0 180)
			(unlocked yes)
			(layer "F.Fab")
			(hide yes)
			(effects
				(font
					(size 1 1)
					(thickness 0.15)
				)
			)
		)
		(property "Author" "Antmicro"
			(at 0 0 180)
			(unlocked yes)
			(layer "F.Fab")
			(hide yes)
			(effects
				(font
					(size 1 1)
					(thickness 0.15)
				)
			)
		)
		(property "Val" "0R002"
			(at 0 0 180)
			(unlocked yes)
			(layer "F.Fab")
			(hide yes)
			(effects
				(font
					(size 1 1)
					(thickness 0.15)
				)
			)
		)
		(property "Tolerance" "1%"
			(at 0 0 180)
			(unlocked yes)
			(layer "F.Fab")
			(hide yes)
			(effects
				(font
					(size 1 1)
					(thickness 0.15)
				)
			)
		)
		(sheetname "/Supply/DC-DC AUX, MGT/")
		(sheetfile "dc-dc-aux-mgt.kicad_sch")
		(attr smd)
		(fp_line
			(start -0.3 -0.701)
			(end 0.298 -0.701)
			(stroke
				(width 0.15)
				(type solid)
			)
			(layer "F.SilkS")
		)
		(fp_line
			(start -0.32 0.699)
			(end 0.28 0.699)
			(stroke
				(width 0.15)
				(type solid)
			)
			(layer "F.SilkS")
		)
		(fp_rect
			(start 1.95 -0.9)
			(end -1.95 0.9)
			(stroke
				(width 0.05)
				(type default)
			)
			(fill no)
			(layer "F.CrtYd")
		)
		(fp_line
			(start 0.949 -0.677)
			(end 0.949 0.675)
			(stroke
				(width 0.15)
				(type solid)
			)
			(layer "F.Fab")
		)
		(fp_line
			(start -0.951 0.68)
			(end 0.949 0.68)
			(stroke
				(width 0.15)
				(type solid)
			)
			(layer "F.Fab")
		)
		(fp_line
			(start -0.951 -0.677)
			(end -0.951 0.675)
			(stroke
				(width 0.15)
				(type solid)
			)
			(layer "F.Fab")
		)
		(fp_line
			(start -0.951 -0.682)
			(end 0.949 -0.682)
			(stroke
				(width 0.15)
				(type solid)
			)
			(layer "F.Fab")
		)
		(fp_text user "License: Apache-2.0"
			(at -1.9 5.75 180)
			(layer "F.Fab")
			(effects
				(font
					(size 0.7 0.7)
					(thickness 0.15)
				)
				(justify left bottom)
			)
		)
		(fp_text user "Author: Antmicro"
			(at -1.9 4.4 180)
			(layer "F.Fab")
			(effects
				(font
					(size 0.7 0.7)
					(thickness 0.15)
				)
				(justify left bottom)
			)
		)
		(fp_text user "${REFERENCE}"
			(at -1.9 3.1 180)
			(layer "F.Fab")
			(effects
				(font
					(size 0.7 0.7)
					(thickness 0.15)
				)
				(justify left bottom)
			)
		)
		(pad "1" smd roundrect
			(at -1.1 0 180)
			(size 1.2 1.3)
			(layers "F.Cu" "F.Mask" "F.Paste")
			(roundrect_rratio 0.25)
			(net 48 "/Supply/DC-DC AUX, MGT/MGTAVTT_local")
			(pintype "passive")
		)
		(pad "2" smd roundrect
			(at 1.1 0 180)
			(size 1.2 1.3)
			(layers "F.Cu" "F.Mask" "F.Paste")
			(roundrect_rratio 0.25)
			(net 172 "+1V2_MGTAVTT")
			(pintype "passive")
		)
	)
	(footprint "antmicro-footprints:R_0402_1005Metric"
		(layer "F.Cu")
		(at 118.098 112.72 -90)
		(descr "Resistor SMD 0402")
		(tags "resistor SMD 0402")
		(property "Reference" "R12"
			(at -1.12 -1.427 90)
			(layer "F.SilkS")
			(effects
				(font
					(size 0.7 0.7)
					(thickness 0.15)
				)
				(justify right bottom)
			)
		)
		(property "Value" "R_330R_0402"
			(at -1.011843 1.772047 90)
			(layer "F.Fab")
			(effects
				(font
					(size 0.7 0.7)
					(thickness 0.15)
				)
				(justify right bottom)
			)
		)
		(property "Datasheet" "https://www.bourns.com/docs/product-datasheets/cr.pdf"
			(at 0 0 270)
			(layer "F.Fab")
			(hide yes)
			(effects
				(font
					(size 1.27 1.27)
					(thickness 0.15)
				)
			)
		)
		(property "Manufacturer" "Bourns"
			(at 0 0 270)
			(unlocked yes)
			(layer "F.Fab")
			(hide yes)
			(effects
				(font
					(size 1 1)
					(thickness 0.15)
				)
			)
		)
		(property "MPN" "CR0402-FX-3300GLF"
			(at 0 0 270)
			(unlocked yes)
			(layer "F.Fab")
			(hide yes)
			(effects
				(font
					(size 1 1)
					(thickness 0.15)
				)
			)
		)
		(property "Val" "330R"
			(at 0 0 270)
			(unlocked yes)
			(layer "F.Fab")
			(hide yes)
			(effects
				(font
					(size 1 1)
					(thickness 0.15)
				)
			)
		)
		(property "License" "Apache-2.0"
			(at 0 0 270)
			(unlocked yes)
			(layer "F.Fab")
			(hide yes)
			(effects
				(font
					(size 1 1)
					(thickness 0.15)
				)
			)
		)
		(property "Author" "Antmicro"
			(at 0 0 270)
			(unlocked yes)
			(layer "F.Fab")
			(hide yes)
			(effects
				(font
					(size 1 1)
					(thickness 0.15)
				)
			)
		)
		(property "Tolerance" "1%"
			(at 0 0 270)
			(unlocked yes)
			(layer "F.Fab")
			(hide yes)
			(effects
				(font
					(size 1 1)
					(thickness 0.15)
				)
			)
		)
		(sheetname "/FPGA Config/")
		(sheetfile "fpga-config.kicad_sch")
		(attr smd)
		(fp_rect
			(start -0.925 -0.47)
			(end 0.925 0.47)
			(stroke
				(width 0.05)
				(type default)
			)
			(fill no)
			(layer "F.CrtYd")
		)
		(fp_rect
			(start -0.5 -0.25)
			(end 0.5 0.25)
			(stroke
				(width 0.15)
				(type solid)
			)
			(fill no)
			(layer "F.Fab")
		)
		(fp_text user "License: Apache-2.0"
			(at -0.95 5.169 270)
			(layer "F.Fab")
			(effects
				(font
					(size 0.7 0.7)
					(thickness 0.15)
				)
				(justify left bottom)
			)
		)
		(fp_text user "Author: Antmicro"
			(at -0.95 4.169 270)
			(layer "F.Fab")
			(effects
				(font
					(size 0.7 0.7)
					(thickness 0.15)
				)
				(justify left bottom)
			)
		)
		(fp_text user "${REFERENCE}"
			(at -0.95 3.168 270)
			(layer "F.Fab")
			(effects
				(font
					(size 0.7 0.7)
					(thickness 0.15)
				)
				(justify left bottom)
			)
		)
		(pad "1" smd roundrect
			(at -0.48 0 270)
			(size 0.59 0.64)
			(layers "F.Cu" "F.Mask" "F.Paste")
			(roundrect_rratio 0.25)
			(net 785 "Net-(D3-C)")
			(pintype "passive")
		)
		(pad "2" smd roundrect
			(at 0.48 0 270)
			(size 0.59 0.64)
			(layers "F.Cu" "F.Mask" "F.Paste")
			(roundrect_rratio 0.25)
			(net 271 "Net-(Q3-D)")
			(pintype "passive")
		)
	)
	(footprint "antmicro-footprints:TSSOP-8_3x3mm_P0.65mm"
		(layer "F.Cu")
		(at 239.274499 133.77)
		(property "Reference" "U45"
			(at 0 -2 0)
			(layer "F.SilkS")
			(effects
				(font
					(size 0.7 0.7)
					(thickness 0.15)
				)
				(justify left bottom)
			)
		)
		(property "Value" "PCA9517ADP"
			(at 0 2.8 0)
			(layer "F.Fab")
			(effects
				(font
					(size 0.7 0.7)
					(thickness 0.15)
				)
				(justify left bottom)
			)
		)
		(property "Datasheet" "https://www.nxp.com/docs/en/data-sheet/PCA9517A.pdf"
			(at 0 0 0)
			(layer "F.Fab")
			(hide yes)
			(effects
				(font
					(size 1.27 1.27)
					(thickness 0.15)
				)
			)
		)
		(property "MPN" "PCA9517ADP,118"
			(at 0 0 0)
			(unlocked yes)
			(layer "F.Fab")
			(hide yes)
			(effects
				(font
					(size 1 1)
					(thickness 0.15)
				)
			)
		)
		(property "Manufacturer" "NXP"
			(at 0 0 0)
			(unlocked yes)
			(layer "F.Fab")
			(hide yes)
			(effects
				(font
					(size 1 1)
					(thickness 0.15)
				)
			)
		)
		(property "Author" "Antmicro"
			(at 0 0 0)
			(unlocked yes)
			(layer "F.Fab")
			(hide yes)
			(effects
				(font
					(size 1 1)
					(thickness 0.15)
				)
			)
		)
		(property "License" "Apache-2.0"
			(at 0 0 0)
			(unlocked yes)
			(layer "F.Fab")
			(hide yes)
			(effects
				(font
					(size 1 1)
					(thickness 0.15)
				)
			)
		)
		(sheetname "/I^{2}C + I3C/")
		(sheetfile "i2c.kicad_sch")
		(attr smd)
		(fp_line
			(start -1.55 1.561)
			(end 1.552 1.561)
			(stroke
				(width 0.15)
				(type solid)
			)
			(layer "F.SilkS")
		)
		(fp_line
			(start -1.525 -1.537)
			(end 1.552 -1.539)
			(stroke
				(width 0.15)
				(type solid)
			)
			(layer "F.SilkS")
		)
		(fp_circle
			(center -1.87 -1.4)
			(end -1.82 -1.4)
			(stroke
				(width 0.15)
				(type solid)
			)
			(fill yes)
			(layer "F.SilkS")
		)
		(fp_rect
			(start -3.15 -1.789)
			(end 3.15 1.811)
			(stroke
				(width 0.05)
				(type solid)
			)
			(fill no)
			(layer "F.CrtYd")
		)
		(fp_line
			(start -1.55 -0.937)
			(end -1.55 1.561)
			(stroke
				(width 0.15)
				(type solid)
			)
			(layer "F.Fab")
		)
		(fp_line
			(start -1.55 -0.937)
			(end -0.949 -1.539)
			(stroke
				(width 0.15)
				(type solid)
			)
			(layer "F.Fab")
		)
		(fp_line
			(start -1.55 1.561)
			(end 1.552 1.561)
			(stroke
				(width 0.15)
				(type solid)
			)
			(layer "F.Fab")
		)
		(fp_line
			(start -0.949 -1.539)
			(end 1.552 -1.539)
			(stroke
				(width 0.15)
				(type solid)
			)
			(layer "F.Fab")
		)
		(fp_line
			(start 1.552 -1.539)
			(end 1.552 1.561)
			(stroke
				(width 0.15)
				(type solid)
			)
			(layer "F.Fab")
		)
		(fp_text user "Author: Antmicro"
			(at -1.789 7.78 0)
			(layer "F.Fab")
			(effects
				(font
					(size 0.7 0.7)
					(thickness 0.15)
				)
				(justify left bottom)
			)
		)
		(fp_text user "${REFERENCE}"
			(at -1.789 6.58 0)
			(layer "F.Fab")
			(effects
				(font
					(size 0.7 0.7)
					(thickness 0.15)
				)
				(justify left bottom)
			)
		)
		(fp_text user "License: Apache-2.0"
			(at -1.789 8.98 0)
			(layer "F.Fab")
			(effects
				(font
					(size 0.7 0.7)
					(thickness 0.15)
				)
				(justify left bottom)
			)
		)
		(pad "1" smd roundrect
			(at -2.148 -0.962)
			(size 1.47 0.4)
			(layers "F.Cu" "F.Mask" "F.Paste")
			(roundrect_rratio 0.25)
			(net 201 "VDDSPD")
			(pinfunction "V_{CC(A)}")
			(pintype "power_in")
		)
		(pad "2" smd roundrect
			(at -2.148 -0.313)
			(size 1.47 0.4)
			(layers "F.Cu" "F.Mask" "F.Paste")
			(roundrect_rratio 0.25)
			(net 460 "/DDR5 RDIMM/DDR.SCL")
			(pinfunction "SCLA")
			(pintype "input")
		)
		(pad "3" smd roundrect
			(at -2.148 0.338)
			(size 1.47 0.4)
			(layers "F.Cu" "F.Mask" "F.Paste")
			(roundrect_rratio 0.25)
			(net 459 "/DDR5 RDIMM/DDR.SDA")
			(pinfunction "SDAA")
			(pintype "bidirectional")
		)
		(pad "4" smd roundrect
			(at -2.148 0.987)
			(size 1.47 0.4)
			(layers "F.Cu" "F.Mask" "F.Paste")
			(roundrect_rratio 0.25)
			(net 1 "GND")
			(pinfunction "GND")
			(pintype "power_in")
		)
		(pad "5" smd roundrect
			(at 2.151 0.987)
			(size 1.47 0.4)
			(layers "F.Cu" "F.Mask" "F.Paste")
			(roundrect_rratio 0.25)
			(net 796 "Net-(U45-EN)")
			(pinfunction "EN")
			(pintype "input")
		)
		(pad "6" smd roundrect
			(at 2.151 0.338)
			(size 1.47 0.4)
			(layers "F.Cu" "F.Mask" "F.Paste")
			(roundrect_rratio 0.25)
			(net 472 "/FPGA banks HD/FPGA_DDR.SDA")
			(pinfunction "SDAB")
			(pintype "bidirectional")
		)
		(pad "7" smd roundrect
			(at 2.151 -0.313)
			(size 1.47 0.4)
			(layers "F.Cu" "F.Mask" "F.Paste")
			(roundrect_rratio 0.25)
			(net 465 "/FPGA banks HD/FPGA_DDR.SCL")
			(pinfunction "SCLB")
			(pintype "input")
		)
		(pad "8" smd roundrect
			(at 2.151 -0.962)
			(size 1.47 0.4)
			(layers "F.Cu" "F.Mask" "F.Paste")
			(roundrect_rratio 0.25)
			(net 151 "+3V3")
			(pinfunction "V_{CC(B)}")
			(pintype "power_in")
		)
	)
	(footprint "antmicro-footprints:NetTie-2_SMD_Pad0.127mm"
		(layer "F.Cu")
		(at 257.267 148.15)
		(descr "Net tie, 2 pin, 0.127mm  SMD pads")
		(tags "net tie")
		(property "Reference" "NT7"
			(at -0.128 -1.345 0)
			(layer "F.SilkS")
			(hide yes)
			(effects
				(font
					(size 0.7 0.7)
					(thickness 0.15)
				)
				(justify left bottom)
			)
		)
		(property "Value" "Net-Tie_P0.127mm"
			(at 0 1.199 0)
			(layer "F.Fab")
			(effects
				(font
					(size 0.7 0.7)
					(thickness 0.15)
				)
				(justify left bottom)
			)
		)
		(property "MPN" ""
			(at 0 0 0)
			(unlocked yes)
			(layer "F.Fab")
			(hide yes)
			(effects
				(font
					(size 1 1)
					(thickness 0.15)
				)
			)
		)
		(property "Manufacturer" ""
			(at 0 0 0)
			(unlocked yes)
			(layer "F.Fab")
			(hide yes)
			(effects
				(font
					(size 1 1)
					(thickness 0.15)
				)
			)
		)
		(property "Author" "Antmicro"
			(at 0 0 0)
			(unlocked yes)
			(layer "F.Fab")
			(hide yes)
			(effects
				(font
					(size 1 1)
					(thickness 0.15)
				)
			)
		)
		(property "License" "Apache-2.0"
			(at 0 0 0)
			(unlocked yes)
			(layer "F.Fab")
			(hide yes)
			(effects
				(font
					(size 1 1)
					(thickness 0.15)
				)
			)
		)
		(property ki_fp_filters "Net*Tie*")
		(sheetname "/Supply/DC-DC IO/")
		(sheetfile "dc-dc-io.kicad_sch")
		(attr through_hole exclude_from_pos_files exclude_from_bom)
		(net_tie_pad_groups "1, 2")
		(fp_poly
			(pts
				(xy -0.0635 -0.0635) (xy 0.0625 -0.0635) (xy 0.0625 0.0635) (xy -0.0635 0.0635)
			)
			(stroke
				(width 0)
				(type solid)
			)
			(fill yes)
			(layer "F.Cu")
		)
		(fp_poly
			(pts
				(xy 0.2 -0.16) (xy 0.29 -0.07) (xy 0.29 0.07) (xy 0.2 0.16) (xy -0.2 0.16) (xy -0.29 0.07) (xy -0.29 -0.06)
				(xy -0.19 -0.16)
			)
			(stroke
				(width 0.05)
				(type solid)
			)
			(fill no)
			(layer "F.CrtYd")
		)
		(fp_text user "Author: Antmicro"
			(at -0.128 4.4 0)
			(layer "F.Fab")
			(effects
				(font
					(size 0.7 0.7)
					(thickness 0.15)
				)
				(justify left bottom)
			)
		)
		(fp_text user "License: Apache-2.0"
			(at -0.128 5.6 0)
			(layer "F.Fab")
			(effects
				(font
					(size 0.7 0.7)
					(thickness 0.15)
				)
				(justify left bottom)
			)
		)
		(fp_text user "${REFERENCE}"
			(at -0.128 3.2 0)
			(layer "F.Fab")
			(effects
				(font
					(size 0.7 0.7)
					(thickness 0.15)
				)
				(justify left bottom)
			)
		)
		(pad "1" smd roundrect
			(at -0.127 0 180)
			(size 0.127 0.127)
			(layers "F.Cu")
			(roundrect_rratio 0.5)
			(chamfer_ratio 0)
			(chamfer top_left bottom_left)
			(net 695 "/Supply/DC-DC IO/VDDQ_SEN_+")
			(pinfunction "1")
			(pintype "passive")
		)
		(pad "2" smd roundrect
			(at 0.126 0)
			(size 0.127 0.127)
			(layers "F.Cu")
			(roundrect_rratio 0.5)
			(chamfer_ratio 0)
			(chamfer top_left bottom_left)
			(net 158 "/Supply/DC-DC IO/VDDQ_local")
			(pinfunction "2")
			(pintype "passive")
		)
	)
	(footprint "antmicro-footprints:C_0402_1005Metric"
		(layer "F.Cu")
		(at 114.773499 139.083 90)
		(descr "Capacitor SMD 0402")
		(tags "capacitor SMD 0402")
		(property "Reference" "C113"
			(at -3.942 0.401501 90)
			(layer "F.SilkS")
			(effects
				(font
					(size 0.7 0.7)
					(thickness 0.15)
				)
				(justify left bottom)
			)
		)
		(property "Value" "C_10u_6.3V_0402"
			(at -1.022927 2.155213 90)
			(layer "F.Fab")
			(effects
				(font
					(size 0.7 0.7)
					(thickness 0.15)
				)
				(justify left bottom)
			)
		)
		(property "Datasheet" "https://www.murata.com/products/productdetail?partno=GRM155R60J106ME15%23"
			(at 0 0 90)
			(layer "F.Fab")
			(hide yes)
			(effects
				(font
					(size 1.27 1.27)
					(thickness 0.15)
				)
			)
		)
		(property "MPN" "GRM155R60J106ME15D"
			(at 0 0 90)
			(unlocked yes)
			(layer "F.Fab")
			(hide yes)
			(effects
				(font
					(size 1 1)
					(thickness 0.15)
				)
			)
		)
		(property "Manufacturer" "Murata"
			(at 0 0 90)
			(unlocked yes)
			(layer "F.Fab")
			(hide yes)
			(effects
				(font
					(size 1 1)
					(thickness 0.15)
				)
			)
		)
		(property "License" "Apache-2.0"
			(at 0 0 90)
			(unlocked yes)
			(layer "F.Fab")
			(hide yes)
			(effects
				(font
					(size 1 1)
					(thickness 0.15)
				)
			)
		)
		(property "Author" "Antmicro"
			(at 0 0 90)
			(unlocked yes)
			(layer "F.Fab")
			(hide yes)
			(effects
				(font
					(size 1 1)
					(thickness 0.15)
				)
			)
		)
		(property "Val" "10u"
			(at 0 0 90)
			(unlocked yes)
			(layer "F.Fab")
			(hide yes)
			(effects
				(font
					(size 1 1)
					(thickness 0.15)
				)
			)
		)
		(property "Voltage" "6.3V"
			(at 0 0 90)
			(unlocked yes)
			(layer "F.Fab")
			(hide yes)
			(effects
				(font
					(size 1 1)
					(thickness 0.15)
				)
			)
		)
		(property "Dielectric" "X5R"
			(at 0 0 90)
			(unlocked yes)
			(layer "F.Fab")
			(hide yes)
			(effects
				(font
					(size 1 1)
					(thickness 0.15)
				)
			)
		)
		(sheetname "/Debug FTDI + VNA/")
		(sheetfile "debug-ftdi.kicad_sch")
		(attr smd)
		(fp_rect
			(start -0.925 -0.47)
			(end 0.925 0.47)
			(stroke
				(width 0.05)
				(type default)
			)
			(fill no)
			(layer "F.CrtYd")
		)
		(fp_line
			(start 0.504 -0.25)
			(end 0.504 0.248)
			(stroke
				(width 0.15)
				(type solid)
			)
			(layer "F.Fab")
		)
		(fp_line
			(start -0.494 -0.25)
			(end 0.504 -0.25)
			(stroke
				(width 0.15)
				(type solid)
			)
			(layer "F.Fab")
		)
		(fp_line
			(start 0.504 0.248)
			(end -0.494 0.248)
			(stroke
				(width 0.15)
				(type solid)
			)
			(layer "F.Fab")
		)
		(fp_line
			(start -0.494 0.248)
			(end -0.494 -0.25)
			(stroke
				(width 0.15)
				(type solid)
			)
			(layer "F.Fab")
		)
		(fp_text user "${REFERENCE}"
			(at -0.939 4.599 90)
			(layer "F.Fab")
			(effects
				(font
					(size 0.7 0.7)
					(thickness 0.15)
				)
				(justify left bottom)
			)
		)
		(fp_text user "License: Apache-2.0"
			(at -0.939 5.799 90)
			(layer "F.Fab")
			(effects
				(font
					(size 0.7 0.7)
					(thickness 0.15)
				)
				(justify left bottom)
			)
		)
		(fp_text user "Author: Antmicro"
			(at -0.939 3.399 90)
			(layer "F.Fab")
			(effects
				(font
					(size 0.7 0.7)
					(thickness 0.15)
				)
				(justify left bottom)
			)
		)
		(pad "1" smd roundrect
			(at -0.48 0 90)
			(size 0.59 0.64)
			(layers "F.Cu" "F.Mask" "F.Paste")
			(roundrect_rratio 0.25)
			(net 1 "GND")
			(pintype "passive")
		)
		(pad "2" smd roundrect
			(at 0.48 0 90)
			(size 0.59 0.64)
			(layers "F.Cu" "F.Mask" "F.Paste")
			(roundrect_rratio 0.25)
			(net 6 "/Debug FTDI + VNA/FTDI_3V3")
			(pintype "passive")
		)
	)
	(footprint "antmicro-footprints:R_0402_1005Metric"
		(layer "F.Cu")
		(at 260.5055 158.671 -90)
		(descr "Resistor SMD 0402")
		(tags "resistor SMD 0402")
		(property "Reference" "R168"
			(at 2.029 -0.4945 90)
			(layer "F.SilkS")
			(effects
				(font
					(size 0.7 0.7)
					(thickness 0.15)
				)
				(justify right bottom)
			)
		)
		(property "Value" "R_0R_0402"
			(at -1.011843 1.772047 90)
			(layer "F.Fab")
			(effects
				(font
					(size 0.7 0.7)
					(thickness 0.15)
				)
				(justify right bottom)
			)
		)
		(property "Datasheet" "https://industrial.panasonic.com/cdbs/www-data/pdf/RDA0000/AOA0000C301.pdf"
			(at 0 0 270)
			(layer "F.Fab")
			(hide yes)
			(effects
				(font
					(size 1.27 1.27)
					(thickness 0.15)
				)
			)
		)
		(property "Manufacturer" "Panasonic"
			(at 0 0 270)
			(unlocked yes)
			(layer "F.Fab")
			(hide yes)
			(effects
				(font
					(size 1 1)
					(thickness 0.15)
				)
			)
		)
		(property "MPN" "ERJ2GE0R00X"
			(at 0 0 270)
			(unlocked yes)
			(layer "F.Fab")
			(hide yes)
			(effects
				(font
					(size 1 1)
					(thickness 0.15)
				)
			)
		)
		(property "Val" "0R"
			(at 0 0 270)
			(unlocked yes)
			(layer "F.Fab")
			(hide yes)
			(effects
				(font
					(size 1 1)
					(thickness 0.15)
				)
			)
		)
		(property "License" "Apache-2.0"
			(at 0 0 270)
			(unlocked yes)
			(layer "F.Fab")
			(hide yes)
			(effects
				(font
					(size 1 1)
					(thickness 0.15)
				)
			)
		)
		(property "Author" "Antmicro"
			(at 0 0 270)
			(unlocked yes)
			(layer "F.Fab")
			(hide yes)
			(effects
				(font
					(size 1 1)
					(thickness 0.15)
				)
			)
		)
		(property "Tolerance" "~"
			(at 0 0 270)
			(unlocked yes)
			(layer "F.Fab")
			(hide yes)
			(effects
				(font
					(size 1 1)
					(thickness 0.15)
				)
			)
		)
		(property "Current" "1A"
			(at 0 0 270)
			(unlocked yes)
			(layer "F.Fab")
			(hide yes)
			(effects
				(font
					(size 1 1)
					(thickness 0.15)
				)
			)
		)
		(sheetname "/Supply/DC-DC IO/")
		(sheetfile "dc-dc-io.kicad_sch")
		(attr smd)
		(fp_rect
			(start -0.925 -0.47)
			(end 0.925 0.47)
			(stroke
				(width 0.05)
				(type default)
			)
			(fill no)
			(layer "F.CrtYd")
		)
		(fp_rect
			(start -0.5 -0.25)
			(end 0.5 0.25)
			(stroke
				(width 0.15)
				(type solid)
			)
			(fill no)
			(layer "F.Fab")
		)
		(fp_text user "Author: Antmicro"
			(at -0.95 4.169 270)
			(layer "F.Fab")
			(effects
				(font
					(size 0.7 0.7)
					(thickness 0.15)
				)
				(justify left bottom)
			)
		)
		(fp_text user "License: Apache-2.0"
			(at -0.95 5.169 270)
			(layer "F.Fab")
			(effects
				(font
					(size 0.7 0.7)
					(thickness 0.15)
				)
				(justify left bottom)
			)
		)
		(fp_text user "${REFERENCE}"
			(at -0.95 3.168 270)
			(layer "F.Fab")
			(effects
				(font
					(size 0.7 0.7)
					(thickness 0.15)
				)
				(justify left bottom)
			)
		)
		(pad "1" smd roundrect
			(at -0.48 0 270)
			(size 0.59 0.64)
			(layers "F.Cu" "F.Mask" "F.Paste")
			(roundrect_rratio 0.25)
			(net 719 "/Supply/DC-DC IO/FB8")
			(pintype "passive")
		)
		(pad "2" smd roundrect
			(at 0.48 0 270)
			(size 0.59 0.64)
			(layers "F.Cu" "F.Mask" "F.Paste")
			(roundrect_rratio 0.25)
			(net 159 "/Supply/DC-DC IO/1V2_local")
			(pintype "passive")
		)
	)
	(footprint "antmicro-footprints:SOD-523"
		(layer "F.Cu")
		(at 108.84 146.96)
		(property "Reference" "D18"
			(at 1.11 0.44 0)
			(layer "F.SilkS")
			(effects
				(font
					(size 0.7 0.7)
					(thickness 0.15)
				)
				(justify left bottom)
			)
		)
		(property "Value" "PESD5V0X1UB"
			(at 0 1.499 0)
			(layer "F.Fab")
			(effects
				(font
					(size 0.7 0.7)
					(thickness 0.15)
				)
				(justify left bottom)
			)
		)
		(property "Datasheet" "https://assets.nexperia.com/documents/data-sheet/PESD5V0X1UB.pdf"
			(at 0 0 0)
			(layer "F.Fab")
			(hide yes)
			(effects
				(font
					(size 1.27 1.27)
					(thickness 0.15)
				)
			)
		)
		(property "MPN" "PESD5V0X1UB,135"
			(at 0 0 0)
			(unlocked yes)
			(layer "F.Fab")
			(hide yes)
			(effects
				(font
					(size 1 1)
					(thickness 0.15)
				)
			)
		)
		(property "Manufacturer" "Nexperia"
			(at 0 0 0)
			(unlocked yes)
			(layer "F.Fab")
			(hide yes)
			(effects
				(font
					(size 1 1)
					(thickness 0.15)
				)
			)
		)
		(property "Author" "Antmicro"
			(at 0 0 0)
			(unlocked yes)
			(layer "F.Fab")
			(hide yes)
			(effects
				(font
					(size 1 1)
					(thickness 0.15)
				)
			)
		)
		(property "License" "Apache-2.0"
			(at 0 0 0)
			(unlocked yes)
			(layer "F.Fab")
			(hide yes)
			(effects
				(font
					(size 1 1)
					(thickness 0.15)
				)
			)
		)
		(sheetname "/Debug FTDI + VNA/")
		(sheetfile "debug-ftdi.kicad_sch")
		(attr smd)
		(fp_line
			(start -0.35 -0.5)
			(end -0.35 0.5)
			(stroke
				(width 0.15)
				(type solid)
			)
			(layer "F.SilkS")
		)
		(fp_rect
			(start -1 -0.6)
			(end 1 0.6)
			(stroke
				(width 0.05)
				(type solid)
			)
			(fill no)
			(layer "F.CrtYd")
		)
		(fp_line
			(start -0.652 -0.425)
			(end 0.65 -0.425)
			(stroke
				(width 0.15)
				(type solid)
			)
			(layer "F.Fab")
		)
		(fp_line
			(start -0.652 0.423)
			(end -0.652 -0.425)
			(stroke
				(width 0.15)
				(type solid)
			)
			(layer "F.Fab")
		)
		(fp_line
			(start -0.652 0.423)
			(end 0.65 0.423)
			(stroke
				(width 0.15)
				(type solid)
			)
			(layer "F.Fab")
		)
		(fp_line
			(start -0.35 -0.4)
			(end -0.35 0.4)
			(stroke
				(width 0.15)
				(type solid)
			)
			(layer "F.Fab")
		)
		(fp_line
			(start 0.65 -0.425)
			(end 0.65 0.423)
			(stroke
				(width 0.15)
				(type solid)
			)
			(layer "F.Fab")
		)
		(fp_text user "Author: Antmicro"
			(at -1.276 4.7 0)
			(layer "F.Fab")
			(effects
				(font
					(size 0.7 0.7)
					(thickness 0.15)
				)
				(justify left bottom)
			)
		)
		(fp_text user "License: Apache-2.0"
			(at -1.276 5.9 0)
			(layer "F.Fab")
			(effects
				(font
					(size 0.7 0.7)
					(thickness 0.15)
				)
				(justify left bottom)
			)
		)
		(fp_text user "${REFERENCE}"
			(at -1.276 3.499 0)
			(layer "F.Fab")
			(effects
				(font
					(size 0.7 0.7)
					(thickness 0.15)
				)
				(justify left bottom)
			)
		)
		(pad "1" smd roundrect
			(at -0.701 0)
			(size 0.5 0.6)
			(layers "F.Cu" "F.Mask" "F.Paste")
			(roundrect_rratio 0.25)
			(net 2 "/Debug FTDI + VNA/VBUS")
			(pinfunction "C")
			(pintype "passive")
		)
		(pad "2" smd roundrect
			(at 0.699 0)
			(size 0.5 0.6)
			(layers "F.Cu" "F.Mask" "F.Paste")
			(roundrect_rratio 0.25)
			(net 1 "GND")
			(pinfunction "A")
			(pintype "passive")
		)
	)
	(footprint "antmicro-footprints:NetTie-2_SMD_Pad0.127mm"
		(layer "F.Cu")
		(at 246.887 150.451)
		(descr "Net tie, 2 pin, 0.127mm  SMD pads")
		(tags "net tie")
		(property "Reference" "NT6"
			(at -0.128 -1.345 0)
			(layer "F.SilkS")
			(hide yes)
			(effects
				(font
					(size 0.7 0.7)
					(thickness 0.15)
				)
				(justify left bottom)
			)
		)
		(property "Value" "Net-Tie_P0.127mm"
			(at 0 1.199 0)
			(layer "F.Fab")
			(effects
				(font
					(size 0.7 0.7)
					(thickness 0.15)
				)
				(justify left bottom)
			)
		)
		(property "MPN" ""
			(at 0 0 0)
			(unlocked yes)
			(layer "F.Fab")
			(hide yes)
			(effects
				(font
					(size 1 1)
					(thickness 0.15)
				)
			)
		)
		(property "Manufacturer" ""
			(at 0 0 0)
			(unlocked yes)
			(layer "F.Fab")
			(hide yes)
			(effects
				(font
					(size 1 1)
					(thickness 0.15)
				)
			)
		)
		(property "Author" "Antmicro"
			(at 0 0 0)
			(unlocked yes)
			(layer "F.Fab")
			(hide yes)
			(effects
				(font
					(size 1 1)
					(thickness 0.15)
				)
			)
		)
		(property "License" "Apache-2.0"
			(at 0 0 0)
			(unlocked yes)
			(layer "F.Fab")
			(hide yes)
			(effects
				(font
					(size 1 1)
					(thickness 0.15)
				)
			)
		)
		(property ki_fp_filters "Net*Tie*")
		(sheetname "/Supply/DC-DC IO/")
		(sheetfile "dc-dc-io.kicad_sch")
		(attr through_hole exclude_from_pos_files exclude_from_bom)
		(net_tie_pad_groups "1, 2")
		(fp_poly
			(pts
				(xy -0.0635 -0.0635) (xy 0.0625 -0.0635) (xy 0.0625 0.0635) (xy -0.0635 0.0635)
			)
			(stroke
				(width 0)
				(type solid)
			)
			(fill yes)
			(layer "F.Cu")
		)
		(fp_poly
			(pts
				(xy 0.2 -0.16) (xy 0.29 -0.07) (xy 0.29 0.07) (xy 0.2 0.16) (xy -0.2 0.16) (xy -0.29 0.07) (xy -0.29 -0.06)
				(xy -0.19 -0.16)
			)
			(stroke
				(width 0.05)
				(type solid)
			)
			(fill no)
			(layer "F.CrtYd")
		)
		(fp_text user "Author: Antmicro"
			(at -0.128 4.4 0)
			(layer "F.Fab")
			(effects
				(font
					(size 0.7 0.7)
					(thickness 0.15)
				)
				(justify left bottom)
			)
		)
		(fp_text user "License: Apache-2.0"
			(at -0.128 5.6 0)
			(layer "F.Fab")
			(effects
				(font
					(size 0.7 0.7)
					(thickness 0.15)
				)
				(justify left bottom)
			)
		)
		(fp_text user "${REFERENCE}"
			(at -0.128 3.2 0)
			(layer "F.Fab")
			(effects
				(font
					(size 0.7 0.7)
					(thickness 0.15)
				)
				(justify left bottom)
			)
		)
		(pad "1" smd roundrect
			(at -0.127 0 180)
			(size 0.127 0.127)
			(layers "F.Cu")
			(roundrect_rratio 0.5)
			(chamfer_ratio 0)
			(chamfer top_left bottom_left)
			(net 686 "/Supply/DC-DC IO/5V_SEN_+")
			(pinfunction "1")
			(pintype "passive")
		)
		(pad "2" smd roundrect
			(at 0.126 0)
			(size 0.127 0.127)
			(layers "F.Cu")
			(roundrect_rratio 0.5)
			(chamfer_ratio 0)
			(chamfer top_left bottom_left)
			(net 46 "/Supply/DC-DC IO/5V_local")
			(pinfunction "2")
			(pintype "passive")
		)
	)
	(footprint "antmicro-footprints:antmicro-logo_scaled_30mm"
		(layer "F.Cu")
		(at 155.9 120.89)
		(property "Reference" "G***"
			(at -7.7 -10.3 0)
			(layer "F.SilkS")
			(hide yes)
			(effects
				(font
					(size 1.524 1.524)
					(thickness 0.3)
				)
			)
		)
		(property "Value" "LOGO"
			(at -5.3 10.1 0)
			(layer "F.SilkS")
			(hide yes)
			(effects
				(font
					(size 1.524 1.524)
					(thickness 0.3)
				)
			)
		)
		(attr exclude_from_pos_files exclude_from_bom allow_soldermask_bridges)
		(fp_poly
			(pts
				(xy 6.912132 1.55682) (xy 6.345204 1.55682) (xy 6.345204 -1.797504) (xy 6.912132 -1.797504) (xy 6.912132 1.55682)
			)
			(stroke
				(width 0.00279)
				(type solid)
			)
			(fill yes)
			(layer "F.Cu")
		)
		(fp_poly
			(pts
				(xy 11.340704 -1.841043) (xy 11.383146 -1.835075) (xy 11.399626 -1.825218) (xy 11.400312 -1.821945)
				(xy 11.393617 -1.787258) (xy 11.375745 -1.719809) (xy 11.35001 -1.631803) (xy 11.338272 -1.593625)
				(xy 11.306574 -1.497032) (xy 11.282387 -1.438676) (xy 11.261494 -1.411028) (xy 11.239676 -1.40656)
				(xy 11.234259 -1.407963) (xy 11.087402 -1.439293) (xy 10.923404 -1.449612) (xy 10.760846 -1.43919)
				(xy 10.618313 -1.408295) (xy 10.591259 -1.398688) (xy 10.526298 -1.373477) (xy 10.526298 1.55682)
				(xy 9.95937 1.55682) (xy 9.95937 -1.627357) (xy 10.130629 -1.688724) (xy 10.279454 -1.738722) (xy 10.415589 -1.775887)
				(xy 10.552002 -1.802432) (xy 10.701659 -1.820566) (xy 10.877526 -1.832501) (xy 11.004644 -1.837729)
				(xy 11.156748 -1.842159) (xy 11.267003 -1.843334) (xy 11.340704 -1.841043)
			)
			(stroke
				(width 0.00279)
				(type solid)
			)
			(fill yes)
			(layer "F.Cu")
		)
		(fp_poly
			(pts
				(xy 0.286882 -2.696334) (xy 0.291195 -2.633826) (xy 0.294644 -2.538397) (xy 0.296982 -2.41721) (xy 0.297958 -2.277426)
				(xy 0.297972 -2.258133) (xy 0.297972 -1.797504) (xy 0.8649 -1.797504) (xy 0.8649 -1.419552) (xy 0.297972 -1.419552)
				(xy 0.297972 0.887973) (xy 0.35171 0.989594) (xy 0.420809 1.086396) (xy 0.509669 1.146307) (xy 0.625356 1.172892)
				(xy 0.717312 1.174035) (xy 0.864999 1.167057) (xy 0.864949 1.348733) (xy 0.860772 1.460716) (xy 0.84846 1.528604)
				(xy 0.835373 1.548939) (xy 0.800261 1.557487) (xy 0.729644 1.565503) (xy 0.635257 1.571858) (xy 0.569625 1.57448)
				(xy 0.440081 1.575664) (xy 0.342385 1.569249) (xy 0.261533 1.553675) (xy 0.208325 1.536992) (xy 0.064544 1.469148)
				(xy -0.049904 1.37486) (xy -0.144592 1.245474) (xy -0.174468 1.191014) (xy -0.257145 1.030172) (xy -0.26386 -0.19469)
				(xy -0.270574 -1.419552) (xy -0.646908 -1.419552) (xy -0.646908 -1.797504) (xy -0.268956 -1.797504)
				(xy -0.268956 -2.551783) (xy -0.001508 -2.635272) (xy 0.104164 -2.667861) (xy 0.192964 -2.694497)
				(xy 0.255428 -2.712391) (xy 0.281956 -2.718762) (xy 0.286882 -2.696334)
			)
			(stroke
				(width 0.00279)
				(type solid)
			)
			(fill yes)
			(layer "F.Cu")
		)
		(fp_poly
			(pts
				(xy -2.136607 -1.83175) (xy -2.010904 -1.828463) (xy -1.914265 -1.822037) (xy -1.837617 -1.811764)
				(xy -1.771885 -1.796939) (xy -1.74634 -1.789492) (xy -1.532158 -1.70751) (xy -1.359129 -1.605683)
				(xy -1.224749 -1.482223) (xy -1.136379 -1.354088) (xy -1.108163 -1.301039) (xy -1.084174 -1.250965)
				(xy -1.064068 -1.19968) (xy -1.047504 -1.142994) (xy -1.034138 -1.076717) (xy -1.023628 -0.996662)
				(xy -1.015631 -0.89864) (xy -1.009804 -0.778462) (xy -1.005806 -0.63194) (xy -1.003292 -0.454884)
				(xy -1.001922 -0.243105) (xy -1.001351 0.007584) (xy -1.001238 0.298006) (xy -1.001238 1.55682)
				(xy -1.568166 1.55682) (xy -1.568166 0.309141) (xy -1.568286 0.015459) (xy -1.56889 -0.234942) (xy -1.570346 -0.44602)
				(xy -1.573022 -0.621739) (xy -1.577286 -0.766058) (xy -1.583506 -0.882939) (xy -1.592049 -0.976344)
				(xy -1.603283 -1.050233) (xy -1.617577 -1.108567) (xy -1.635297 -1.155309) (xy -1.656812 -1.194418)
				(xy -1.682489 -1.229857) (xy -1.712696 -1.265585) (xy -1.714581 -1.267734) (xy -1.812287 -1.355903)
				(xy -1.931432 -1.417802) (xy -2.082042 -1.458151) (xy -2.138368 -1.46726) (xy -2.29674 -1.477433)
				(xy -2.472019 -1.46882) (xy -2.642327 -1.443409) (xy -2.766455 -1.410218) (xy -2.855565 -1.37937)
				(xy -2.861649 0.088725) (xy -2.867734 1.55682) (xy -3.434304 1.55682) (xy -3.434304 -1.626184) (xy -3.215801 -1.697862)
				(xy -3.065439 -1.745385) (xy -2.937666 -1.780369) (xy -2.819819 -1.804679) (xy -2.699238 -1.820176)
				(xy -2.563261 -1.828726) (xy -2.399228 -1.832192) (xy -2.300448 -1.832603) (xy -2.136607 -1.83175)
			)
			(stroke
				(width 0.00279)
				(type solid)
			)
			(fill yes)
			(layer "F.Cu")
		)
		(fp_poly
			(pts
				(xy 4.729063 -1.8271) (xy 4.959571 -1.776882) (xy 5.157893 -1.693771) (xy 5.323148 -1.578206) (xy 5.454451 -1.43062)
				(xy 5.517493 -1.325064) (xy 5.542461 -1.274165) (xy 5.563676 -1.22495) (xy 5.581442 -1.173239) (xy 5.596064 -1.114853)
				(xy 5.607848 -1.045613) (xy 5.617099 -0.96134) (xy 5.624121 -0.857855) (xy 5.629219 -0.730978) (xy 5.632699 -0.576531)
				(xy 5.634866 -0.390333) (xy 5.636025 -0.168207) (xy 5.63648 0.094028) (xy 5.636544 0.306017) (xy 5.636544 1.55682)
				(xy 5.071143 1.55682) (xy 5.064474 0.251704) (xy 5.057805 -1.053411) (xy 4.988868 -1.177834) (xy 4.895109 -1.301546)
				(xy 4.773134 -1.393175) (xy 4.629913 -1.452165) (xy 4.472416 -1.477959) (xy 4.307613 -1.470001)
				(xy 4.142475 -1.427734) (xy 3.98397 -1.350603) (xy 3.870799 -1.267078) (xy 3.770406 -1.179651) (xy 3.770406 1.55682)
				(xy 3.203478 1.55682) (xy 3.203478 0.278067) (xy 3.203064 -0.042779) (xy 3.201801 -0.31793) (xy 3.19966 -0.548927)
				(xy 3.196609 -0.737311) (xy 3.192619 -0.884624) (xy 3.187659 -0.992408) (xy 3.181699 -1.062204)
				(xy 3.176515 -1.09068) (xy 3.113168 -1.224355) (xy 3.012925 -1.331319) (xy 2.878719 -1.410269) (xy 2.713483 -1.459907)
				(xy 2.52015 -1.478929) (xy 2.324287 -1.468768) (xy 2.217475 -1.455784) (xy 2.140831 -1.44347) (xy 2.077483 -1.428123)
				(xy 2.010555 -1.406041) (xy 1.969229 -1.39085) (xy 1.904268 -1.366577) (xy 1.904268 1.55682) (xy 1.360962 1.55682)
				(xy 1.360962 -1.629932) (xy 1.585996 -1.702017) (xy 1.839432 -1.773628) (xy 2.076192 -1.818337)
				(xy 2.316338 -1.838944) (xy 2.565684 -1.838752) (xy 2.765772 -1.826957) (xy 2.929729 -1.804535)
				(xy 3.068058 -1.768421) (xy 3.191262 -1.715547) (xy 3.309844 -1.64285) (xy 3.35863 -1.60731) (xy 3.513772 -1.489884)
				(xy 3.612561 -1.570037) (xy 3.803824 -1.696423) (xy 4.018585 -1.783662) (xy 4.258747 -1.832362)
				(xy 4.467255 -1.843989) (xy 4.729063 -1.8271)
			)
			(stroke
				(width 0.00279)
				(type solid)
			)
			(fill yes)
			(layer "F.Cu")
		)
		(fp_poly
			(pts
				(xy 13.011 -1.828598) (xy 13.222157 -1.780519) (xy 13.409082 -1.697802) (xy 13.577941 -1.578087)
				(xy 13.656079 -1.505081) (xy 13.8057 -1.322147) (xy 13.924227 -1.106958) (xy 14.012192 -0.85815)
				(xy 14.070128 -0.574357) (xy 14.090393 -0.390545) (xy 14.101846 -0.06018) (xy 14.082517 0.248736)
				(xy 14.033408 0.533287) (xy 13.955524 0.790553) (xy 13.849866 1.017617) (xy 13.717438 1.211561)
				(xy 13.559243 1.369467) (xy 13.461074 1.440241) (xy 13.306254 1.517112) (xy 13.121999 1.574401)
				(xy 12.922961 1.609506) (xy 12.723792 1.619827) (xy 12.542357 1.603344) (xy 12.30932 1.539496) (xy 12.102782 1.436939)
				(xy 11.923619 1.296654) (xy 11.772705 1.119624) (xy 11.650914 0.906828) (xy 11.559121 0.659249)
				(xy 11.509091 0.443636) (xy 11.467044 0.123703) (xy 11.458222 -0.133265) (xy 12.022913 -0.133265)
				(xy 12.033208 0.130412) (xy 12.06476 0.384026) (xy 12.117594 0.617116) (xy 12.189245 0.813805) (xy 12.281708 0.968837)
				(xy 12.398869 1.090076) (xy 12.534807 1.175098) (xy 12.683598 1.221477) (xy 12.839322 1.226788)
				(xy 12.996055 1.188608) (xy 13.048162 1.165468) (xy 13.180842 1.078195) (xy 13.290857 0.958674)
				(xy 13.37932 0.804507) (xy 13.447344 0.613298) (xy 13.496041 0.382646) (xy 13.524253 0.1395) (xy 13.536499 -0.156891)
				(xy 13.524426 -0.432929) (xy 13.488984 -0.684487) (xy 13.431119 -0.907435) (xy 13.351781 -1.097642)
				(xy 13.251917 -1.250979) (xy 13.189895 -1.316899) (xy 13.054995 -1.412386) (xy 12.90868 -1.465731)
				(xy 12.757488 -1.478493) (xy 12.607953 -1.452231) (xy 12.466612 -1.388504) (xy 12.340002 -1.288871)
				(xy 12.234658 -1.15489) (xy 12.193793 -1.079317) (xy 12.119314 -0.880028) (xy 12.065991 -0.648948)
				(xy 12.033849 -0.396539) (xy 12.022913 -0.133265) (xy 11.458222 -0.133265) (xy 11.456366 -0.187331)
				(xy 11.476106 -0.484529) (xy 11.525315 -0.762953) (xy 11.603043 -1.017667) (xy 11.70834 -1.243733)
				(xy 11.840256 -1.436213) (xy 11.879302 -1.480693) (xy 12.04917 -1.632047) (xy 12.241107 -1.742502)
				(xy 12.456488 -1.812618) (xy 12.696687 -1.842957) (xy 12.769446 -1.844399) (xy 13.011 -1.828598)
			)
			(stroke
				(width 0.00279)
				(type solid)
			)
			(fill yes)
			(layer "F.Cu")
		)
		(fp_poly
			(pts
				(xy 8.814213 -1.840483) (xy 8.969759 -1.825412) (xy 9.056281 -1.809134) (xy 9.145452 -1.783461)
				(xy 9.241206 -1.748594) (xy 9.331151 -1.709938) (xy 9.402898 -1.672901) (xy 9.444054 -1.642889)
				(xy 9.447346 -1.638505) (xy 9.444801 -1.609133) (xy 9.427786 -1.551422) (xy 9.401635 -1.478945)
				(xy 9.371683 -1.405273) (xy 9.343265 -1.343977) (xy 9.321716 -1.308629) (xy 9.316165 -1.304791)
				(xy 9.28701 -1.3133) (xy 9.228967 -1.336582) (xy 9.170199 -1.362544) (xy 8.989584 -1.425274) (xy 8.810705 -1.449653)
				(xy 8.641862 -1.435423) (xy 8.493873 -1.383637) (xy 8.370199 -1.295153) (xy 8.256869 -1.165361)
				(xy 8.157444 -0.999709) (xy 8.075486 -0.803644) (xy 8.04073 -0.690661) (xy 8.0133 -0.551431) (xy 7.995672 -0.37999)
				(xy 7.987846 -0.190341) (xy 7.989822 0.003512) (xy 8.001598 0.187565) (xy 8.023174 0.347814) (xy 8.040794 0.426604)
				(xy 8.120911 0.661281) (xy 8.221774 0.853813) (xy 8.343673 1.00464) (xy 8.4869 1.114204) (xy 8.498013 1.120496)
				(xy 8.570319 1.157192) (xy 8.633963 1.178299) (xy 8.70729 1.187849) (xy 8.808641 1.18987) (xy 8.813703 1.189851)
				(xy 8.920044 1.185178) (xy 9.013384 1.169314) (xy 9.108059 1.137943) (xy 9.218407 1.086747) (xy 9.300948 1.043176)
				(xy 9.311241 1.049795) (xy 9.329071 1.080783) (xy 9.356659 1.141006) (xy 9.396222 1.235333) (xy 9.449978 1.368632)
				(xy 9.455034 1.381317) (xy 9.441745 1.40673) (xy 9.393674 1.442381) (xy 9.32065 1.48296) (xy 9.232503 1.523157)
				(xy 9.139062 1.557662) (xy 9.114694 1.565169) (xy 8.987614 1.592214) (xy 8.834546 1.609553) (xy 8.675805 1.616006)
				(xy 8.531704 1.610388) (xy 8.471184 1.602631) (xy 8.382682 1.580174) (xy 8.27615 1.542853) (xy 8.175909 1.499329)
				(xy 7.979839 1.377324) (xy 7.810569 1.217033) (xy 7.668836 1.019577) (xy 7.555379 0.786076) (xy 7.470937 0.517652)
				(xy 7.442822 0.386949) (xy 7.422315 0.232254) (xy 7.411523 0.048978) (xy 7.410053 -0.149598) (xy 7.417508 -0.350189)
				(xy 7.433495 -0.539511) (xy 7.457618 -0.704283) (xy 7.477921 -0.793551) (xy 7.569718 -1.055031)
				(xy 7.690906 -1.282895) (xy 7.839972 -1.475439) (xy 8.015408 -1.630955) (xy 8.215702 -1.747738)
				(xy 8.375078 -1.807062) (xy 8.499369 -1.831256) (xy 8.651582 -1.842414) (xy 8.814213 -1.840483)
			)
			(stroke
				(width 0.00279)
				(type solid)
			)
			(fill yes)
			(layer "F.Cu")
		)
		(fp_poly
			(pts
				(xy -5.050123 -1.828751) (xy -4.900576 -1.800755) (xy -4.730837 -1.748715) (xy -4.593875 -1.684132)
				(xy -4.475494 -1.599519) (xy -4.417289 -1.545833) (xy -4.33145 -1.438632) (xy -4.25438 -1.301382)
				(xy -4.194656 -1.151275) (xy -4.167075 -1.044179) (xy -4.161601 -0.991002) (xy -4.156686 -0.894515)
				(xy -4.152404 -0.758651) (xy -4.14883 -0.587342) (xy -4.146038 -0.38452) (xy -4.144102 -0.154118)
				(xy -4.143096 0.099932) (xy -4.142964 0.236107) (xy -4.142964 1.389255) (xy -4.253676 1.438228)
				(xy -4.451908 1.509446) (xy -4.681546 1.56447) (xy -4.929024 1.601579) (xy -5.180775 1.61905) (xy -5.423232 1.615164)
				(xy -5.551117 1.602857) (xy -5.801683 1.552934) (xy -6.015853 1.473578) (xy -6.193196 1.365257)
				(xy -6.33328 1.228443) (xy -6.435674 1.063605) (xy -6.499947 0.871213) (xy -6.525669 0.651739) (xy -6.524424 0.541559)
				(xy -6.521414 0.520731) (xy -5.980195 0.520731) (xy -5.975801 0.716157) (xy -5.933333 0.885059)
				(xy -5.853697 1.026031) (xy -5.737804 1.137664) (xy -5.58656 1.218552) (xy -5.514208 1.242597) (xy -5.421778 1.258401)
				(xy -5.297997 1.265595) (xy -5.157857 1.264744) (xy -5.016352 1.25641) (xy -4.888475 1.241159) (xy -4.789219 1.219554)
				(xy -4.774853 1.214784) (xy -4.662648 1.174427) (xy -4.662648 -0.312718) (xy -4.798474 -0.29633)
				(xy -4.885159 -0.282693) (xy -4.997384 -0.260692) (xy -5.115103 -0.234352) (xy -5.152116 -0.225299)
				(xy -5.394278 -0.150849) (xy -5.593128 -0.059371) (xy -5.749805 0.050162) (xy -5.865449 0.178776)
				(xy -5.941198 0.327497) (xy -5.978194 0.497353) (xy -5.980195 0.520731) (xy -6.521414 0.520731)
				(xy -6.493668 0.328754) (xy -6.422351 0.139568) (xy -6.30958 -0.028039) (xy -6.245225 -0.096814)
				(xy -6.103026 -0.209801) (xy -5.920199 -0.31379) (xy -5.702882 -0.406508) (xy -5.457208 -0.48568)
				(xy -5.189315 -0.549035) (xy -4.905337 -0.594299) (xy -4.901094 -0.594815) (xy -4.656202 -0.624496)
				(xy -4.67036 -0.825112) (xy -4.697756 -1.014305) (xy -4.7521 -1.166118) (xy -4.835845 -1.283573)
				(xy -4.951447 -1.369689) (xy -5.101362 -1.427488) (xy -5.173118 -1.443664) (xy -5.368453 -1.460676)
				(xy -5.585568 -1.444404) (xy -5.814301 -1.396375) (xy -6.044491 -1.318113) (xy -6.064756 -1.309714)
				(xy -6.137401 -1.280895) (xy -6.190621 -1.263081) (xy -6.21177 -1.260016) (xy -6.223817 -1.284953)
				(xy -6.246487 -1.340557) (xy -6.274545 -1.412991) (xy -6.30276 -1.488418) (xy -6.325898 -1.553)
				(xy -6.338724 -1.592902) (xy -6.33981 -1.598556) (xy -6.320033 -1.613975) (xy -6.268692 -1.64124)
				(xy -6.210986 -1.6681) (xy -5.998934 -1.744812) (xy -5.763807 -1.80055) (xy -5.51862 -1.833998)
				(xy -5.276387 -1.843837) (xy -5.050123 -1.828751)
			)
			(stroke
				(width 0.00279)
				(type solid)
			)
			(fill yes)
			(layer "F.Cu")
		)
		(fp_poly
			(pts
				(xy -11.634962 -4.909269) (xy -11.537229 -4.886866) (xy -11.535595 -4.886192) (xy -11.504855 -4.870152)
				(xy -11.436833 -4.832523) (xy -11.335138 -4.775379) (xy -11.203377 -4.700793) (xy -11.045161 -4.610843)
				(xy -10.864096 -4.507601) (xy -10.663791 -4.393143) (xy -10.447855 -4.269542) (xy -10.219896 -4.138875)
				(xy -9.983523 -4.003215) (xy -9.742343 -3.864638) (xy -9.499965 -3.725217) (xy -9.259997 -3.587029)
				(xy -9.026048 -3.452146) (xy -8.801727 -3.322644) (xy -8.590641 -3.200598) (xy -8.396399 -3.088082)
				(xy -8.222609 -2.98717) (xy -8.07288 -2.899939) (xy -7.950819 -2.828462) (xy -7.860036 -2.774814)
				(xy -7.804139 -2.741069) (xy -7.797751 -2.737074) (xy -7.697553 -2.654792) (xy -7.620586 -2.556391)
				(xy -7.556343 -2.447109) (xy -7.549972 -0.195459) (xy -7.549017 0.235367) (xy -7.548701 0.6241)
				(xy -7.549022 0.970152) (xy -7.549975 1.272938) (xy -7.551555 1.53187) (xy -7.553759 1.746362) (xy -7.556581 1.915829)
				(xy -7.560017 2.039683) (xy -7.564064 2.117338) (xy -7.567619 2.145384) (xy -7.577264 2.180947)
				(xy -7.587545 2.213383) (xy -7.600916 2.244325) (xy -7.619829 2.275406) (xy -7.646736 2.30826) (xy -7.684091 2.344521)
				(xy -7.734346 2.385822) (xy -7.799953 2.433797) (xy -7.883366 2.49008) (xy -7.987037 2.556303) (xy -8.113418 2.634101)
				(xy -8.264963 2.725108) (xy -8.444124 2.830956) (xy -8.653354 2.953279) (xy -8.895105 3.093711)
				(xy -9.17183 3.253885) (xy -9.485981 3.435436) (xy -9.625797 3.516214) (xy -11.524839 4.613405)
				(xy -11.702004 4.622509) (xy -11.879169 4.631612) (xy -12.576018 4.230845) (xy -13.002735 3.985469)
				(xy -13.390442 3.762529) (xy -13.741039 3.560827) (xy -14.056425 3.379165) (xy -14.338499 3.216347)
				(xy -14.589159 3.071175) (xy -14.810305 2.942451) (xy -15.003836 2.828979) (xy -15.171651 2.729561)
				(xy -15.315648 2.643) (xy -15.437727 2.568099) (xy -15.539787 2.503659) (xy -15.623728 2.448485)
				(xy -15.691447 2.401378) (xy -15.744844 2.361141) (xy -15.785818 2.326577) (xy -15.816268 2.296489)
				(xy -15.838093 2.269678) (xy -15.853192 2.244949) (xy -15.863464 2.221104) (xy -15.870808 2.196945)
				(xy -15.877123 2.171275) (xy -15.883619 2.145435) (xy -15.888143 2.103987) (xy -15.892058 2.015869)
				(xy -15.895361 1.881652) (xy -15.898047 1.701907) (xy -15.900112 1.477205) (xy -15.901551 1.208115)
				(xy -15.902361 0.89521) (xy -15.902536 0.539059) (xy -15.902073 0.140233) (xy -15.901402 -0.143964)
				(xy -14.442156 -0.143964) (xy -14.442124 0.163081) (xy -14.441853 0.426492) (xy -14.441076 0.649878)
				(xy -14.439527 0.836849) (xy -14.436941 0.991014) (xy -14.433052 1.115983) (xy -14.427595 1.215365)
				(xy -14.420304 1.292771) (xy -14.410912 1.351809) (xy -14.399155 1.39609) (xy -14.384767 1.429223)
				(xy -14.367482 1.454817) (xy -14.347035 1.476482) (xy -14.323159 1.497828) (xy -14.321185 1.49955)
				(xy -14.289536 1.521118) (xy -14.221441 1.563277) (xy -14.121348 1.623467) (xy -13.993705 1.699126)
				(xy -13.842963 1.787694) (xy -13.67357 1.88661) (xy -13.489974 1.993314) (xy -13.296625 2.105246)
				(xy -13.097972 2.219844) (xy -12.898464 2.334548) (xy -12.702549 2.446797) (xy -12.514678 2.554031)
				(xy -12.339297 2.653689) (xy -12.180857 2.74321) (xy -12.043807 2.820035) (xy -11.932595 2.881601)
				(xy -11.85167 2.92535) (xy -11.805481 2.948719) (xy -11.798239 2.951643) (xy -11.739669 2.967611)
				(xy -11.698729 2.968556) (xy -11.650207 2.952973) (xy -11.621431 2.941108) (xy -11.582082 2.921398)
				(xy -11.507211 2.880786) (xy -11.401295 2.821862) (xy -11.26881 2.747214) (xy -11.114234 2.659433)
				(xy -10.942044 2.561108) (xy -10.756716 2.454828) (xy -10.562727 2.343182) (xy -10.364553 2.228759)
				(xy -10.166673 2.11415) (xy -9.973562 2.001942) (xy -9.789697 1.894726) (xy -9.619556 1.795091)
				(xy -9.467615 1.705626) (xy -9.338351 1.628921) (xy -9.236241 1.567564) (xy -9.165761 1.524145)
				(xy -9.131389 1.501254) (xy -9.130067 1.500156) (xy -9.105914 1.478431) (xy -9.08521 1.456719) (xy -9.06769 1.431407)
				(xy -9.053089 1.398882) (xy -9.04114 1.355531) (xy -9.031578 1.297741) (xy -9.024136 1.221898) (xy -9.01855 1.12439)
				(xy -9.014552 1.001603) (xy -9.011878 0.849924) (xy -9.010261 0.665741) (xy -9.009436 0.445438)
				(xy -9.009136 0.185404) (xy -9.009096 -0.117974) (xy -9.009096 -0.143964) (xy -9.0091 -0.452362)
				(xy -9.009321 -0.717103) (xy -9.010073 -0.941774) (xy -9.01167 -1.129961) (xy -9.014425 -1.285251)
				(xy -9.018653 -1.411232) (xy -9.024668 -1.511489) (xy -9.032783 -1.58961) (xy -9.043312 -1.649182)
				(xy -9.056569 -1.69379) (xy -9.072868 -1.727023) (xy -9.092523 -1.752467) (xy -9.115847 -1.773708)
				(xy -9.143156 -1.794333) (xy -9.154227 -1.80245) (xy -9.188912 -1.824767) (xy -9.260658 -1.868304)
				(xy -9.365548 -1.930764) (xy -9.499667 -2.009853) (xy -9.659099 -2.103275) (xy -9.839929 -2.208734)
				(xy -10.038241 -2.323934) (xy -10.250119 -2.44658) (xy -10.42874 -2.549657) (xy -10.683967 -2.696551)
				(xy -10.901677 -2.821355) (xy -11.085146 -2.925812) (xy -11.237649 -3.011663) (xy -11.362461 -3.080652)
				(xy -11.462857 -3.134521) (xy -11.542113 -3.175015) (xy -11.603503 -3.203875) (xy -11.650303 -3.222844)
				(xy -11.685788 -3.233665) (xy -11.713233 -3.238082) (xy -11.723096 -3.238446) (xy -11.747788 -3.236214)
				(xy -11.779117 -3.228375) (xy -11.820299 -3.213209) (xy -11.87455 -3.189) (xy -11.945086 -3.154031)
				(xy -12.035122 -3.106582) (xy -12.147874 -3.044939) (xy -12.286558 -2.967382) (xy -12.45439 -2.872194)
				(xy -12.654587 -2.757658) (xy -12.890362 -2.622057) (xy -13.055415 -2.526885) (xy -13.277555 -2.398503)
				(xy -13.488307 -2.276303) (xy -13.683963 -2.162462) (xy -13.860818 -2.059154) (xy -14.015167 -1.968555)
				(xy -14.143302 -1.892839) (xy -14.241518 -1.834183) (xy -14.30611 -1.79476) (xy -14.333212 -1.776887)
				(xy -14.354964 -1.757361) (xy -14.373609 -1.736701) (xy -14.389386 -1.711319) (xy -14.402536 -1.677626)
				(xy -14.413297 -1.632035) (xy -14.421909 -1.570958) (xy -14.428611 -1.490807) (xy -14.433642 -1.387994)
				(xy -14.437243 -1.258931) (xy -14.439651 -1.100029) (xy -14.441108 -0.907702) (xy -14.441851 -0.678361)
				(xy -14.44212 -0.408418) (xy -14.442156 -0.143964) (xy -15.901402 -0.143964) (xy -15.90128 -0.195459)
				(xy -15.900261 -0.578211) (xy -15.899381 -0.916603) (xy -15.898458 -1.213517) (xy -15.89731 -1.471836)
				(xy -15.895755 -1.694444) (xy -15.893611 -1.884222) (xy -15.890696 -2.044053) (xy -15.886827 -2.176821)
				(xy -15.881824 -2.285408) (xy -15.875504 -2.372697) (xy -15.867686 -2.441569) (xy -15.858186 -2.49491)
				(xy -15.846824 -2.535599) (xy -15.833418 -2.566522) (xy -15.817785 -2.59056) (xy -15.799743 -2.610596)
				(xy -15.779112 -2.629513) (xy -15.755708 -2.650193) (xy -15.745777 -2.659371) (xy -15.715671 -2.680398)
				(xy -15.647598 -2.723193) (xy -15.544554 -2.785985) (xy -15.409536 -2.867005) (xy -15.245541 -2.964486)
				(xy -15.055566 -3.076657) (xy -14.842607 -3.20175) (xy -14.609663 -3.337996) (xy -14.359728 -3.483626)
				(xy -14.0958 -3.636872) (xy -13.820877 -3.795963) (xy -13.791539 -3.812909) (xy -13.471051 -3.997959)
				(xy -13.18881 -4.160791) (xy -12.942164 -4.302841) (xy -12.728464 -4.425542) (xy -12.545058 -4.530328)
				(xy -12.389295 -4.618633) (xy -12.258526 -4.691893) (xy -12.150098 -4.751541) (xy -12.061361 -4.799011)
				(xy -11.989665 -4.835738) (xy -11.932359 -4.863157) (xy -11.886792 -4.8827) (xy -11.850312 -4.895803)
				(xy -11.820271 -4.9039) (xy -11.794016 -4.908426) (xy -11.768896 -4.910813) (xy -11.761531 -4.911305)
				(xy -11.634962 -4.909269)
			)
			(stroke
				(width 0.00279)
				(type solid)
			)
			(fill yes)
			(layer "F.Cu")
		)
		(fp_poly
			(pts
				(xy -11.598428 -2.080424) (xy -11.57723 -2.072066) (xy -11.468751 -2.001658) (xy -11.389638 -1.901364)
				(xy -11.34533 -1.781817) (xy -11.341267 -1.653648) (xy -11.347026 -1.622167) (xy -11.393935 -1.501154)
				(xy -11.47506 -1.410426) (xy -11.556887 -1.360523) (xy -11.65476 -1.313304) (xy -11.65476 -0.758136)
				(xy -11.242486 -0.758136) (xy -11.072717 -0.926772) (xy -10.902947 -1.095409) (xy -10.91549 -1.216935)
				(xy -10.915635 -1.219488) (xy -10.755191 -1.219488) (xy -10.728778 -1.164434) (xy -10.673757 -1.138779)
				(xy -10.607221 -1.144244) (xy -10.558024 -1.173208) (xy -10.524273 -1.228567) (xy -10.536119 -1.285278)
				(xy -10.568148 -1.325064) (xy -10.613088 -1.363188) (xy -10.650323 -1.366995) (xy -10.700942 -1.338104)
				(xy -10.704624 -1.335536) (xy -10.746388 -1.283194) (xy -10.755191 -1.219488) (xy -10.915635 -1.219488)
				(xy -10.919936 -1.294799) (xy -10.9095 -1.347615) (xy -10.878693 -1.396634) (xy -10.864682 -1.413748)
				(xy -10.778844 -1.486331) (xy -10.684406 -1.519496) (xy -10.589344 -1.517602) (xy -10.501633 -1.485007)
				(xy -10.429249 -1.426066) (xy -10.380166 -1.34514) (xy -10.36236 -1.246585) (xy -10.379014 -1.148379)
				(xy -10.432246 -1.055367) (xy -10.517668 -0.995483) (xy -10.631547 -0.971164) (xy -10.650843 -0.970734)
				(xy -10.700173 -0.969021) (xy -10.741166 -0.960188) (xy -10.782998 -0.93869) (xy -10.834845 -0.898984)
				(xy -10.905884 -0.835526) (xy -10.96366 -0.781758) (xy -11.165642 -0.592782) (xy -11.65476 -0.592782)
				(xy -11.65476 -0.21483) (xy -10.758337 -0.21483) (xy -10.723338 -0.282511) (xy -10.659408 -0.359534)
				(xy -10.571221 -0.40564) (xy -10.47149 -0.419331) (xy -10.372929 -0.399105) (xy -10.288248 -0.343464)
				(xy -10.280045 -0.334805) (xy -10.218985 -0.239159) (xy -10.198673 -0.141594) (xy -10.213428 -0.048914)
				(xy -10.257567 0.032077) (xy -10.325406 0.094573) (xy -10.411263 0.13177) (xy -10.509456 0.136864)
				(xy -10.614302 0.103049) (xy -10.63563 0.090981) (xy -10.690298 0.048218) (xy -10.724151 0.004288)
				(xy -10.726968 -0.003419) (xy -10.733524 -0.019303) (xy -10.747921 -0.031049) (xy -10.776503 -0.03928)
				(xy -10.825609 -0.044615) (xy -10.901582 -0.047677) (xy -11.010765 -0.049088) (xy -11.159498 -0.049469)
				(xy -11.196886 -0.049476) (xy -11.65476 -0.049476) (xy -11.65476 0.304854) (xy -11.169466 0.304854)
				(xy -10.777215 0.699153) (xy -10.666776 0.689665) (xy -10.54838 0.697916) (xy -10.45636 0.743895)
				(xy -10.393666 0.825779) (xy -10.377361 0.868512) (xy -10.361371 0.981493) (xy -10.388493 1.07909)
				(xy -10.447693 1.156536) (xy -10.539198 1.220541) (xy -10.636418 1.243765) (xy -10.730888 1.23049)
				(xy -10.81414 1.185001) (xy -10.877707 1.111581) (xy -10.913123 1.014512) (xy -10.914674 0.943593)
				(xy -10.75263 0.943593) (xy -10.744939 1.002359) (xy -10.722338 1.036421) (xy -10.668584 1.077858)
				(xy -10.616765 1.074443) (xy -10.568148 1.037136) (xy -10.527141 0.979502) (xy -10.530991 0.9279)
				(xy -10.5662 0.885356) (xy -10.625941 0.854578) (xy -10.683408 0.860296) (xy -10.728879 0.893103)
				(xy -10.75263 0.943593) (xy -10.914674 0.943593) (xy -10.91519 0.920035) (xy -10.901974 0.808447)
				(xy -11.242486 0.470208) (xy -11.65476 0.470208) (xy -11.65476 1.029961) (xy -11.557366 1.073879)
				(xy -11.455133 1.142987) (xy -11.384628 1.237535) (xy -11.346116 1.348001) (xy -11.33986 1.464867)
				(xy -11.366124 1.578613) (xy -11.42517 1.679718) (xy -11.517263 1.758662) (xy -11.538089 1.770152)
				(xy -11.661781 1.808862) (xy -11.793522 1.808868) (xy -11.91585 1.770223) (xy -11.918197 1.768995)
				(xy -12.015055 1.693955) (xy -12.078707 1.595232) (xy -12.109487 1.482413) (xy -12.108656 1.426899)
				(xy -11.947673 1.426899) (xy -11.938086 1.497165) (xy -11.90202 1.553977) (xy -11.87171 1.583435)
				(xy -11.784326 1.639137) (xy -11.698287 1.647711) (xy -11.61162 1.609158) (xy -11.579542 1.583435)
				(xy -11.526679 1.525013) (xy -11.505614 1.464095) (xy -11.503579 1.426899) (xy -11.524839 1.341071)
				(xy -11.580199 1.266709) (xy -11.65703 1.216575) (xy -11.725626 1.20249) (xy -11.81055 1.223976)
				(xy -11.88413 1.279925) (xy -11.933736 1.357574) (xy -11.947673 1.426899) (xy -12.108656 1.426899)
				(xy -12.107731 1.365086) (xy -12.073774 1.252838) (xy -12.007952 1.155256) (xy -11.9106 1.081929)
				(xy -11.893886 1.073879) (xy -11.796492 1.029961) (xy -11.796492 0.470208) (xy -12.208766 0.470208)
				(xy -12.549278 0.808447) (xy -12.536062 0.920035) (xy -12.541999 1.033334) (xy -12.583046 1.126506)
				(xy -12.650738 1.195267) (xy -12.736606 1.235334) (xy -12.832185 1.242424) (xy -12.929008 1.212252)
				(xy -13.003559 1.156536) (xy -13.069237 1.066034) (xy -13.090194 0.96674) (xy -13.085366 0.937646)
				(xy -12.92434 0.937646) (xy -12.919831 0.989652) (xy -12.883104 1.037136) (xy -12.825593 1.07811)
				(xy -12.774031 1.074247) (xy -12.730422 1.038088) (xy -12.700833 0.977326) (xy -12.708615 0.915658)
				(xy -12.749494 0.869261) (xy -12.778117 0.857531) (xy -12.847796 0.860939) (xy -12.884056 0.884454)
				(xy -12.92434 0.937646) (xy -13.085366 0.937646) (xy -13.073891 0.868512) (xy -13.02385 0.772676)
				(xy -12.943292 0.712009) (xy -12.83517 0.688335) (xy -12.784476 0.689665) (xy -12.674037 0.699153)
				(xy -12.281786 0.304854) (xy -11.796492 0.304854) (xy -11.796492 -0.049476) (xy -12.255529 -0.049476)
				(xy -12.413558 -0.049274) (xy -12.530739 -0.04823) (xy -12.613468 -0.045683) (xy -12.668141 -0.040976)
				(xy -12.701154 -0.033451) (xy -12.718903 -0.022447) (xy -12.727784 -0.007307) (xy -12.730078 -0.000602)
				(xy -12.768179 0.053795) (xy -12.836662 0.101408) (xy -12.918753 0.132562) (xy -12.97286 0.139412)
				(xy -13.081927 0.119662) (xy -13.16716 0.066135) (xy -13.224798 -0.01218) (xy -13.251082 -0.106295)
				(xy -13.248267 -0.138461) (xy -13.092435 -0.138461) (xy -13.085594 -0.104362) (xy -13.06173 -0.074712)
				(xy -12.999893 -0.032025) (xy -12.936774 -0.035011) (xy -12.896602 -0.062974) (xy -12.862603 -0.123872)
				(xy -12.869847 -0.163375) (xy -10.58825 -0.163375) (xy -10.579305 -0.097122) (xy -10.55465 -0.062974)
				(xy -10.494098 -0.028987) (xy -10.430729 -0.040964) (xy -10.389522 -0.074712) (xy -10.360749 -0.113869)
				(xy -10.362101 -0.149471) (xy -10.380745 -0.186917) (xy -10.430735 -0.241425) (xy -10.490836 -0.256827)
				(xy -10.549013 -0.230385) (xy -10.553393 -0.226211) (xy -10.58825 -0.163375) (xy -12.869847 -0.163375)
				(xy -12.874232 -0.187285) (xy -12.904968 -0.225051) (xy -12.965739 -0.256682) (xy -13.023234 -0.242178)
				(xy -13.070485 -0.18675) (xy -13.092435 -0.138461) (xy -13.248267 -0.138461) (xy -13.24225 -0.20722)
				(xy -13.194545 -0.305966) (xy -13.171207 -0.334805) (xy -13.086844 -0.396657) (xy -12.988403 -0.420452)
				(xy -12.887861 -0.407544) (xy -12.797197 -0.359286) (xy -12.733093 -0.285314) (xy -12.691457 -0.21483)
				(xy -11.796492 -0.21483) (xy -11.796492 -0.592782) (xy -12.28561 -0.592782) (xy -12.487592 -0.781758)
				(xy -12.574784 -0.862522) (xy -12.637071 -0.916226) (xy -12.683768 -0.948383) (xy -12.724188 -0.964507)
				(xy -12.767644 -0.970114) (xy -12.806775 -0.970734) (xy -12.922899 -0.987671) (xy -13.00786 -1.039568)
				(xy -13.063979 -1.128054) (xy -13.074609 -1.158837) (xy -13.084885 -1.244074) (xy -12.930348 -1.244074)
				(xy -12.910031 -1.190176) (xy -12.860199 -1.152565) (xy -12.797538 -1.137632) (xy -12.738728 -1.15177)
				(xy -12.722474 -1.164434) (xy -12.695969 -1.22018) (xy -12.705149 -1.283867) (xy -12.746628 -1.335536)
				(xy -12.791873 -1.362923) (xy -12.817494 -1.372308) (xy -12.851732 -1.3546) (xy -12.892344 -1.313705)
				(xy -12.923186 -1.267968) (xy -12.930348 -1.244074) (xy -13.084885 -1.244074) (xy -13.087974 -1.269701)
				(xy -13.063381 -1.365651) (xy -13.008888 -1.442479) (xy -12.932552 -1.495976) (xy -12.842431 -1.521934)
				(xy -12.746584 -1.516145) (xy -12.653067 -1.474399) (xy -12.58657 -1.413748) (xy -12.548594 -1.36173)
				(xy -12.532631 -1.312282) (xy -12.533195 -1.24415) (xy -12.535762 -1.216935) (xy -12.548305 -1.095409)
				(xy -12.378536 -0.926772) (xy -12.208766 -0.758136) (xy -11.796492 -0.758136) (xy -11.796492 -1.315972)
				(xy -11.890413 -1.35741) (xy -12.000362 -1.428554) (xy -12.074751 -1.530309) (xy -12.103547 -1.608413)
				(xy -12.114691 -1.719427) (xy -11.953136 -1.719427) (xy -11.944244 -1.665249) (xy -11.927218 -1.625373)
				(xy -11.866718 -1.543897) (xy -11.786289 -1.49957) (xy -11.696376 -1.495069) (xy -11.607427 -1.533073)
				(xy -11.597127 -1.540764) (xy -11.527435 -1.615972) (xy -11.503765 -1.69764) (xy -11.522499 -1.783736)
				(xy -11.579788 -1.872176) (xy -11.655413 -1.92277) (xy -11.739655 -1.935681) (xy -11.822795 -1.911076)
				(xy -11.895117 -1.849121) (xy -11.937073 -1.77666) (xy -11.953136 -1.719427) (xy -12.114691 -1.719427)
				(xy -12.116284 -1.735287) (xy -12.089238 -1.852462) (xy -12.0293 -1.953869) (xy -11.943361 -2.033438)
				(xy -11.838308 -2.0851) (xy -11.721034 -2.102786) (xy -11.598428 -2.080424)
			)
			(stroke
				(width 0.00279)
				(type solid)
			)
			(fill yes)
			(layer "F.Cu")
		)
		(fp_poly
			(pts
				(xy 6.912132 1.55682) (xy 6.345204 1.55682) (xy 6.345204 -1.797504) (xy 6.912132 -1.797504) (xy 6.912132 1.55682)
			)
			(stroke
				(width 0.00279)
				(type solid)
			)
			(fill yes)
			(layer "F.Mask")
		)
		(fp_poly
			(pts
				(xy 11.340704 -1.841043) (xy 11.383146 -1.835075) (xy 11.399626 -1.825218) (xy 11.400312 -1.821945)
				(xy 11.393617 -1.787258) (xy 11.375745 -1.719809) (xy 11.35001 -1.631803) (xy 11.338272 -1.593625)
				(xy 11.306574 -1.497032) (xy 11.282387 -1.438676) (xy 11.261494 -1.411028) (xy 11.239676 -1.40656)
				(xy 11.234259 -1.407963) (xy 11.087402 -1.439293) (xy 10.923404 -1.449612) (xy 10.760846 -1.43919)
				(xy 10.618313 -1.408295) (xy 10.591259 -1.398688) (xy 10.526298 -1.373477) (xy 10.526298 1.55682)
				(xy 9.95937 1.55682) (xy 9.95937 -1.627357) (xy 10.130629 -1.688724) (xy 10.279454 -1.738722) (xy 10.415589 -1.775887)
				(xy 10.552002 -1.802432) (xy 10.701659 -1.820566) (xy 10.877526 -1.832501) (xy 11.004644 -1.837729)
				(xy 11.156748 -1.842159) (xy 11.267003 -1.843334) (xy 11.340704 -1.841043)
			)
			(stroke
				(width 0.00279)
				(type solid)
			)
			(fill yes)
			(layer "F.Mask")
		)
		(fp_poly
			(pts
				(xy 0.286882 -2.696334) (xy 0.291195 -2.633826) (xy 0.294644 -2.538397) (xy 0.296982 -2.41721) (xy 0.297958 -2.277426)
				(xy 0.297972 -2.258133) (xy 0.297972 -1.797504) (xy 0.8649 -1.797504) (xy 0.8649 -1.419552) (xy 0.297972 -1.419552)
				(xy 0.297972 0.887973) (xy 0.35171 0.989594) (xy 0.420809 1.086396) (xy 0.509669 1.146307) (xy 0.625356 1.172892)
				(xy 0.717312 1.174035) (xy 0.864999 1.167057) (xy 0.864949 1.348733) (xy 0.860772 1.460716) (xy 0.84846 1.528604)
				(xy 0.835373 1.548939) (xy 0.800261 1.557487) (xy 0.729644 1.565503) (xy 0.635257 1.571858) (xy 0.569625 1.57448)
				(xy 0.440081 1.575664) (xy 0.342385 1.569249) (xy 0.261533 1.553675) (xy 0.208325 1.536992) (xy 0.064544 1.469148)
				(xy -0.049904 1.37486) (xy -0.144592 1.245474) (xy -0.174468 1.191014) (xy -0.257145 1.030172) (xy -0.26386 -0.19469)
				(xy -0.270574 -1.419552) (xy -0.646908 -1.419552) (xy -0.646908 -1.797504) (xy -0.268956 -1.797504)
				(xy -0.268956 -2.551783) (xy -0.001508 -2.635272) (xy 0.104164 -2.667861) (xy 0.192964 -2.694497)
				(xy 0.255428 -2.712391) (xy 0.281956 -2.718762) (xy 0.286882 -2.696334)
			)
			(stroke
				(width 0.00279)
				(type solid)
			)
			(fill yes)
			(layer "F.Mask")
		)
		(fp_poly
			(pts
				(xy -2.136607 -1.83175) (xy -2.010904 -1.828463) (xy -1.914265 -1.822037) (xy -1.837617 -1.811764)
				(xy -1.771885 -1.796939) (xy -1.74634 -1.789492) (xy -1.532158 -1.70751) (xy -1.359129 -1.605683)
				(xy -1.224749 -1.482223) (xy -1.136379 -1.354088) (xy -1.108163 -1.301039) (xy -1.084174 -1.250965)
				(xy -1.064068 -1.19968) (xy -1.047504 -1.142994) (xy -1.034138 -1.076717) (xy -1.023628 -0.996662)
				(xy -1.015631 -0.89864) (xy -1.009804 -0.778462) (xy -1.005806 -0.63194) (xy -1.003292 -0.454884)
				(xy -1.001922 -0.243105) (xy -1.001351 0.007584) (xy -1.001238 0.298006) (xy -1.001238 1.55682)
				(xy -1.568166 1.55682) (xy -1.568166 0.309141) (xy -1.568286 0.015459) (xy -1.56889 -0.234942) (xy -1.570346 -0.44602)
				(xy -1.573022 -0.621739) (xy -1.577286 -0.766058) (xy -1.583506 -0.882939) (xy -1.592049 -0.976344)
				(xy -1.603283 -1.050233) (xy -1.617577 -1.108567) (xy -1.635297 -1.155309) (xy -1.656812 -1.194418)
				(xy -1.682489 -1.229857) (xy -1.712696 -1.265585) (xy -1.714581 -1.267734) (xy -1.812287 -1.355903)
				(xy -1.931432 -1.417802) (xy -2.082042 -1.458151) (xy -2.138368 -1.46726) (xy -2.29674 -1.477433)
				(xy -2.472019 -1.46882) (xy -2.642327 -1.443409) (xy -2.766455 -1.410218) (xy -2.855565 -1.37937)
				(xy -2.861649 0.088725) (xy -2.867734 1.55682) (xy -3.434304 1.55682) (xy -3.434304 -1.626184) (xy -3.215801 -1.697862)
				(xy -3.065439 -1.745385) (xy -2.937666 -1.780369) (xy -2.819819 -1.804679) (xy -2.699238 -1.820176)
				(xy -2.563261 -1.828726) (xy -2.399228 -1.832192) (xy -2.300448 -1.832603) (xy -2.136607 -1.83175)
			)
			(stroke
				(width 0.00279)
				(type solid)
			)
			(fill yes)
			(layer "F.Mask")
		)
		(fp_poly
			(pts
				(xy 4.729063 -1.8271) (xy 4.959571 -1.776882) (xy 5.157893 -1.693771) (xy 5.323148 -1.578206) (xy 5.454451 -1.43062)
				(xy 5.517493 -1.325064) (xy 5.542461 -1.274165) (xy 5.563676 -1.22495) (xy 5.581442 -1.173239) (xy 5.596064 -1.114853)
				(xy 5.607848 -1.045613) (xy 5.617099 -0.96134) (xy 5.624121 -0.857855) (xy 5.629219 -0.730978) (xy 5.632699 -0.576531)
				(xy 5.634866 -0.390333) (xy 5.636025 -0.168207) (xy 5.63648 0.094028) (xy 5.636544 0.306017) (xy 5.636544 1.55682)
				(xy 5.071143 1.55682) (xy 5.064474 0.251704) (xy 5.057805 -1.053411) (xy 4.988868 -1.177834) (xy 4.895109 -1.301546)
				(xy 4.773134 -1.393175) (xy 4.629913 -1.452165) (xy 4.472416 -1.477959) (xy 4.307613 -1.470001)
				(xy 4.142475 -1.427734) (xy 3.98397 -1.350603) (xy 3.870799 -1.267078) (xy 3.770406 -1.179651) (xy 3.770406 1.55682)
				(xy 3.203478 1.55682) (xy 3.203478 0.278067) (xy 3.203064 -0.042779) (xy 3.201801 -0.31793) (xy 3.19966 -0.548927)
				(xy 3.196609 -0.737311) (xy 3.192619 -0.884624) (xy 3.187659 -0.992408) (xy 3.181699 -1.062204)
				(xy 3.176515 -1.09068) (xy 3.113168 -1.224355) (xy 3.012925 -1.331319) (xy 2.878719 -1.410269) (xy 2.713483 -1.459907)
				(xy 2.52015 -1.478929) (xy 2.324287 -1.468768) (xy 2.217475 -1.455784) (xy 2.140831 -1.44347) (xy 2.077483 -1.428123)
				(xy 2.010555 -1.406041) (xy 1.969229 -1.39085) (xy 1.904268 -1.366577) (xy 1.904268 1.55682) (xy 1.360962 1.55682)
				(xy 1.360962 -1.629932) (xy 1.585996 -1.702017) (xy 1.839432 -1.773628) (xy 2.076192 -1.818337)
				(xy 2.316338 -1.838944) (xy 2.565684 -1.838752) (xy 2.765772 -1.826957) (xy 2.929729 -1.804535)
				(xy 3.068058 -1.768421) (xy 3.191262 -1.715547) (xy 3.309844 -1.64285) (xy 3.35863 -1.60731) (xy 3.513772 -1.489884)
				(xy 3.612561 -1.570037) (xy 3.803824 -1.696423) (xy 4.018585 -1.783662) (xy 4.258747 -1.832362)
				(xy 4.467255 -1.843989) (xy 4.729063 -1.8271)
			)
			(stroke
				(width 0.00279)
				(type solid)
			)
			(fill yes)
			(layer "F.Mask")
		)
		(fp_poly
			(pts
				(xy 13.011 -1.828598) (xy 13.222157 -1.780519) (xy 13.409082 -1.697802) (xy 13.577941 -1.578087)
				(xy 13.656079 -1.505081) (xy 13.8057 -1.322147) (xy 13.924227 -1.106958) (xy 14.012192 -0.85815)
				(xy 14.070128 -0.574357) (xy 14.090393 -0.390545) (xy 14.101846 -0.06018) (xy 14.082517 0.248736)
				(xy 14.033408 0.533287) (xy 13.955524 0.790553) (xy 13.849866 1.017617) (xy 13.717438 1.211561)
				(xy 13.559243 1.369467) (xy 13.461074 1.440241) (xy 13.306254 1.517112) (xy 13.121999 1.574401)
				(xy 12.922961 1.609506) (xy 12.723792 1.619827) (xy 12.542357 1.603344) (xy 12.30932 1.539496) (xy 12.102782 1.436939)
				(xy 11.923619 1.296654) (xy 11.772705 1.119624) (xy 11.650914 0.906828) (xy 11.559121 0.659249)
				(xy 11.509091 0.443636) (xy 11.467044 0.123703) (xy 11.458222 -0.133265) (xy 12.022913 -0.133265)
				(xy 12.033208 0.130412) (xy 12.06476 0.384026) (xy 12.117594 0.617116) (xy 12.189245 0.813805) (xy 12.281708 0.968837)
				(xy 12.398869 1.090076) (xy 12.534807 1.175098) (xy 12.683598 1.221477) (xy 12.839322 1.226788)
				(xy 12.996055 1.188608) (xy 13.048162 1.165468) (xy 13.180842 1.078195) (xy 13.290857 0.958674)
				(xy 13.37932 0.804507) (xy 13.447344 0.613298) (xy 13.496041 0.382646) (xy 13.524253 0.1395) (xy 13.536499 -0.156891)
				(xy 13.524426 -0.432929) (xy 13.488984 -0.684487) (xy 13.431119 -0.907435) (xy 13.351781 -1.097642)
				(xy 13.251917 -1.250979) (xy 13.189895 -1.316899) (xy 13.054995 -1.412386) (xy 12.90868 -1.465731)
				(xy 12.757488 -1.478493) (xy 12.607953 -1.452231) (xy 12.466612 -1.388504) (xy 12.340002 -1.288871)
				(xy 12.234658 -1.15489) (xy 12.193793 -1.079317) (xy 12.119314 -0.880028) (xy 12.065991 -0.648948)
				(xy 12.033849 -0.396539) (xy 12.022913 -0.133265) (xy 11.458222 -0.133265) (xy 11.456366 -0.187331)
				(xy 11.476106 -0.484529) (xy 11.525315 -0.762953) (xy 11.603043 -1.017667) (xy 11.70834 -1.243733)
				(xy 11.840256 -1.436213) (xy 11.879302 -1.480693) (xy 12.04917 -1.632047) (xy 12.241107 -1.742502)
				(xy 12.456488 -1.812618) (xy 12.696687 -1.842957) (xy 12.769446 -1.844399) (xy 13.011 -1.828598)
			)
			(stroke
				(width 0.00279)
				(type solid)
			)
			(fill yes)
			(layer "F.Mask")
		)
		(fp_poly
			(pts
				(xy 8.814213 -1.840483) (xy 8.969759 -1.825412) (xy 9.056281 -1.809134) (xy 9.145452 -1.783461)
				(xy 9.241206 -1.748594) (xy 9.331151 -1.709938) (xy 9.402898 -1.672901) (xy 9.444054 -1.642889)
				(xy 9.447346 -1.638505) (xy 9.444801 -1.609133) (xy 9.427786 -1.551422) (xy 9.401635 -1.478945)
				(xy 9.371683 -1.405273) (xy 9.343265 -1.343977) (xy 9.321716 -1.308629) (xy 9.316165 -1.304791)
				(xy 9.28701 -1.3133) (xy 9.228967 -1.336582) (xy 9.170199 -1.362544) (xy 8.989584 -1.425274) (xy 8.810705 -1.449653)
				(xy 8.641862 -1.435423) (xy 8.493873 -1.383637) (xy 8.370199 -1.295153) (xy 8.256869 -1.165361)
				(xy 8.157444 -0.999709) (xy 8.075486 -0.803644) (xy 8.04073 -0.690661) (xy 8.0133 -0.551431) (xy 7.995672 -0.37999)
				(xy 7.987846 -0.190341) (xy 7.989822 0.003512) (xy 8.001598 0.187565) (xy 8.023174 0.347814) (xy 8.040794 0.426604)
				(xy 8.120911 0.661281) (xy 8.221774 0.853813) (xy 8.343673 1.00464) (xy 8.4869 1.114204) (xy 8.498013 1.120496)
				(xy 8.570319 1.157192) (xy 8.633963 1.178299) (xy 8.70729 1.187849) (xy 8.808641 1.18987) (xy 8.813703 1.189851)
				(xy 8.920044 1.185178) (xy 9.013384 1.169314) (xy 9.108059 1.137943) (xy 9.218407 1.086747) (xy 9.300948 1.043176)
				(xy 9.311241 1.049795) (xy 9.329071 1.080783) (xy 9.356659 1.141006) (xy 9.396222 1.235333) (xy 9.449978 1.368632)
				(xy 9.455034 1.381317) (xy 9.441745 1.40673) (xy 9.393674 1.442381) (xy 9.32065 1.48296) (xy 9.232503 1.523157)
				(xy 9.139062 1.557662) (xy 9.114694 1.565169) (xy 8.987614 1.592214) (xy 8.834546 1.609553) (xy 8.675805 1.616006)
				(xy 8.531704 1.610388) (xy 8.471184 1.602631) (xy 8.382682 1.580174) (xy 8.27615 1.542853) (xy 8.175909 1.499329)
				(xy 7.979839 1.377324) (xy 7.810569 1.217033) (xy 7.668836 1.019577) (xy 7.555379 0.786076) (xy 7.470937 0.517652)
				(xy 7.442822 0.386949) (xy 7.422315 0.232254) (xy 7.411523 0.048978) (xy 7.410053 -0.149598) (xy 7.417508 -0.350189)
				(xy 7.433495 -0.539511) (xy 7.457618 -0.704283) (xy 7.477921 -0.793551) (xy 7.569718 -1.055031)
				(xy 7.690906 -1.282895) (xy 7.839972 -1.475439) (xy 8.015408 -1.630955) (xy 8.215702 -1.747738)
				(xy 8.375078 -1.807062) (xy 8.499369 -1.831256) (xy 8.651582 -1.842414) (xy 8.814213 -1.840483)
			)
			(stroke
				(width 0.00279)
				(type solid)
			)
			(fill yes)
			(layer "F.Mask")
		)
		(fp_poly
			(pts
				(xy -5.050123 -1.828751) (xy -4.900576 -1.800755) (xy -4.730837 -1.748715) (xy -4.593875 -1.684132)
				(xy -4.475494 -1.599519) (xy -4.417289 -1.545833) (xy -4.33145 -1.438632) (xy -4.25438 -1.301382)
				(xy -4.194656 -1.151275) (xy -4.167075 -1.044179) (xy -4.161601 -0.991002) (xy -4.156686 -0.894515)
				(xy -4.152404 -0.758651) (xy -4.14883 -0.587342) (xy -4.146038 -0.38452) (xy -4.144102 -0.154118)
				(xy -4.143096 0.099932) (xy -4.142964 0.236107) (xy -4.142964 1.389255) (xy -4.253676 1.438228)
				(xy -4.451908 1.509446) (xy -4.681546 1.56447) (xy -4.929024 1.601579) (xy -5.180775 1.61905) (xy -5.423232 1.615164)
				(xy -5.551117 1.602857) (xy -5.801683 1.552934) (xy -6.015853 1.473578) (xy -6.193196 1.365257)
				(xy -6.33328 1.228443) (xy -6.435674 1.063605) (xy -6.499947 0.871213) (xy -6.525669 0.651739) (xy -6.524424 0.541559)
				(xy -6.521414 0.520731) (xy -5.980195 0.520731) (xy -5.975801 0.716157) (xy -5.933333 0.885059)
				(xy -5.853697 1.026031) (xy -5.737804 1.137664) (xy -5.58656 1.218552) (xy -5.514208 1.242597) (xy -5.421778 1.258401)
				(xy -5.297997 1.265595) (xy -5.157857 1.264744) (xy -5.016352 1.25641) (xy -4.888475 1.241159) (xy -4.789219 1.219554)
				(xy -4.774853 1.214784) (xy -4.662648 1.174427) (xy -4.662648 -0.312718) (xy -4.798474 -0.29633)
				(xy -4.885159 -0.282693) (xy -4.997384 -0.260692) (xy -5.115103 -0.234352) (xy -5.152116 -0.225299)
				(xy -5.394278 -0.150849) (xy -5.593128 -0.059371) (xy -5.749805 0.050162) (xy -5.865449 0.178776)
				(xy -5.941198 0.327497) (xy -5.978194 0.497353) (xy -5.980195 0.520731) (xy -6.521414 0.520731)
				(xy -6.493668 0.328754) (xy -6.422351 0.139568) (xy -6.30958 -0.028039) (xy -6.245225 -0.096814)
				(xy -6.103026 -0.209801) (xy -5.920199 -0.31379) (xy -5.702882 -0.406508) (xy -5.457208 -0.48568)
				(xy -5.189315 -0.549035) (xy -4.905337 -0.594299) (xy -4.901094 -0.594815) (xy -4.656202 -0.624496)
				(xy -4.67036 -0.825112) (xy -4.697756 -1.014305) (xy -4.7521 -1.166118) (xy -4.835845 -1.283573)
				(xy -4.951447 -1.369689) (xy -5.101362 -1.427488) (xy -5.173118 -1.443664) (xy -5.368453 -1.460676)
				(xy -5.585568 -1.444404) (xy -5.814301 -1.396375) (xy -6.044491 -1.318113) (xy -6.064756 -1.309714)
				(xy -6.137401 -1.280895) (xy -6.190621 -1.263081) (xy -6.21177 -1.260016) (xy -6.223817 -1.284953)
				(xy -6.246487 -1.340557) (xy -6.274545 -1.412991) (xy -6.30276 -1.488418) (xy -6.325898 -1.553)
				(xy -6.338724 -1.592902) (xy -6.33981 -1.598556) (xy -6.320033 -1.613975) (xy -6.268692 -1.64124)
				(xy -6.210986 -1.6681) (xy -5.998934 -1.744812) (xy -5.763807 -1.80055) (xy -5.51862 -1.833998)
				(xy -5.276387 -1.843837) (xy -5.050123 -1.828751)
			)
			(stroke
				(width 0.00279)
				(type solid)
			)
			(fill yes)
			(layer "F.Mask")
		)
		(fp_poly
			(pts
				(xy -11.634962 -4.909269) (xy -11.537229 -4.886866) (xy -11.535595 -4.886192) (xy -11.504855 -4.870152)
				(xy -11.436833 -4.832523) (xy -11.335138 -4.775379) (xy -11.203377 -4.700793) (xy -11.045161 -4.610843)
				(xy -10.864096 -4.507601) (xy -10.663791 -4.393143) (xy -10.447855 -4.269542) (xy -10.219896 -4.138875)
				(xy -9.983523 -4.003215) (xy -9.742343 -3.864638) (xy -9.499965 -3.725217) (xy -9.259997 -3.587029)
				(xy -9.026048 -3.452146) (xy -8.801727 -3.322644) (xy -8.590641 -3.200598) (xy -8.396399 -3.088082)
				(xy -8.222609 -2.98717) (xy -8.07288 -2.899939) (xy -7.950819 -2.828462) (xy -7.860036 -2.774814)
				(xy -7.804139 -2.741069) (xy -7.797751 -2.737074) (xy -7.697553 -2.654792) (xy -7.620586 -2.556391)
				(xy -7.556343 -2.447109) (xy -7.549972 -0.195459) (xy -7.549017 0.235367) (xy -7.548701 0.6241)
				(xy -7.549022 0.970152) (xy -7.549975 1.272938) (xy -7.551555 1.53187) (xy -7.553759 1.746362) (xy -7.556581 1.915829)
				(xy -7.560017 2.039683) (xy -7.564064 2.117338) (xy -7.567619 2.145384) (xy -7.577264 2.180947)
				(xy -7.587545 2.213383) (xy -7.600916 2.244325) (xy -7.619829 2.275406) (xy -7.646736 2.30826) (xy -7.684091 2.344521)
				(xy -7.734346 2.385822) (xy -7.799953 2.433797) (xy -7.883366 2.49008) (xy -7.987037 2.556303) (xy -8.113418 2.634101)
				(xy -8.264963 2.725108) (xy -8.444124 2.830956) (xy -8.653354 2.953279) (xy -8.895105 3.093711)
				(xy -9.17183 3.253885) (xy -9.485981 3.435436) (xy -9.625797 3.516214) (xy -11.524839 4.613405)
				(xy -11.702004 4.622509) (xy -11.879169 4.631612) (xy -12.576018 4.230845) (xy -13.002735 3.985469)
				(xy -13.390442 3.762529) (xy -13.741039 3.560827) (xy -14.056425 3.379165) (xy -14.338499 3.216347)
				(xy -14.589159 3.071175) (xy -14.810305 2.942451) (xy -15.003836 2.828979) (xy -15.171651 2.729561)
				(xy -15.315648 2.643) (xy -15.437727 2.568099) (xy -15.539787 2.503659) (xy -15.623728 2.448485)
				(xy -15.691447 2.401378) (xy -15.744844 2.361141) (xy -15.785818 2.326577) (xy -15.816268 2.296489)
				(xy -15.838093 2.269678) (xy -15.853192 2.244949) (xy -15.863464 2.221104) (xy -15.870808 2.196945)
				(xy -15.877123 2.171275) (xy -15.883619 2.145435) (xy -15.888143 2.103987) (xy -15.892058 2.015869)
				(xy -15.895361 1.881652) (xy -15.898047 1.701907) (xy -15.900112 1.477205) (xy -15.901551 1.208115)
				(xy -15.902361 0.89521) (xy -15.902536 0.539059) (xy -15.902073 0.140233) (xy -15.901402 -0.143964)
				(xy -14.442156 -0.143964) (xy -14.442124 0.163081) (xy -14.441853 0.426492) (xy -14.441076 0.649878)
				(xy -14.439527 0.836849) (xy -14.436941 0.991014) (xy -14.433052 1.115983) (xy -14.427595 1.215365)
				(xy -14.420304 1.292771) (xy -14.410912 1.351809) (xy -14.399155 1.39609) (xy -14.384767 1.429223)
				(xy -14.367482 1.454817) (xy -14.347035 1.476482) (xy -14.323159 1.497828) (xy -14.321185 1.49955)
				(xy -14.289536 1.521118) (xy -14.221441 1.563277) (xy -14.121348 1.623467) (xy -13.993705 1.699126)
				(xy -13.842963 1.787694) (xy -13.67357 1.88661) (xy -13.489974 1.993314) (xy -13.296625 2.105246)
				(xy -13.097972 2.219844) (xy -12.898464 2.334548) (xy -12.702549 2.446797) (xy -12.514678 2.554031)
				(xy -12.339297 2.653689) (xy -12.180857 2.74321) (xy -12.043807 2.820035) (xy -11.932595 2.881601)
				(xy -11.85167 2.92535) (xy -11.805481 2.948719) (xy -11.798239 2.951643) (xy -11.739669 2.967611)
				(xy -11.698729 2.968556) (xy -11.650207 2.952973) (xy -11.621431 2.941108) (xy -11.582082 2.921398)
				(xy -11.507211 2.880786) (xy -11.401295 2.821862) (xy -11.26881 2.747214) (xy -11.114234 2.659433)
				(xy -10.942044 2.561108) (xy -10.756716 2.454828) (xy -10.562727 2.343182) (xy -10.364553 2.228759)
				(xy -10.166673 2.11415) (xy -9.973562 2.001942) (xy -9.789697 1.894726) (xy -9.619556 1.795091)
				(xy -9.467615 1.705626) (xy -9.338351 1.628921) (xy -9.236241 1.567564) (xy -9.165761 1.524145)
				(xy -9.131389 1.501254) (xy -9.130067 1.500156) (xy -9.105914 1.478431) (xy -9.08521 1.456719) (xy -9.06769 1.431407)
				(xy -9.053089 1.398882) (xy -9.04114 1.355531) (xy -9.031578 1.297741) (xy -9.024136 1.221898) (xy -9.01855 1.12439)
				(xy -9.014552 1.001603) (xy -9.011878 0.849924) (xy -9.010261 0.665741) (xy -9.009436 0.445438)
				(xy -9.009136 0.185404) (xy -9.009096 -0.117974) (xy -9.009096 -0.143964) (xy -9.0091 -0.452362)
				(xy -9.009321 -0.717103) (xy -9.010073 -0.941774) (xy -9.01167 -1.129961) (xy -9.014425 -1.285251)
				(xy -9.018653 -1.411232) (xy -9.024668 -1.511489) (xy -9.032783 -1.58961) (xy -9.043312 -1.649182)
				(xy -9.056569 -1.69379) (xy -9.072868 -1.727023) (xy -9.092523 -1.752467) (xy -9.115847 -1.773708)
				(xy -9.143156 -1.794333) (xy -9.154227 -1.80245) (xy -9.188912 -1.824767) (xy -9.260658 -1.868304)
				(xy -9.365548 -1.930764) (xy -9.499667 -2.009853) (xy -9.659099 -2.103275) (xy -9.839929 -2.208734)
				(xy -10.038241 -2.323934) (xy -10.250119 -2.44658) (xy -10.42874 -2.549657) (xy -10.683967 -2.696551)
				(xy -10.901677 -2.821355) (xy -11.085146 -2.925812) (xy -11.237649 -3.011663) (xy -11.362461 -3.080652)
				(xy -11.462857 -3.134521) (xy -11.542113 -3.175015) (xy -11.603503 -3.203875) (xy -11.650303 -3.222844)
				(xy -11.685788 -3.233665) (xy -11.713233 -3.238082) (xy -11.723096 -3.238446) (xy -11.747788 -3.236214)
				(xy -11.779117 -3.228375) (xy -11.820299 -3.213209) (xy -11.87455 -3.189) (xy -11.945086 -3.154031)
				(xy -12.035122 -3.106582) (xy -12.147874 -3.044939) (xy -12.286558 -2.967382) (xy -12.45439 -2.872194)
				(xy -12.654587 -2.757658) (xy -12.890362 -2.622057) (xy -13.055415 -2.526885) (xy -13.277555 -2.398503)
				(xy -13.488307 -2.276303) (xy -13.683963 -2.162462) (xy -13.860818 -2.059154) (xy -14.015167 -1.968555)
				(xy -14.143302 -1.892839) (xy -14.241518 -1.834183) (xy -14.30611 -1.79476) (xy -14.333212 -1.776887)
				(xy -14.354964 -1.757361) (xy -14.373609 -1.736701) (xy -14.389386 -1.711319) (xy -14.402536 -1.677626)
				(xy -14.413297 -1.632035) (xy -14.421909 -1.570958) (xy -14.428611 -1.490807) (xy -14.433642 -1.387994)
				(xy -14.437243 -1.258931) (xy -14.439651 -1.100029) (xy -14.441108 -0.907702) (xy -14.441851 -0.678361)
				(xy -14.44212 -0.408418) (xy -14.442156 -0.143964) (xy -15.901402 -0.143964) (xy -15.90128 -0.195459)
				(xy -15.900261 -0.578211) (xy -15.899381 -0.916603) (xy -15.898458 -1.213517) (xy -15.89731 -1.471836)
				(xy -15.895755 -1.694444) (xy -15.893611 -1.884222) (xy -15.890696 -2.044053) (xy -15.886827 -2.176821)
				(xy -15.881824 -2.285408) (xy -15.875504 -2.372697) (xy -15.867686 -2.441569) (xy -15.858186 -2.49491)
				(xy -15.846824 -2.535599) (xy -15.833418 -2.566522) (xy -15.817785 -2.59056) (xy -15.799743 -2.610596)
				(xy -15.779112 -2.629513) (xy -15.755708 -2.650193) (xy -15.745777 -2.659371) (xy -15.715671 -2.680398)
				(xy -15.647598 -2.723193) (xy -15.544554 -2.785985) (xy -15.409536 -2.867005) (xy -15.245541 -2.964486)
				(xy -15.055566 -3.076657) (xy -14.842607 -3.20175) (xy -14.609663 -3.337996) (xy -14.359728 -3.483626)
				(xy -14.0958 -3.636872) (xy -13.820877 -3.795963) (xy -13.791539 -3.812909) (xy -13.471051 -3.997959)
				(xy -13.18881 -4.160791) (xy -12.942164 -4.302841) (xy -12.728464 -4.425542) (xy -12.545058 -4.530328)
				(xy -12.389295 -4.618633) (xy -12.258526 -4.691893) (xy -12.150098 -4.751541) (xy -12.061361 -4.799011)
				(xy -11.989665 -4.835738) (xy -11.932359 -4.863157) (xy -11.886792 -4.8827) (xy -11.850312 -4.895803)
				(xy -11.820271 -4.9039) (xy -11.794016 -4.908426) (xy -11.768896 -4.910813) (xy -11.761531 -4.911305)
				(xy -11.634962 -4.909269)
			)
			(stroke
				(width 0.00279)
				(type solid)
			)
			(fill yes)
			(layer "F.Mask")
		)
		(fp_poly
			(pts
				(xy -11.598428 -2.080424) (xy -11.57723 -2.072066) (xy -11.468751 -2.001658) (xy -11.389638 -1.901364)
				(xy -11.34533 -1.781817) (xy -11.341267 -1.653648) (xy -11.347026 -1.622167) (xy -11.393935 -1.501154)
				(xy -11.47506 -1.410426) (xy -11.556887 -1.360523) (xy -11.65476 -1.313304) (xy -11.65476 -0.758136)
				(xy -11.242486 -0.758136) (xy -11.072717 -0.926772) (xy -10.902947 -1.095409) (xy -10.91549 -1.216935)
				(xy -10.915635 -1.219488) (xy -10.755191 -1.219488) (xy -10.728778 -1.164434) (xy -10.673757 -1.138779)
				(xy -10.607221 -1.144244) (xy -10.558024 -1.173208) (xy -10.524273 -1.228567) (xy -10.536119 -1.285278)
				(xy -10.568148 -1.325064) (xy -10.613088 -1.363188) (xy -10.650323 -1.366995) (xy -10.700942 -1.338104)
				(xy -10.704624 -1.335536) (xy -10.746388 -1.283194) (xy -10.755191 -1.219488) (xy -10.915635 -1.219488)
				(xy -10.919936 -1.294799) (xy -10.9095 -1.347615) (xy -10.878693 -1.396634) (xy -10.864682 -1.413748)
				(xy -10.778844 -1.486331) (xy -10.684406 -1.519496) (xy -10.589344 -1.517602) (xy -10.501633 -1.485007)
				(xy -10.429249 -1.426066) (xy -10.380166 -1.34514) (xy -10.36236 -1.246585) (xy -10.379014 -1.148379)
				(xy -10.432246 -1.055367) (xy -10.517668 -0.995483) (xy -10.631547 -0.971164) (xy -10.650843 -0.970734)
				(xy -10.700173 -0.969021) (xy -10.741166 -0.960188) (xy -10.782998 -0.93869) (xy -10.834845 -0.898984)
				(xy -10.905884 -0.835526) (xy -10.96366 -0.781758) (xy -11.165642 -0.592782) (xy -11.65476 -0.592782)
				(xy -11.65476 -0.21483) (xy -10.758337 -0.21483) (xy -10.723338 -0.282511) (xy -10.659408 -0.359534)
				(xy -10.571221 -0.40564) (xy -10.47149 -0.419331) (xy -10.372929 -0.399105) (xy -10.288248 -0.343464)
				(xy -10.280045 -0.334805) (xy -10.218985 -0.239159) (xy -10.198673 -0.141594) (xy -10.213428 -0.048914)
				(xy -10.257567 0.032077) (xy -10.325406 0.094573) (xy -10.411263 0.13177) (xy -10.509456 0.136864)
				(xy -10.614302 0.103049) (xy -10.63563 0.090981) (xy -10.690298 0.048218) (xy -10.724151 0.004288)
				(xy -10.726968 -0.003419) (xy -10.733524 -0.019303) (xy -10.747921 -0.031049) (xy -10.776503 -0.03928)
				(xy -10.825609 -0.044615) (xy -10.901582 -0.047677) (xy -11.010765 -0.049088) (xy -11.159498 -0.049469)
				(xy -11.196886 -0.049476) (xy -11.65476 -0.049476) (xy -11.65476 0.304854) (xy -11.169466 0.304854)
				(xy -10.777215 0.699153) (xy -10.666776 0.689665) (xy -10.54838 0.697916) (xy -10.45636 0.743895)
				(xy -10.393666 0.825779) (xy -10.377361 0.868512) (xy -10.361371 0.981493) (xy -10.388493 1.07909)
				(xy -10.447693 1.156536) (xy -10.539198 1.220541) (xy -10.636418 1.243765) (xy -10.730888 1.23049)
				(xy -10.81414 1.185001) (xy -10.877707 1.111581) (xy -10.913123 1.014512) (xy -10.914674 0.943593)
				(xy -10.75263 0.943593) (xy -10.744939 1.002359) (xy -10.722338 1.036421) (xy -10.668584 1.077858)
				(xy -10.616765 1.074443) (xy -10.568148 1.037136) (xy -10.527141 0.979502) (xy -10.530991 0.9279)
				(xy -10.5662 0.885356) (xy -10.625941 0.854578) (xy -10.683408 0.860296) (xy -10.728879 0.893103)
				(xy -10.75263 0.943593) (xy -10.914674 0.943593) (xy -10.91519 0.920035) (xy -10.901974 0.808447)
				(xy -11.242486 0.470208) (xy -11.65476 0.470208) (xy -11.65476 1.029961) (xy -11.557366 1.073879)
				(xy -11.455133 1.142987) (xy -11.384628 1.237535) (xy -11.346116 1.348001) (xy -11.33986 1.464867)
				(xy -11.366124 1.578613) (xy -11.42517 1.679718) (xy -11.517263 1.758662) (xy -11.538089 1.770152)
				(xy -11.661781 1.808862) (xy -11.793522 1.808868) (xy -11.91585 1.770223) (xy -11.918197 1.768995)
				(xy -12.015055 1.693955) (xy -12.078707 1.595232) (xy -12.109487 1.482413) (xy -12.108656 1.426899)
				(xy -11.947673 1.426899) (xy -11.938086 1.497165) (xy -11.90202 1.553977) (xy -11.87171 1.583435)
				(xy -11.784326 1.639137) (xy -11.698287 1.647711) (xy -11.61162 1.609158) (xy -11.579542 1.583435)
				(xy -11.526679 1.525013) (xy -11.505614 1.464095) (xy -11.503579 1.426899) (xy -11.524839 1.341071)
				(xy -11.580199 1.266709) (xy -11.65703 1.216575) (xy -11.725626 1.20249) (xy -11.81055 1.223976)
				(xy -11.88413 1.279925) (xy -11.933736 1.357574) (xy -11.947673 1.426899) (xy -12.108656 1.426899)
				(xy -12.107731 1.365086) (xy -12.073774 1.252838) (xy -12.007952 1.155256) (xy -11.9106 1.081929)
				(xy -11.893886 1.073879) (xy -11.796492 1.029961) (xy -11.796492 0.470208) (xy -12.208766 0.470208)
				(xy -12.549278 0.808447) (xy -12.536062 0.920035) (xy -12.541999 1.033334) (xy -12.583046 1.126506)
				(xy -12.650738 1.195267) (xy -12.736606 1.235334) (xy -12.832185 1.242424) (xy -12.929008 1.212252)
				(xy -13.003559 1.156536) (xy -13.069237 1.066034) (xy -13.090194 0.96674) (xy -13.085366 0.937646)
				(xy -12.92434 0.937646) (xy -12.919831 0.989652) (xy -12.883104 1.037136) (xy -12.825593 1.07811)
				(xy -12.774031 1.074247) (xy -12.730422 1.038088) (xy -12.700833 0.977326) (xy -12.708615 0.915658)
				(xy -12.749494 0.869261) (xy -12.778117 0.857531) (xy -12.847796 0.860939) (xy -12.884056 0.884454)
				(xy -12.92434 0.937646) (xy -13.085366 0.937646) (xy -13.073891 0.868512) (xy -13.02385 0.772676)
				(xy -12.943292 0.712009) (xy -12.83517 0.688335) (xy -12.784476 0.689665) (xy -12.674037 0.699153)
				(xy -12.281786 0.304854) (xy -11.796492 0.304854) (xy -11.796492 -0.049476) (xy -12.255529 -0.049476)
				(xy -12.413558 -0.049274) (xy -12.530739 -0.04823) (xy -12.613468 -0.045683) (xy -12.668141 -0.040976)
				(xy -12.701154 -0.033451) (xy -12.718903 -0.022447) (xy -12.727784 -0.007307) (xy -12.730078 -0.000602)
				(xy -12.768179 0.053795) (xy -12.836662 0.101408) (xy -12.918753 0.132562) (xy -12.97286 0.139412)
				(xy -13.081927 0.119662) (xy -13.16716 0.066135) (xy -13.224798 -0.01218) (xy -13.251082 -0.106295)
				(xy -13.248267 -0.138461) (xy -13.092435 -0.138461) (xy -13.085594 -0.104362) (xy -13.06173 -0.074712)
				(xy -12.999893 -0.032025) (xy -12.936774 -0.035011) (xy -12.896602 -0.062974) (xy -12.862603 -0.123872)
				(xy -12.869847 -0.163375) (xy -10.58825 -0.163375) (xy -10.579305 -0.097122) (xy -10.55465 -0.062974)
				(xy -10.494098 -0.028987) (xy -10.430729 -0.040964) (xy -10.389522 -0.074712) (xy -10.360749 -0.113869)
				(xy -10.362101 -0.149471) (xy -10.380745 -0.186917) (xy -10.430735 -0.241425) (xy -10.490836 -0.256827)
				(xy -10.549013 -0.230385) (xy -10.553393 -0.226211) (xy -10.58825 -0.163375) (xy -12.869847 -0.163375)
				(xy -12.874232 -0.187285) (xy -12.904968 -0.225051) (xy -12.965739 -0.256682) (xy -13.023234 -0.242178)
				(xy -13.070485 -0.18675) (xy -13.092435 -0.138461) (xy -13.248267 -0.138461) (xy -13.24225 -0.20722)
				(xy -13.194545 -0.305966) (xy -13.171207 -0.334805) (xy -13.086844 -0.396657) (xy -12.988403 -0.420452)
				(xy -12.887861 -0.407544) (xy -12.797197 -0.359286) (xy -12.733093 -0.285314) (xy -12.691457 -0.21483)
				(xy -11.796492 -0.21483) (xy -11.796492 -0.592782) (xy -12.28561 -0.592782) (xy -12.487592 -0.781758)
				(xy -12.574784 -0.862522) (xy -12.637071 -0.916226) (xy -12.683768 -0.948383) (xy -12.724188 -0.964507)
				(xy -12.767644 -0.970114) (xy -12.806775 -0.970734) (xy -12.922899 -0.987671) (xy -13.00786 -1.039568)
				(xy -13.063979 -1.128054) (xy -13.074609 -1.158837) (xy -13.084885 -1.244074) (xy -12.930348 -1.244074)
				(xy -12.910031 -1.190176) (xy -12.860199 -1.152565) (xy -12.797538 -1.137632) (xy -12.738728 -1.15177)
				(xy -12.722474 -1.164434) (xy -12.695969 -1.22018) (xy -12.705149 -1.283867) (xy -12.746628 -1.335536)
				(xy -12.791873 -1.362923) (xy -12.817494 -1.372308) (xy -12.851732 -1.3546) (xy -12.892344 -1.313705)
				(xy -12.923186 -1.267968) (xy -12.930348 -1.244074) (xy -13.084885 -1.244074) (xy -13.087974 -1.269701)
				(xy -13.063381 -1.365651) (xy -13.008888 -1.442479) (xy -12.932552 -1.495976) (xy -12.842431 -1.521934)
				(xy -12.746584 -1.516145) (xy -12.653067 -1.474399) (xy -12.58657 -1.413748) (xy -12.548594 -1.36173)
				(xy -12.532631 -1.312282) (xy -12.533195 -1.24415) (xy -12.535762 -1.216935) (xy -12.548305 -1.095409)
				(xy -12.378536 -0.926772) (xy -12.208766 -0.758136) (xy -11.796492 -0.758136) (xy -11.796492 -1.315972)
				(xy -11.890413 -1.35741) (xy -12.000362 -1.428554) (xy -12.074751 -1.530309) (xy -12.103547 -1.608413)
				(xy -12.114691 -1.719427) (xy -11.953136 -1.719427) (xy -11.944244 -1.665249) (xy -11.927218 -1.625373)
				(xy -11.866718 -1.543897) (xy -11.786289 -1.49957) (xy -11.696376 -1.495069) (xy -11.607427 -1.533073)
				(xy -11.597127 -1.540764) (xy -11.527435 -1.615972) (xy -11.503765 -1.69764) (xy -11.522499 -1.783736)
				(xy -11.579788 -1.872176) (xy -11.655413 -1.92277) (xy -11.739655 -1.935681) (xy -11.822795 -1.911076)
				(xy -11.895117 -1.849121) (xy -11.937073 -1.77666) (xy -11.953136 -1.719427) (xy -12.114691 -1.719427)
				(xy -12.116284 -1.735287) (xy -12.089238 -1.852462) (xy -12.0293 -1.953869) (xy -11.943361 -2.033438)
				(xy -11.838308 -2.0851) (xy -11.721034 -2.102786) (xy -11.598428 -2.080424)
			)
			(stroke
				(width 0.00279)
				(type solid)
			)
			(fill yes)
			(layer "F.Mask")
		)
		(fp_rect
			(start -19.374 -8.384)
			(end 17.584 8.104)
			(stroke
				(width 0.05)
				(type default)
			)
			(fill no)
			(layer "F.CrtYd")
		)
	)
	(footprint "antmicro-footprints:R_0603_1608Metric"
		(layer "F.Cu")
		(at 219.78 167.955 90)
		(descr "Resistor SMD 0603")
		(tags "resistor SMD 0603")
		(property "Reference" "R205"
			(at -0.02 -2.505 90)
			(layer "F.SilkS")
			(effects
				(font
					(size 0.7 0.7)
					(thickness 0.15)
				)
				(justify left bottom)
			)
		)
		(property "Value" "R_0R_22.4A_0603"
			(at 0 1.6 90)
			(layer "F.Fab")
			(effects
				(font
					(size 0.7 0.7)
					(thickness 0.15)
				)
				(justify left bottom)
			)
		)
		(property "Datasheet" "https://fscdn.rohm.com/en/products/databook/datasheet/passive/resistor/chip_resistor/pmr-jpw-e.pdf"
			(at 0 0 90)
			(layer "F.Fab")
			(hide yes)
			(effects
				(font
					(size 1.27 1.27)
					(thickness 0.15)
				)
			)
		)
		(property "Manufacturer" "ROHM Semiconductor"
			(at 0 0 90)
			(unlocked yes)
			(layer "F.Fab")
			(hide yes)
			(effects
				(font
					(size 1 1)
					(thickness 0.15)
				)
			)
		)
		(property "MPN" "PMR03EZPJ000"
			(at 0 0 90)
			(unlocked yes)
			(layer "F.Fab")
			(hide yes)
			(effects
				(font
					(size 1 1)
					(thickness 0.15)
				)
			)
		)
		(property "Val" "0R"
			(at 0 0 90)
			(unlocked yes)
			(layer "F.Fab")
			(hide yes)
			(effects
				(font
					(size 1 1)
					(thickness 0.15)
				)
			)
		)
		(property "Author" "Antmicro"
			(at 0 0 90)
			(unlocked yes)
			(layer "F.Fab")
			(hide yes)
			(effects
				(font
					(size 1 1)
					(thickness 0.15)
				)
			)
		)
		(property "License" "Apache-2.0"
			(at 0 0 90)
			(unlocked yes)
			(layer "F.Fab")
			(hide yes)
			(effects
				(font
					(size 1 1)
					(thickness 0.15)
				)
			)
		)
		(property "Max. Curr." "22.4A"
			(at 0 0 90)
			(unlocked yes)
			(layer "F.Fab")
			(hide yes)
			(effects
				(font
					(size 1 1)
					(thickness 0.15)
				)
			)
		)
		(sheetname "/Supply/DC-DC VCCINT/")
		(sheetfile "dc-dc-vccint.kicad_sch")
		(attr smd)
		(fp_line
			(start -0.15 -0.4)
			(end 0.15 -0.4)
			(stroke
				(width 0.15)
				(type solid)
			)
			(layer "F.SilkS")
		)
		(fp_line
			(start -0.15 0.4)
			(end 0.15 0.4)
			(stroke
				(width 0.15)
				(type solid)
			)
			(layer "F.SilkS")
		)
		(fp_rect
			(start -1.25 -0.65)
			(end 1.25 0.65)
			(stroke
				(width 0.05)
				(type solid)
			)
			(fill no)
			(layer "F.CrtYd")
		)
		(fp_rect
			(start -0.8 -0.4)
			(end 0.8 0.4)
			(stroke
				(width 0.15)
				(type solid)
			)
			(fill no)
			(layer "F.Fab")
		)
		(fp_text user "Author: Antmicro"
			(at -1.25 4.9 90)
			(layer "F.Fab")
			(effects
				(font
					(size 0.7 0.7)
					(thickness 0.15)
				)
				(justify left bottom)
			)
		)
		(fp_text user "License: Apache-2.0"
			(at -1.25 5.9 90)
			(layer "F.Fab")
			(effects
				(font
					(size 0.7 0.7)
					(thickness 0.15)
				)
				(justify left bottom)
			)
		)
		(fp_text user "${REFERENCE}"
			(at -1.25 3.898 90)
			(layer "F.Fab")
			(effects
				(font
					(size 0.7 0.7)
					(thickness 0.15)
				)
				(justify left bottom)
			)
		)
		(pad "1" smd roundrect
			(at -0.7 0 90)
			(size 0.8 1)
			(layers "F.Cu" "F.Mask" "F.Paste")
			(roundrect_rratio 0.2)
			(net 223 "/Supply/DC-DC VCCINT/0V85_REG0")
			(pintype "passive")
		)
		(pad "2" smd roundrect
			(at 0.7 0 90)
			(size 0.8 1)
			(layers "F.Cu" "F.Mask" "F.Paste")
			(roundrect_rratio 0.2)
			(net 553 "+0V85")
			(pintype "passive")
		)
	)
	(footprint "antmicro-footprints:TP_SMD_1mm"
		(layer "F.Cu")
		(at 244.024499 173.299)
		(property "Reference" "TP8"
			(at 0 -0.731898 0)
			(layer "F.SilkS")
			(hide yes)
			(effects
				(font
					(size 0.7 0.7)
					(thickness 0.15)
				)
				(justify left bottom)
			)
		)
		(property "Value" "TP_1mm_SMD"
			(at 0 1.4 0)
			(layer "F.Fab")
			(effects
				(font
					(size 0.7 0.7)
					(thickness 0.15)
				)
				(justify left bottom)
			)
		)
		(property "MPN" ""
			(at 0 0 0)
			(unlocked yes)
			(layer "F.Fab")
			(hide yes)
			(effects
				(font
					(size 1 1)
					(thickness 0.15)
				)
			)
		)
		(property "Manufacturer" ""
			(at 0 0 0)
			(unlocked yes)
			(layer "F.Fab")
			(hide yes)
			(effects
				(font
					(size 1 1)
					(thickness 0.15)
				)
			)
		)
		(property "Author" "Antmicro"
			(at 0 0 0)
			(unlocked yes)
			(layer "F.Fab")
			(hide yes)
			(effects
				(font
					(size 1 1)
					(thickness 0.15)
				)
			)
		)
		(property "License" "Apache-2.0"
			(at 0 0 0)
			(unlocked yes)
			(layer "F.Fab")
			(hide yes)
			(effects
				(font
					(size 1 1)
					(thickness 0.15)
				)
			)
		)
		(sheetname "/Supply/DC-DC AUX, MGT/")
		(sheetfile "dc-dc-aux-mgt.kicad_sch")
		(attr exclude_from_pos_files)
		(fp_circle
			(center 0 0)
			(end 0.6 0)
			(stroke
				(width 0.05)
				(type default)
			)
			(fill no)
			(layer "F.CrtYd")
		)
		(fp_text user "${REFERENCE}"
			(at -0.5 2.8 0)
			(layer "F.Fab")
			(effects
				(font
					(size 0.7 0.7)
					(thickness 0.15)
				)
				(justify left bottom)
			)
		)
		(fp_text user "License: Apache-2.0"
			(at -0.5 5.2 0)
			(layer "F.Fab")
			(effects
				(font
					(size 0.7 0.7)
					(thickness 0.15)
				)
				(justify left bottom)
			)
		)
		(fp_text user "Author: Antmicro"
			(at -0.5 4 0)
			(layer "F.Fab")
			(effects
				(font
					(size 0.7 0.7)
					(thickness 0.15)
				)
				(justify left bottom)
			)
		)
		(pad "1" smd circle
			(at 0 0)
			(size 1 1)
			(layers "F.Cu" "F.Mask")
			(net 797 "+1V8")
			(pinfunction "1")
			(pintype "passive")
		)
	)
	(footprint "antmicro-footprints:R_0402_1005Metric"
		(layer "F.Cu")
		(at 244.25 184.399 90)
		(descr "Resistor SMD 0402")
		(tags "resistor SMD 0402")
		(property "Reference" "R75"
			(at 1.15 0.325 90)
			(layer "F.SilkS")
			(effects
				(font
					(size 0.7 0.7)
					(thickness 0.15)
				)
				(justify left bottom)
			)
		)
		(property "Value" "R_200k_0402"
			(at -1.011843 1.772047 90)
			(layer "F.Fab")
			(effects
				(font
					(size 0.7 0.7)
					(thickness 0.15)
				)
				(justify left bottom)
			)
		)
		(property "Datasheet" "https://www.bourns.com/docs/product-datasheets/cr.pdf"
			(at 0 0 90)
			(layer "F.Fab")
			(hide yes)
			(effects
				(font
					(size 1.27 1.27)
					(thickness 0.15)
				)
			)
		)
		(property "MPN" "CR0402-FX-2003GLF"
			(at 0 0 90)
			(unlocked yes)
			(layer "F.Fab")
			(hide yes)
			(effects
				(font
					(size 1 1)
					(thickness 0.15)
				)
			)
		)
		(property "Manufacturer" "Bourns"
			(at 0 0 90)
			(unlocked yes)
			(layer "F.Fab")
			(hide yes)
			(effects
				(font
					(size 1 1)
					(thickness 0.15)
				)
			)
		)
		(property "License" "Apache-2.0"
			(at 0 0 90)
			(unlocked yes)
			(layer "F.Fab")
			(hide yes)
			(effects
				(font
					(size 1 1)
					(thickness 0.15)
				)
			)
		)
		(property "Author" "Antmicro"
			(at 0 0 90)
			(unlocked yes)
			(layer "F.Fab")
			(hide yes)
			(effects
				(font
					(size 1 1)
					(thickness 0.15)
				)
			)
		)
		(property "Val" "200k"
			(at 0 0 90)
			(unlocked yes)
			(layer "F.Fab")
			(hide yes)
			(effects
				(font
					(size 1 1)
					(thickness 0.15)
				)
			)
		)
		(property "Tolerance" "1%"
			(at 0 0 90)
			(unlocked yes)
			(layer "F.Fab")
			(hide yes)
			(effects
				(font
					(size 1 1)
					(thickness 0.15)
				)
			)
		)
		(sheetname "/I^{2}C + I3C/")
		(sheetfile "i2c.kicad_sch")
		(attr smd)
		(fp_rect
			(start -0.925 -0.47)
			(end 0.925 0.47)
			(stroke
				(width 0.05)
				(type default)
			)
			(fill no)
			(layer "F.CrtYd")
		)
		(fp_rect
			(start -0.5 -0.25)
			(end 0.5 0.25)
			(stroke
				(width 0.15)
				(type solid)
			)
			(fill no)
			(layer "F.Fab")
		)
		(fp_text user "${REFERENCE}"
			(at -0.95 3.168 90)
			(layer "F.Fab")
			(effects
				(font
					(size 0.7 0.7)
					(thickness 0.15)
				)
				(justify left bottom)
			)
		)
		(fp_text user "Author: Antmicro"
			(at -0.95 4.169 90)
			(layer "F.Fab")
			(effects
				(font
					(size 0.7 0.7)
					(thickness 0.15)
				)
				(justify left bottom)
			)
		)
		(fp_text user "License: Apache-2.0"
			(at -0.95 5.169 90)
			(layer "F.Fab")
			(effects
				(font
					(size 0.7 0.7)
					(thickness 0.15)
				)
				(justify left bottom)
			)
		)
		(pad "1" smd roundrect
			(at -0.48 0 90)
			(size 0.59 0.64)
			(layers "F.Cu" "F.Mask" "F.Paste")
			(roundrect_rratio 0.25)
			(net 774 "Net-(U49-EN)")
			(pintype "passive")
		)
		(pad "2" smd roundrect
			(at 0.48 0 90)
			(size 0.59 0.64)
			(layers "F.Cu" "F.Mask" "F.Paste")
			(roundrect_rratio 0.25)
			(net 151 "+3V3")
			(pintype "passive")
		)
	)
	(footprint "antmicro-footprints:R_0402_1005Metric"
		(layer "F.Cu")
		(at 161.81 157.199999 90)
		(descr "Resistor SMD 0402")
		(tags "resistor SMD 0402")
		(property "Reference" "R70"
			(at 0.949999 0.46 90)
			(layer "F.SilkS")
			(effects
				(font
					(size 0.7 0.7)
					(thickness 0.15)
				)
				(justify left bottom)
			)
		)
		(property "Value" "R_4k7_0402"
			(at -1.011843 1.772047 90)
			(layer "F.Fab")
			(effects
				(font
					(size 0.7 0.7)
					(thickness 0.15)
				)
				(justify left bottom)
			)
		)
		(property "Datasheet" "https://www.bourns.com/docs/product-datasheets/cr.pdf"
			(at 0 0 90)
			(layer "F.Fab")
			(hide yes)
			(effects
				(font
					(size 1.27 1.27)
					(thickness 0.15)
				)
			)
		)
		(property "MPN" "CR0402-FX-4701GLF"
			(at 0 0 90)
			(unlocked yes)
			(layer "F.Fab")
			(hide yes)
			(effects
				(font
					(size 1 1)
					(thickness 0.15)
				)
			)
		)
		(property "Manufacturer" "Bourns"
			(at 0 0 90)
			(unlocked yes)
			(layer "F.Fab")
			(hide yes)
			(effects
				(font
					(size 1 1)
					(thickness 0.15)
				)
			)
		)
		(property "License" "Apache-2.0"
			(at 0 0 90)
			(unlocked yes)
			(layer "F.Fab")
			(hide yes)
			(effects
				(font
					(size 1 1)
					(thickness 0.15)
				)
			)
		)
		(property "Author" "Antmicro"
			(at 0 0 90)
			(unlocked yes)
			(layer "F.Fab")
			(hide yes)
			(effects
				(font
					(size 1 1)
					(thickness 0.15)
				)
			)
		)
		(property "Val" "4k7"
			(at 0 0 90)
			(unlocked yes)
			(layer "F.Fab")
			(hide yes)
			(effects
				(font
					(size 1 1)
					(thickness 0.15)
				)
			)
		)
		(property "Tolerance" "1%"
			(at 0 0 90)
			(unlocked yes)
			(layer "F.Fab")
			(hide yes)
			(effects
				(font
					(size 1 1)
					(thickness 0.15)
				)
			)
		)
		(sheetname "/FPGA MGT Interface/")
		(sheetfile "fpga-mgt.kicad_sch")
		(attr smd)
		(fp_rect
			(start -0.925 -0.47)
			(end 0.925 0.47)
			(stroke
				(width 0.05)
				(type default)
			)
			(fill no)
			(layer "F.CrtYd")
		)
		(fp_rect
			(start -0.5 -0.25)
			(end 0.5 0.25)
			(stroke
				(width 0.15)
				(type solid)
			)
			(fill no)
			(layer "F.Fab")
		)
		(fp_text user "License: Apache-2.0"
			(at -0.95 5.169 90)
			(layer "F.Fab")
			(effects
				(font
					(size 0.7 0.7)
					(thickness 0.15)
				)
				(justify left bottom)
			)
		)
		(fp_text user "${REFERENCE}"
			(at -0.95 3.168 90)
			(layer "F.Fab")
			(effects
				(font
					(size 0.7 0.7)
					(thickness 0.15)
				)
				(justify left bottom)
			)
		)
		(fp_text user "Author: Antmicro"
			(at -0.95 4.169 90)
			(layer "F.Fab")
			(effects
				(font
					(size 0.7 0.7)
					(thickness 0.15)
				)
				(justify left bottom)
			)
		)
		(pad "1" smd roundrect
			(at -0.48 0 90)
			(size 0.59 0.64)
			(layers "F.Cu" "F.Mask" "F.Paste")
			(roundrect_rratio 0.25)
			(net 531 "~{SI_5319_RST}")
			(pintype "passive")
		)
		(pad "2" smd roundrect
			(at 0.48 0 90)
			(size 0.59 0.64)
			(layers "F.Cu" "F.Mask" "F.Paste")
			(roundrect_rratio 0.25)
			(net 151 "+3V3")
			(pintype "passive")
		)
	)
	(footprint "antmicro-footprints:TP_SMD_1mm"
		(layer "F.Cu")
		(at 224.325 167.4)
		(property "Reference" "TP17"
			(at 0 -0.731898 0)
			(layer "F.SilkS")
			(hide yes)
			(effects
				(font
					(size 0.7 0.7)
					(thickness 0.15)
				)
				(justify left bottom)
			)
		)
		(property "Value" "TP_1mm_SMD"
			(at 0 1.4 0)
			(layer "F.Fab")
			(effects
				(font
					(size 0.7 0.7)
					(thickness 0.15)
				)
				(justify left bottom)
			)
		)
		(property "MPN" ""
			(at 0 0 0)
			(unlocked yes)
			(layer "F.Fab")
			(hide yes)
			(effects
				(font
					(size 1 1)
					(thickness 0.15)
				)
			)
		)
		(property "Manufacturer" ""
			(at 0 0 0)
			(unlocked yes)
			(layer "F.Fab")
			(hide yes)
			(effects
				(font
					(size 1 1)
					(thickness 0.15)
				)
			)
		)
		(property "Author" "Antmicro"
			(at 0 0 0)
			(unlocked yes)
			(layer "F.Fab")
			(hide yes)
			(effects
				(font
					(size 1 1)
					(thickness 0.15)
				)
			)
		)
		(property "License" "Apache-2.0"
			(at 0 0 0)
			(unlocked yes)
			(layer "F.Fab")
			(hide yes)
			(effects
				(font
					(size 1 1)
					(thickness 0.15)
				)
			)
		)
		(sheetname "/Supply/DC-DC VCCINT/")
		(sheetfile "dc-dc-vccint.kicad_sch")
		(attr exclude_from_pos_files)
		(fp_circle
			(center 0 0)
			(end 0.6 0)
			(stroke
				(width 0.05)
				(type default)
			)
			(fill no)
			(layer "F.CrtYd")
		)
		(fp_text user "${REFERENCE}"
			(at -0.5 2.8 0)
			(layer "F.Fab")
			(effects
				(font
					(size 0.7 0.7)
					(thickness 0.15)
				)
				(justify left bottom)
			)
		)
		(fp_text user "Author: Antmicro"
			(at -0.5 4 0)
			(layer "F.Fab")
			(effects
				(font
					(size 0.7 0.7)
					(thickness 0.15)
				)
				(justify left bottom)
			)
		)
		(fp_text user "License: Apache-2.0"
			(at -0.5 5.2 0)
			(layer "F.Fab")
			(effects
				(font
					(size 0.7 0.7)
					(thickness 0.15)
				)
				(justify left bottom)
			)
		)
		(pad "1" smd circle
			(at 0 0)
			(size 1 1)
			(layers "F.Cu" "F.Mask")
			(net 553 "+0V85")
			(pinfunction "1")
			(pintype "passive")
		)
	)
	(footprint "antmicro-footprints:R_0402_1005Metric"
		(layer "F.Cu")
		(at 215.179999 180.665 -90)
		(descr "Resistor SMD 0402")
		(tags "resistor SMD 0402")
		(property "Reference" "R196"
			(at 1.245 -0.340001 90)
			(layer "F.SilkS")
			(effects
				(font
					(size 0.7 0.7)
					(thickness 0.15)
				)
				(justify right bottom)
			)
		)
		(property "Value" "R_10R_0402"
			(at -1.011843 1.772047 90)
			(layer "F.Fab")
			(effects
				(font
					(size 0.7 0.7)
					(thickness 0.15)
				)
				(justify right bottom)
			)
		)
		(property "Datasheet" "https://www.bourns.com/docs/product-datasheets/cr.pdf"
			(at 0 0 270)
			(layer "F.Fab")
			(hide yes)
			(effects
				(font
					(size 1.27 1.27)
					(thickness 0.15)
				)
			)
		)
		(property "MPN" "CR0402-FX-10R0GLF"
			(at 0 0 270)
			(unlocked yes)
			(layer "F.Fab")
			(hide yes)
			(effects
				(font
					(size 1 1)
					(thickness 0.15)
				)
			)
		)
		(property "Manufacturer" "Bourns"
			(at 0 0 270)
			(unlocked yes)
			(layer "F.Fab")
			(hide yes)
			(effects
				(font
					(size 1 1)
					(thickness 0.15)
				)
			)
		)
		(property "License" "Apache-2.0"
			(at 0 0 270)
			(unlocked yes)
			(layer "F.Fab")
			(hide yes)
			(effects
				(font
					(size 1 1)
					(thickness 0.15)
				)
			)
		)
		(property "Author" "Antmicro"
			(at 0 0 270)
			(unlocked yes)
			(layer "F.Fab")
			(hide yes)
			(effects
				(font
					(size 1 1)
					(thickness 0.15)
				)
			)
		)
		(property "Val" "10R"
			(at 0 0 270)
			(unlocked yes)
			(layer "F.Fab")
			(hide yes)
			(effects
				(font
					(size 1 1)
					(thickness 0.15)
				)
			)
		)
		(property "Tolerance" "1%"
			(at 0 0 270)
			(unlocked yes)
			(layer "F.Fab")
			(hide yes)
			(effects
				(font
					(size 1 1)
					(thickness 0.15)
				)
			)
		)
		(sheetname "/Supply/DC-DC VCCINT/")
		(sheetfile "dc-dc-vccint.kicad_sch")
		(attr smd)
		(fp_rect
			(start -0.925 -0.47)
			(end 0.925 0.47)
			(stroke
				(width 0.05)
				(type default)
			)
			(fill no)
			(layer "F.CrtYd")
		)
		(fp_rect
			(start -0.5 -0.25)
			(end 0.5 0.25)
			(stroke
				(width 0.15)
				(type solid)
			)
			(fill no)
			(layer "F.Fab")
		)
		(fp_text user "License: Apache-2.0"
			(at -0.95 5.169 270)
			(layer "F.Fab")
			(effects
				(font
					(size 0.7 0.7)
					(thickness 0.15)
				)
				(justify left bottom)
			)
		)
		(fp_text user "Author: Antmicro"
			(at -0.95 4.169 270)
			(layer "F.Fab")
			(effects
				(font
					(size 0.7 0.7)
					(thickness 0.15)
				)
				(justify left bottom)
			)
		)
		(fp_text user "${REFERENCE}"
			(at -0.95 3.168 270)
			(layer "F.Fab")
			(effects
				(font
					(size 0.7 0.7)
					(thickness 0.15)
				)
				(justify left bottom)
			)
		)
		(pad "1" smd roundrect
			(at -0.48 0 270)
			(size 0.59 0.64)
			(layers "F.Cu" "F.Mask" "F.Paste")
			(roundrect_rratio 0.25)
			(net 222 "Net-(U4-V_{DRV})")
			(pintype "passive")
		)
		(pad "2" smd roundrect
			(at 0.48 0 270)
			(size 0.59 0.64)
			(layers "F.Cu" "F.Mask" "F.Paste")
			(roundrect_rratio 0.25)
			(net 163 "/Supply/DC-DC VCCINT/V_{CC}")
			(pintype "passive")
		)
	)
	(footprint "antmicro-footprints:LED_0603_1608Metric_G"
		(layer "F.Cu")
		(at 110.706 102.224 90)
		(descr "LED SMD 0603 Green")
		(tags "LED SMD 0603 Green")
		(property "Reference" "D5"
			(at -2.575 -0.305 90)
			(layer "F.SilkS")
			(hide yes)
			(effects
				(font
					(size 0.7 0.7)
					(thickness 0.15)
				)
				(justify left bottom)
			)
		)
		(property "Value" "LED_G_0603_KP-1608CGCK"
			(at -0.001 1.599 90)
			(layer "F.Fab")
			(effects
				(font
					(size 0.7 0.7)
					(thickness 0.15)
				)
				(justify left bottom)
			)
		)
		(property "Datasheet" "http://www.kingbright.com/attachments/file/psearch//000/00/00/KP-1608CGCK(Ver.23B).pdf"
			(at 0 0 90)
			(layer "F.Fab")
			(hide yes)
			(effects
				(font
					(size 1.27 1.27)
					(thickness 0.15)
				)
			)
		)
		(property "MPN" "KP-1608CGCK"
			(at 0 0 90)
			(unlocked yes)
			(layer "F.Fab")
			(hide yes)
			(effects
				(font
					(size 1 1)
					(thickness 0.15)
				)
			)
		)
		(property "Manufacturer" "Kingbright"
			(at 0 0 90)
			(unlocked yes)
			(layer "F.Fab")
			(hide yes)
			(effects
				(font
					(size 1 1)
					(thickness 0.15)
				)
			)
		)
		(property "Author" "Antmicro"
			(at 0 0 90)
			(unlocked yes)
			(layer "F.Fab")
			(hide yes)
			(effects
				(font
					(size 1 1)
					(thickness 0.15)
				)
			)
		)
		(property "License" "Apache-2.0"
			(at 0 0 90)
			(unlocked yes)
			(layer "F.Fab")
			(hide yes)
			(effects
				(font
					(size 1 1)
					(thickness 0.15)
				)
			)
		)
		(property "Color" "Green"
			(at 0 0 90)
			(unlocked yes)
			(layer "F.Fab")
			(hide yes)
			(effects
				(font
					(size 1 1)
					(thickness 0.15)
				)
			)
		)
		(sheetname "/FPGA banks HD/")
		(sheetfile "fpga-hd-banks.kicad_sch")
		(attr smd)
		(fp_line
			(start 0.22 -0.35)
			(end -0.22 -0.35)
			(stroke
				(width 0.15)
				(type solid)
			)
			(layer "F.SilkS")
		)
		(fp_line
			(start -1.18 -0.319)
			(end -1.18 0.321)
			(stroke
				(width 0.15)
				(type solid)
			)
			(layer "F.SilkS")
		)
		(fp_line
			(start 0.105328 0.001008)
			(end 0.24 0.001)
			(stroke
				(width 0.1)
				(type solid)
			)
			(layer "F.SilkS")
		)
		(fp_line
			(start -0.094672 0.001008)
			(end 0.105328 -0.198992)
			(stroke
				(width 0.1)
				(type solid)
			)
			(layer "F.SilkS")
		)
		(fp_line
			(start -0.094672 0.001008)
			(end -0.24 0.001008)
			(stroke
				(width 0.1)
				(type solid)
			)
			(layer "F.SilkS")
		)
		(fp_line
			(start 0.105328 0.201008)
			(end 0.105328 -0.198992)
			(stroke
				(width 0.1)
				(type solid)
			)
			(layer "F.SilkS")
		)
		(fp_line
			(start 0.105328 0.201008)
			(end -0.094672 0.001008)
			(stroke
				(width 0.1)
				(type solid)
			)
			(layer "F.SilkS")
		)
		(fp_line
			(start -0.094672 0.201008)
			(end -0.094672 -0.198992)
			(stroke
				(width 0.1)
				(type solid)
			)
			(layer "F.SilkS")
		)
		(fp_line
			(start 0.22 0.35)
			(end -0.22 0.35)
			(stroke
				(width 0.15)
				(type solid)
			)
			(layer "F.SilkS")
		)
		(fp_rect
			(start 1.25 0.65)
			(end -1.25 -0.65)
			(stroke
				(width 0.05)
				(type solid)
			)
			(fill no)
			(layer "F.CrtYd")
		)
		(fp_line
			(start 0.201 -0.202)
			(end -0.101 0)
			(stroke
				(width 0.15)
				(type solid)
			)
			(layer "F.Fab")
		)
		(fp_line
			(start -0.199 -0.202)
			(end -0.199 0.1)
			(stroke
				(width 0.15)
				(type solid)
			)
			(layer "F.Fab")
		)
		(fp_line
			(start 0.599 0)
			(end 0.201 0)
			(stroke
				(width 0.15)
				(type solid)
			)
			(layer "F.Fab")
		)
		(fp_line
			(start 0.201 0)
			(end 0.201 -0.202)
			(stroke
				(width 0.15)
				(type solid)
			)
			(layer "F.Fab")
		)
		(fp_line
			(start -0.101 0)
			(end 0.201 0.2)
			(stroke
				(width 0.15)
				(type solid)
			)
			(layer "F.Fab")
		)
		(fp_line
			(start -0.199 0)
			(end -0.597 0)
			(stroke
				(width 0.15)
				(type solid)
			)
			(layer "F.Fab")
		)
		(fp_line
			(start 0.201 0.2)
			(end 0.201 0)
			(stroke
				(width 0.15)
				(type solid)
			)
			(layer "F.Fab")
		)
		(fp_line
			(start -0.199 0.2)
			(end -0.199 0.1)
			(stroke
				(width 0.15)
				(type solid)
			)
			(layer "F.Fab")
		)
		(fp_rect
			(start 0.848 0.4)
			(end -0.85 -0.402)
			(stroke
				(width 0.15)
				(type solid)
			)
			(fill no)
			(layer "F.Fab")
		)
		(fp_text user "${REFERENCE}"
			(at -1.4224 5.999 90)
			(layer "F.Fab")
			(effects
				(font
					(size 0.7 0.7)
					(thickness 0.15)
				)
				(justify left bottom)
			)
		)
		(fp_text user "License: Apache-2.0"
			(at -1.4224 3.599 90)
			(layer "F.Fab")
			(effects
				(font
					(size 0.7 0.7)
					(thickness 0.15)
				)
				(justify left bottom)
			)
		)
		(fp_text user "Author: Antmicro"
			(at -1.4224 4.799 90)
			(layer "F.Fab")
			(effects
				(font
					(size 0.7 0.7)
					(thickness 0.15)
				)
				(justify left bottom)
			)
		)
		(pad "1" smd roundrect
			(at -0.7 0 270)
			(size 0.8 1)
			(layers "F.Cu" "F.Mask" "F.Paste")
			(roundrect_rratio 0.2)
			(net 151 "+3V3")
			(pinfunction "C")
			(pintype "passive")
		)
		(pad "2" smd roundrect
			(at 0.7 0 270)
			(size 0.8 1)
			(layers "F.Cu" "F.Mask" "F.Paste")
			(roundrect_rratio 0.2)
			(net 230 "Net-(D5-A)")
			(pinfunction "A")
			(pintype "passive")
		)
	)
	(footprint "antmicro-footprints:R_0402_1005Metric"
		(layer "F.Cu")
		(at 144.774499 169.899 -90)
		(descr "Resistor SMD 0402")
		(tags "resistor SMD 0402")
		(property "Reference" "R91"
			(at 1.001 0.974499 90)
			(layer "F.SilkS")
			(effects
				(font
					(size 0.7 0.7)
					(thickness 0.15)
				)
				(justify right bottom)
			)
		)
		(property "Value" "R_0R_0402"
			(at -1.011843 1.772047 90)
			(layer "F.Fab")
			(effects
				(font
					(size 0.7 0.7)
					(thickness 0.15)
				)
				(justify right bottom)
			)
		)
		(property "Datasheet" "https://industrial.panasonic.com/cdbs/www-data/pdf/RDA0000/AOA0000C301.pdf"
			(at 0 0 270)
			(layer "F.Fab")
			(hide yes)
			(effects
				(font
					(size 1.27 1.27)
					(thickness 0.15)
				)
			)
		)
		(property "Manufacturer" "Panasonic"
			(at 0 0 270)
			(unlocked yes)
			(layer "F.Fab")
			(hide yes)
			(effects
				(font
					(size 1 1)
					(thickness 0.15)
				)
			)
		)
		(property "MPN" "ERJ2GE0R00X"
			(at 0 0 270)
			(unlocked yes)
			(layer "F.Fab")
			(hide yes)
			(effects
				(font
					(size 1 1)
					(thickness 0.15)
				)
			)
		)
		(property "Val" "0R"
			(at 0 0 270)
			(unlocked yes)
			(layer "F.Fab")
			(hide yes)
			(effects
				(font
					(size 1 1)
					(thickness 0.15)
				)
			)
		)
		(property "License" "Apache-2.0"
			(at 0 0 270)
			(unlocked yes)
			(layer "F.Fab")
			(hide yes)
			(effects
				(font
					(size 1 1)
					(thickness 0.15)
				)
			)
		)
		(property "Author" "Antmicro"
			(at 0 0 270)
			(unlocked yes)
			(layer "F.Fab")
			(hide yes)
			(effects
				(font
					(size 1 1)
					(thickness 0.15)
				)
			)
		)
		(property "Tolerance" "~"
			(at 0 0 270)
			(unlocked yes)
			(layer "F.Fab")
			(hide yes)
			(effects
				(font
					(size 1 1)
					(thickness 0.15)
				)
			)
		)
		(property "Current" "1A"
			(at 0 0 270)
			(unlocked yes)
			(layer "F.Fab")
			(hide yes)
			(effects
				(font
					(size 1 1)
					(thickness 0.15)
				)
			)
		)
		(sheetname "/Debug FTDI + VNA/")
		(sheetfile "debug-ftdi.kicad_sch")
		(attr smd exclude_from_bom dnp)
		(fp_rect
			(start -0.925 -0.47)
			(end 0.925 0.47)
			(stroke
				(width 0.05)
				(type default)
			)
			(fill no)
			(layer "F.CrtYd")
		)
		(fp_rect
			(start -0.5 -0.25)
			(end 0.5 0.25)
			(stroke
				(width 0.15)
				(type solid)
			)
			(fill no)
			(layer "F.Fab")
		)
		(fp_text user "License: Apache-2.0"
			(at -0.95 5.169 270)
			(layer "F.Fab")
			(effects
				(font
					(size 0.7 0.7)
					(thickness 0.15)
				)
				(justify left bottom)
			)
		)
		(fp_text user "Author: Antmicro"
			(at -0.95 4.169 270)
			(layer "F.Fab")
			(effects
				(font
					(size 0.7 0.7)
					(thickness 0.15)
				)
				(justify left bottom)
			)
		)
		(fp_text user "${REFERENCE}"
			(at -0.95 3.168 270)
			(layer "F.Fab")
			(effects
				(font
					(size 0.7 0.7)
					(thickness 0.15)
				)
				(justify left bottom)
			)
		)
		(pad "1" smd roundrect
			(at -0.48 0 270)
			(size 0.59 0.64)
			(layers "F.Cu" "F.Mask" "F.Paste")
			(roundrect_rratio 0.25)
			(net 441 "/Debug FTDI + VNA/I2C_EN")
			(pintype "passive")
		)
		(pad "2" smd roundrect
			(at 0.48 0 270)
			(size 0.59 0.64)
			(layers "F.Cu" "F.Mask" "F.Paste")
			(roundrect_rratio 0.25)
			(net 301 "Net-(U13-OE)")
			(pintype "passive")
		)
	)
	(footprint "antmicro-footprints:MP_NPTH_Drill3mm"
		(layer "F.Cu")
		(at 262 103)
		(property "Reference" "MP4"
			(at -10.06 1.28 0)
			(layer "F.SilkS")
			(hide yes)
			(effects
				(font
					(size 0.7 0.7)
					(thickness 0.15)
				)
				(justify left bottom)
			)
		)
		(property "Value" "MP_NPTH_Drill3mm"
			(at -13.52 6.2 0)
			(layer "F.Fab")
			(effects
				(font
					(size 0.7 0.7)
					(thickness 0.15)
				)
				(justify left bottom)
			)
		)
		(sheetfile "data-center-rdimm-ddr5-tester.kicad_sch")
		(attr board_only exclude_from_pos_files exclude_from_bom)
		(fp_circle
			(center 0 0)
			(end 1.6 0)
			(stroke
				(width 0.05)
				(type default)
			)
			(fill no)
			(layer "F.CrtYd")
		)
		(fp_text user "License: Apache-2.0"
			(at 0 7.15 0)
			(layer "F.Fab")
			(effects
				(font
					(size 0.7 0.7)
					(thickness 0.15)
				)
				(justify left bottom)
			)
		)
		(fp_text user "${REFERENCE}"
			(at 0 4.749 0)
			(layer "F.Fab")
			(effects
				(font
					(size 0.7 0.7)
					(thickness 0.15)
				)
				(justify left bottom)
			)
		)
		(fp_text user "Author: Antmicro"
			(at 0 5.95 0)
			(layer "F.Fab")
			(effects
				(font
					(size 0.7 0.7)
					(thickness 0.15)
				)
				(justify left bottom)
			)
		)
		(pad "" np_thru_hole circle
			(at 0 0)
			(size 3 3)
			(drill 3)
			(layers "*.Cu" "*.Mask")
		)
	)
	(footprint "antmicro-footprints:SOT-23-6"
		(layer "F.Cu")
		(at 254.224499 132.714 90)
		(property "Reference" "U22"
			(at -0.835 2.7 90)
			(layer "F.SilkS")
			(effects
				(font
					(size 0.7 0.7)
					(thickness 0.15)
				)
				(justify left bottom)
			)
		)
		(property "Value" "MAX16150A_SOT"
			(at -1.75 2.75 90)
			(layer "F.Fab")
			(effects
				(font
					(size 0.7 0.7)
					(thickness 0.15)
				)
				(justify left bottom)
			)
		)
		(property "Datasheet" "https://datasheets.maximintegrated.com/en/ds/MAX16150.pdf"
			(at 0 0 90)
			(layer "F.Fab")
			(hide yes)
			(effects
				(font
					(size 1.27 1.27)
					(thickness 0.15)
				)
			)
		)
		(property "Manufacturer" "Maxim Integrated Products"
			(at 0 0 90)
			(unlocked yes)
			(layer "F.Fab")
			(hide yes)
			(effects
				(font
					(size 1 1)
					(thickness 0.15)
				)
			)
		)
		(property "MPN" "MAX16150AUT+T"
			(at 0 0 90)
			(unlocked yes)
			(layer "F.Fab")
			(hide yes)
			(effects
				(font
					(size 1 1)
					(thickness 0.15)
				)
			)
		)
		(property "License" "Apache-2.0"
			(at 0 0 90)
			(unlocked yes)
			(layer "F.Fab")
			(hide yes)
			(effects
				(font
					(size 1 1)
					(thickness 0.15)
				)
			)
		)
		(property "Author" "Antmicro"
			(at 0 0 90)
			(unlocked yes)
			(layer "F.Fab")
			(hide yes)
			(effects
				(font
					(size 1 1)
					(thickness 0.15)
				)
			)
		)
		(sheetname "/Supply/")
		(sheetfile "supply.kicad_sch")
		(attr smd)
		(fp_line
			(start 1.45 -0.757)
			(end 1.45 -0.457)
			(stroke
				(width 0.12)
				(type solid)
			)
			(layer "F.SilkS")
		)
		(fp_line
			(start 1.3 -0.757)
			(end 1.45 -0.757)
			(stroke
				(width 0.12)
				(type solid)
			)
			(layer "F.SilkS")
		)
		(fp_line
			(start -1.3 -0.757)
			(end -1.45 -0.757)
			(stroke
				(width 0.12)
				(type solid)
			)
			(layer "F.SilkS")
		)
		(fp_line
			(start -1.45 -0.757)
			(end -1.45 -0.457)
			(stroke
				(width 0.12)
				(type solid)
			)
			(layer "F.SilkS")
		)
		(fp_line
			(start 1.45 0.643)
			(end 1.45 0.343)
			(stroke
				(width 0.12)
				(type solid)
			)
			(layer "F.SilkS")
		)
		(fp_line
			(start 1.3 0.643)
			(end 1.45 0.643)
			(stroke
				(width 0.12)
				(type solid)
			)
			(layer "F.SilkS")
		)
		(fp_line
			(start -1.45 0.643)
			(end -1.45 0.343)
			(stroke
				(width 0.12)
				(type solid)
			)
			(layer "F.SilkS")
		)
		(fp_rect
			(start -1.55 -1.85)
			(end 1.55 1.75)
			(stroke
				(width 0.05)
				(type solid)
			)
			(fill no)
			(layer "F.CrtYd")
		)
		(fp_line
			(start 1.5 -0.757)
			(end 1.5 0.643)
			(stroke
				(width 0.1)
				(type solid)
			)
			(layer "F.Fab")
		)
		(fp_line
			(start -1.5 -0.757)
			(end 1.5 -0.757)
			(stroke
				(width 0.1)
				(type solid)
			)
			(layer "F.Fab")
		)
		(fp_line
			(start 1.5 0.643)
			(end -1.5 0.643)
			(stroke
				(width 0.1)
				(type solid)
			)
			(layer "F.Fab")
		)
		(fp_line
			(start -1.5 0.643)
			(end -1.5 -0.757)
			(stroke
				(width 0.1)
				(type solid)
			)
			(layer "F.Fab")
		)
		(fp_text user "."
			(at -1.4 1.2 90)
			(layer "F.SilkS")
			(effects
				(font
					(size 1 1)
					(thickness 0.15)
				)
			)
		)
		(fp_text user "License: Apache-2.0"
			(at -1.75 6.5 90)
			(layer "F.Fab")
			(effects
				(font
					(size 0.7 0.7)
					(thickness 0.15)
				)
				(justify left bottom)
			)
		)
		(fp_text user "Author: Antmicro"
			(at -1.829 5.25 90)
			(layer "F.Fab")
			(effects
				(font
					(size 0.7 0.7)
					(thickness 0.15)
				)
				(justify left bottom)
			)
		)
		(fp_text user "${REFERENCE}"
			(at -1.75 4 90)
			(layer "F.Fab")
			(effects
				(font
					(size 0.7 0.7)
					(thickness 0.15)
				)
				(justify left bottom)
			)
		)
		(pad "1" smd roundrect
			(at -0.954 1.1 90)
			(size 0.55 1)
			(layers "F.Cu" "F.Mask" "F.Paste")
			(roundrect_rratio 0.15)
			(net 189 "/Supply/~{PB_CTRL_IN}")
			(pinfunction "~{PB_IN}")
			(pintype "input")
		)
		(pad "2" smd roundrect
			(at -0.003 1.1 90)
			(size 0.55 1)
			(layers "F.Cu" "F.Mask" "F.Paste")
			(roundrect_rratio 0.15)
			(net 1 "GND")
			(pinfunction "GND")
			(pintype "power_in")
		)
		(pad "3" smd roundrect
			(at 0.947 1.1 90)
			(size 0.55 1)
			(layers "F.Cu" "F.Mask" "F.Paste")
			(roundrect_rratio 0.15)
			(net 38 "+3V3_AON")
			(pinfunction "VCC")
			(pintype "power_in")
		)
		(pad "4" smd roundrect
			(at 0.947 -1.214 90)
			(size 0.55 1)
			(layers "F.Cu" "F.Mask" "F.Paste")
			(roundrect_rratio 0.15)
			(net 138 "/Supply/PB_CTRL_OUT")
			(pinfunction "OUT")
			(pintype "output")
		)
		(pad "5" smd roundrect
			(at -0.003 -1.214 90)
			(size 0.55 1)
			(layers "F.Cu" "F.Mask" "F.Paste")
			(roundrect_rratio 0.15)
			(net 157 "/Supply/~{PB_CTRL_INT}")
			(pinfunction "~{INT}")
			(pintype "output")
		)
		(pad "6" smd roundrect
			(at -0.954 -1.214 90)
			(size 0.55 1)
			(layers "F.Cu" "F.Mask" "F.Paste")
			(roundrect_rratio 0.15)
			(net 137 "/Supply/~{PB_CTRL_CLR}")
			(pinfunction "~{CLR}")
			(pintype "input")
		)
	)
	(footprint "antmicro-footprints:TP_1206_SMD_RCW-0C"
		(layer "F.Cu")
		(at 262.424499 178.449 90)
		(property "Reference" "TP20"
			(at -2.29 -1.4 90)
			(layer "F.SilkS")
			(hide yes)
			(effects
				(font
					(size 0.7 0.7)
					(thickness 0.15)
				)
				(justify left bottom)
			)
		)
		(property "Value" "TP_1206_SMD_RCW-0C"
			(at -4.68 2.25 90)
			(layer "F.Fab")
			(effects
				(font
					(size 0.7 0.7)
					(thickness 0.15)
				)
				(justify left bottom)
			)
		)
		(property "Datasheet" "https://www.te.com/commerce/DocumentDelivery/DDEController?Action=srchrtrv&DocNm=1773266&DocType=DS&DocLang=English"
			(at 0 0 90)
			(layer "F.Fab")
			(hide yes)
			(effects
				(font
					(size 1.27 1.27)
					(thickness 0.15)
				)
			)
		)
		(property "MPN" "RCW-0C"
			(at 0 0 90)
			(unlocked yes)
			(layer "F.Fab")
			(hide yes)
			(effects
				(font
					(size 1 1)
					(thickness 0.15)
				)
			)
		)
		(property "Manufacturer" "TE Connectivity"
			(at 0 0 90)
			(unlocked yes)
			(layer "F.Fab")
			(hide yes)
			(effects
				(font
					(size 1 1)
					(thickness 0.15)
				)
			)
		)
		(property "Author" "Antmicro"
			(at 0 0 90)
			(unlocked yes)
			(layer "F.Fab")
			(hide yes)
			(effects
				(font
					(size 1 1)
					(thickness 0.15)
				)
			)
		)
		(property "License" "Apache-2.0"
			(at 0 0 90)
			(unlocked yes)
			(layer "F.Fab")
			(hide yes)
			(effects
				(font
					(size 1 1)
					(thickness 0.15)
				)
			)
		)
		(sheetname "/Supply/")
		(sheetfile "supply.kicad_sch")
		(attr smd)
		(fp_line
			(start 1.78 -0.981)
			(end 1.281 -0.981)
			(stroke
				(width 0.15)
				(type solid)
			)
			(layer "F.SilkS")
		)
		(fp_line
			(start 1.78 -0.981)
			(end 1.78 -0.479)
			(stroke
				(width 0.15)
				(type solid)
			)
			(layer "F.SilkS")
		)
		(fp_line
			(start -1.779 -0.981)
			(end -1.279 -0.981)
			(stroke
				(width 0.15)
				(type solid)
			)
			(layer "F.SilkS")
		)
		(fp_line
			(start -1.779 -0.981)
			(end -1.779 -0.479)
			(stroke
				(width 0.15)
				(type solid)
			)
			(layer "F.SilkS")
		)
		(fp_line
			(start -1.779 0.482)
			(end -1.779 0.98)
			(stroke
				(width 0.15)
				(type solid)
			)
			(layer "F.SilkS")
		)
		(fp_line
			(start -1.779 0.98)
			(end -1.279 0.98)
			(stroke
				(width 0.15)
				(type solid)
			)
			(layer "F.SilkS")
		)
		(fp_line
			(start 1.78 0.982)
			(end 1.78 0.482)
			(stroke
				(width 0.15)
				(type solid)
			)
			(layer "F.SilkS")
		)
		(fp_line
			(start 1.78 0.982)
			(end 1.281 0.982)
			(stroke
				(width 0.15)
				(type solid)
			)
			(layer "F.SilkS")
		)
		(fp_rect
			(start -2.101 -1.314)
			(end 2.1 1.312)
			(stroke
				(width 0.05)
				(type solid)
			)
			(fill no)
			(layer "F.CrtYd")
		)
		(fp_rect
			(start -1.601 -0.814)
			(end 1.6 0.812)
			(stroke
				(width 0.15)
				(type solid)
			)
			(fill no)
			(layer "F.Fab")
		)
		(fp_text user "Author: Antmicro"
			(at -4.68 4.25 90)
			(layer "F.Fab")
			(effects
				(font
					(size 0.7 0.7)
					(thickness 0.15)
				)
				(justify left bottom)
			)
		)
		(fp_text user "${REFERENCE}"
			(at -4.68 6.65 90)
			(layer "F.Fab")
			(effects
				(font
					(size 0.7 0.7)
					(thickness 0.15)
				)
				(justify left bottom)
			)
		)
		(fp_text user "License: Apache-2.0"
			(at -4.68 5.45 90)
			(layer "F.Fab")
			(effects
				(font
					(size 0.7 0.7)
					(thickness 0.15)
				)
				(justify left bottom)
			)
		)
		(pad "1" smd rect
			(at 0 0 90)
			(size 3.4 1.8)
			(layers "F.Cu" "F.Mask" "F.Paste")
			(net 1 "GND")
			(pinfunction "1")
			(pintype "passive")
		)
	)
	(footprint "antmicro-footprints:Fiducial_1mm_Mask2mm"
		(layer "F.Cu")
		(at 259.37 102.04)
		(descr "Circular Fiducial, 1mm bare copper, 3mm soldermask opening")
		(tags "fiducial")
		(property "Reference" "FID1006"
			(at 0 -1.4 0)
			(layer "F.SilkS")
			(hide yes)
			(effects
				(font
					(size 0.7 0.7)
					(thickness 0.15)
				)
				(justify left bottom)
			)
		)
		(property "Value" "Fiducial_1mm_Mask2mm"
			(at 0 2.2 0)
			(layer "F.Fab")
			(effects
				(font
					(size 0.7 0.7)
					(thickness 0.15)
				)
				(justify left bottom)
			)
		)
		(sheetfile "data-center-rdimm-ddr5-tester.kicad_sch")
		(attr board_only exclude_from_pos_files exclude_from_bom)
		(fp_circle
			(center 0 0)
			(end 1.24 0)
			(stroke
				(width 0.05)
				(type solid)
			)
			(fill no)
			(layer "F.CrtYd")
		)
		(fp_circle
			(center 0 0)
			(end 0.999 0)
			(stroke
				(width 0.15)
				(type solid)
			)
			(fill no)
			(layer "F.Fab")
		)
		(fp_text user "${REFERENCE}"
			(at -1.25 4.603 0)
			(layer "F.Fab")
			(effects
				(font
					(size 0.7 0.7)
					(thickness 0.15)
				)
				(justify left bottom)
			)
		)
		(fp_text user "License: Apache-2.0"
			(at -1.25 7.003 0)
			(layer "F.Fab")
			(effects
				(font
					(size 0.7 0.7)
					(thickness 0.15)
				)
				(justify left bottom)
			)
		)
		(fp_text user "Author: Antmicro"
			(at -1.25 5.803 0)
			(layer "F.Fab")
			(effects
				(font
					(size 0.7 0.7)
					(thickness 0.15)
				)
				(justify left bottom)
			)
		)
		(pad "" smd circle
			(at 0 0)
			(size 1 1)
			(layers "F.Cu" "F.Mask")
			(solder_mask_margin 0.5)
			(clearance 0.5)
		)
	)
	(footprint "antmicro-footprints:R_0603_1608Metric"
		(layer "F.Cu")
		(at 218.18 167.955 90)
		(descr "Resistor SMD 0603")
		(tags "resistor SMD 0603")
		(property "Reference" "R204"
			(at -0.02 -2.505 90)
			(layer "F.SilkS")
			(effects
				(font
					(size 0.7 0.7)
					(thickness 0.15)
				)
				(justify left bottom)
			)
		)
		(property "Value" "R_0R_22.4A_0603"
			(at 0 1.6 90)
			(layer "F.Fab")
			(effects
				(font
					(size 0.7 0.7)
					(thickness 0.15)
				)
				(justify left bottom)
			)
		)
		(property "Datasheet" "https://fscdn.rohm.com/en/products/databook/datasheet/passive/resistor/chip_resistor/pmr-jpw-e.pdf"
			(at 0 0 90)
			(layer "F.Fab")
			(hide yes)
			(effects
				(font
					(size 1.27 1.27)
					(thickness 0.15)
				)
			)
		)
		(property "Manufacturer" "ROHM Semiconductor"
			(at 0 0 90)
			(unlocked yes)
			(layer "F.Fab")
			(hide yes)
			(effects
				(font
					(size 1 1)
					(thickness 0.15)
				)
			)
		)
		(property "MPN" "PMR03EZPJ000"
			(at 0 0 90)
			(unlocked yes)
			(layer "F.Fab")
			(hide yes)
			(effects
				(font
					(size 1 1)
					(thickness 0.15)
				)
			)
		)
		(property "Val" "0R"
			(at 0 0 90)
			(unlocked yes)
			(layer "F.Fab")
			(hide yes)
			(effects
				(font
					(size 1 1)
					(thickness 0.15)
				)
			)
		)
		(property "Author" "Antmicro"
			(at 0 0 90)
			(unlocked yes)
			(layer "F.Fab")
			(hide yes)
			(effects
				(font
					(size 1 1)
					(thickness 0.15)
				)
			)
		)
		(property "License" "Apache-2.0"
			(at 0 0 90)
			(unlocked yes)
			(layer "F.Fab")
			(hide yes)
			(effects
				(font
					(size 1 1)
					(thickness 0.15)
				)
			)
		)
		(property "Max. Curr." "22.4A"
			(at 0 0 90)
			(unlocked yes)
			(layer "F.Fab")
			(hide yes)
			(effects
				(font
					(size 1 1)
					(thickness 0.15)
				)
			)
		)
		(sheetname "/Supply/DC-DC VCCINT/")
		(sheetfile "dc-dc-vccint.kicad_sch")
		(attr smd)
		(fp_line
			(start -0.15 -0.4)
			(end 0.15 -0.4)
			(stroke
				(width 0.15)
				(type solid)
			)
			(layer "F.SilkS")
		)
		(fp_line
			(start -0.15 0.4)
			(end 0.15 0.4)
			(stroke
				(width 0.15)
				(type solid)
			)
			(layer "F.SilkS")
		)
		(fp_rect
			(start -1.25 -0.65)
			(end 1.25 0.65)
			(stroke
				(width 0.05)
				(type solid)
			)
			(fill no)
			(layer "F.CrtYd")
		)
		(fp_rect
			(start -0.8 -0.4)
			(end 0.8 0.4)
			(stroke
				(width 0.15)
				(type solid)
			)
			(fill no)
			(layer "F.Fab")
		)
		(fp_text user "License: Apache-2.0"
			(at -1.25 5.9 90)
			(layer "F.Fab")
			(effects
				(font
					(size 0.7 0.7)
					(thickness 0.15)
				)
				(justify left bottom)
			)
		)
		(fp_text user "Author: Antmicro"
			(at -1.25 4.9 90)
			(layer "F.Fab")
			(effects
				(font
					(size 0.7 0.7)
					(thickness 0.15)
				)
				(justify left bottom)
			)
		)
		(fp_text user "${REFERENCE}"
			(at -1.25 3.898 90)
			(layer "F.Fab")
			(effects
				(font
					(size 0.7 0.7)
					(thickness 0.15)
				)
				(justify left bottom)
			)
		)
		(pad "1" smd roundrect
			(at -0.7 0 90)
			(size 0.8 1)
			(layers "F.Cu" "F.Mask" "F.Paste")
			(roundrect_rratio 0.2)
			(net 223 "/Supply/DC-DC VCCINT/0V85_REG0")
			(pintype "passive")
		)
		(pad "2" smd roundrect
			(at 0.7 0 90)
			(size 0.8 1)
			(layers "F.Cu" "F.Mask" "F.Paste")
			(roundrect_rratio 0.2)
			(net 553 "+0V85")
			(pintype "passive")
		)
	)
	(footprint "antmicro-footprints:Fiducial_1mm_Mask2mm"
		(layer "F.Cu")
		(at 113.585 186.315)
		(descr "Circular Fiducial, 1mm bare copper, 3mm soldermask opening")
		(tags "fiducial")
		(property "Reference" "FID1004"
			(at 0 -1.4 0)
			(layer "F.SilkS")
			(hide yes)
			(effects
				(font
					(size 0.7 0.7)
					(thickness 0.15)
				)
				(justify left bottom)
			)
		)
		(property "Value" "Fiducial_1mm_Mask2mm"
			(at 0 2.2 0)
			(layer "F.Fab")
			(effects
				(font
					(size 0.7 0.7)
					(thickness 0.15)
				)
				(justify left bottom)
			)
		)
		(sheetfile "data-center-rdimm-ddr5-tester.kicad_sch")
		(attr board_only exclude_from_pos_files exclude_from_bom)
		(fp_circle
			(center 0 0)
			(end 1.24 0)
			(stroke
				(width 0.05)
				(type solid)
			)
			(fill no)
			(layer "F.CrtYd")
		)
		(fp_circle
			(center 0 0)
			(end 0.999 0)
			(stroke
				(width 0.15)
				(type solid)
			)
			(fill no)
			(layer "F.Fab")
		)
		(fp_text user "Author: Antmicro"
			(at -1.25 5.803 0)
			(layer "F.Fab")
			(effects
				(font
					(size 0.7 0.7)
					(thickness 0.15)
				)
				(justify left bottom)
			)
		)
		(fp_text user "${REFERENCE}"
			(at -1.25 4.603 0)
			(layer "F.Fab")
			(effects
				(font
					(size 0.7 0.7)
					(thickness 0.15)
				)
				(justify left bottom)
			)
		)
		(fp_text user "License: Apache-2.0"
			(at -1.25 7.003 0)
			(layer "F.Fab")
			(effects
				(font
					(size 0.7 0.7)
					(thickness 0.15)
				)
				(justify left bottom)
			)
		)
		(pad "" smd circle
			(at 0 0)
			(size 1 1)
			(layers "F.Cu" "F.Mask")
			(solder_mask_margin 0.5)
			(clearance 0.5)
		)
	)
	(footprint "antmicro-footprints:R_0402_1005Metric"
		(layer "F.Cu")
		(at 252.785 142.4 180)
		(descr "Resistor SMD 0402")
		(tags "resistor SMD 0402")
		(property "Reference" "R62"
			(at -3.065 -0.5 0)
			(layer "F.SilkS")
			(effects
				(font
					(size 0.7 0.7)
					(thickness 0.15)
				)
				(justify right bottom)
			)
		)
		(property "Value" "R_330R_0402"
			(at -1.011843 1.772047 0)
			(layer "F.Fab")
			(effects
				(font
					(size 0.7 0.7)
					(thickness 0.15)
				)
				(justify right bottom)
			)
		)
		(property "Datasheet" "https://www.bourns.com/docs/product-datasheets/cr.pdf"
			(at 0 0 180)
			(layer "F.Fab")
			(hide yes)
			(effects
				(font
					(size 1.27 1.27)
					(thickness 0.15)
				)
			)
		)
		(property "Manufacturer" "Bourns"
			(at 0 0 180)
			(unlocked yes)
			(layer "F.Fab")
			(hide yes)
			(effects
				(font
					(size 1 1)
					(thickness 0.15)
				)
			)
		)
		(property "MPN" "CR0402-FX-3300GLF"
			(at 0 0 180)
			(unlocked yes)
			(layer "F.Fab")
			(hide yes)
			(effects
				(font
					(size 1 1)
					(thickness 0.15)
				)
			)
		)
		(property "Val" "330R"
			(at 0 0 180)
			(unlocked yes)
			(layer "F.Fab")
			(hide yes)
			(effects
				(font
					(size 1 1)
					(thickness 0.15)
				)
			)
		)
		(property "License" "Apache-2.0"
			(at 0 0 180)
			(unlocked yes)
			(layer "F.Fab")
			(hide yes)
			(effects
				(font
					(size 1 1)
					(thickness 0.15)
				)
			)
		)
		(property "Author" "Antmicro"
			(at 0 0 180)
			(unlocked yes)
			(layer "F.Fab")
			(hide yes)
			(effects
				(font
					(size 1 1)
					(thickness 0.15)
				)
			)
		)
		(property "Tolerance" "1%"
			(at 0 0 180)
			(unlocked yes)
			(layer "F.Fab")
			(hide yes)
			(effects
				(font
					(size 1 1)
					(thickness 0.15)
				)
			)
		)
		(sheetname "/DDR5 RDIMM/")
		(sheetfile "ddr5-rdimm.kicad_sch")
		(attr smd)
		(fp_rect
			(start -0.925 -0.47)
			(end 0.925 0.47)
			(stroke
				(width 0.05)
				(type default)
			)
			(fill no)
			(layer "F.CrtYd")
		)
		(fp_rect
			(start -0.5 -0.25)
			(end 0.5 0.25)
			(stroke
				(width 0.15)
				(type solid)
			)
			(fill no)
			(layer "F.Fab")
		)
		(fp_text user "Author: Antmicro"
			(at -0.95 4.169 180)
			(layer "F.Fab")
			(effects
				(font
					(size 0.7 0.7)
					(thickness 0.15)
				)
				(justify left bottom)
			)
		)
		(fp_text user "License: Apache-2.0"
			(at -0.95 5.169 180)
			(layer "F.Fab")
			(effects
				(font
					(size 0.7 0.7)
					(thickness 0.15)
				)
				(justify left bottom)
			)
		)
		(fp_text user "${REFERENCE}"
			(at -0.95 3.168 180)
			(layer "F.Fab")
			(effects
				(font
					(size 0.7 0.7)
					(thickness 0.15)
				)
				(justify left bottom)
			)
		)
		(pad "1" smd roundrect
			(at -0.48 0 180)
			(size 0.59 0.64)
			(layers "F.Cu" "F.Mask" "F.Paste")
			(roundrect_rratio 0.25)
			(net 236 "Net-(D20-C_{G})")
			(pintype "passive")
		)
		(pad "2" smd roundrect
			(at 0.48 0 180)
			(size 0.59 0.64)
			(layers "F.Cu" "F.Mask" "F.Paste")
			(roundrect_rratio 0.25)
			(net 278 "Net-(Q10-D)")
			(pintype "passive")
		)
	)
	(footprint "antmicro-footprints:R_0402_1005Metric"
		(layer "F.Cu")
		(at 120.975 170.775 90)
		(descr "Resistor SMD 0402")
		(tags "resistor SMD 0402")
		(property "Reference" "R248"
			(at 1.375 0.025 90)
			(layer "F.SilkS")
			(effects
				(font
					(size 0.7 0.7)
					(thickness 0.15)
				)
				(justify left bottom)
			)
		)
		(property "Value" "R_0R_0402"
			(at -1.011843 1.772047 90)
			(layer "F.Fab")
			(effects
				(font
					(size 0.7 0.7)
					(thickness 0.15)
				)
				(justify left bottom)
			)
		)
		(property "Datasheet" "https://industrial.panasonic.com/cdbs/www-data/pdf/RDA0000/AOA0000C301.pdf"
			(at 0 0 90)
			(layer "F.Fab")
			(hide yes)
			(effects
				(font
					(size 1.27 1.27)
					(thickness 0.15)
				)
			)
		)
		(property "MPN" "ERJ2GE0R00X"
			(at 0 0 90)
			(unlocked yes)
			(layer "F.Fab")
			(hide yes)
			(effects
				(font
					(size 1 1)
					(thickness 0.15)
				)
			)
		)
		(property "Manufacturer" "Panasonic"
			(at 0 0 90)
			(unlocked yes)
			(layer "F.Fab")
			(hide yes)
			(effects
				(font
					(size 1 1)
					(thickness 0.15)
				)
			)
		)
		(property "License" "Apache-2.0"
			(at 0 0 90)
			(unlocked yes)
			(layer "F.Fab")
			(hide yes)
			(effects
				(font
					(size 1 1)
					(thickness 0.15)
				)
			)
		)
		(property "Author" "Antmicro"
			(at 0 0 90)
			(unlocked yes)
			(layer "F.Fab")
			(hide yes)
			(effects
				(font
					(size 1 1)
					(thickness 0.15)
				)
			)
		)
		(property "Val" "0R"
			(at 0 0 90)
			(unlocked yes)
			(layer "F.Fab")
			(hide yes)
			(effects
				(font
					(size 1 1)
					(thickness 0.15)
				)
			)
		)
		(property "Tolerance" "~"
			(at 0 0 90)
			(unlocked yes)
			(layer "F.Fab")
			(hide yes)
			(effects
				(font
					(size 1 1)
					(thickness 0.15)
				)
			)
		)
		(property "Current" "1A"
			(at 0 0 90)
			(unlocked yes)
			(layer "F.Fab")
			(hide yes)
			(effects
				(font
					(size 1 1)
					(thickness 0.15)
				)
			)
		)
		(sheetname "/HDMI + SD Card/")
		(sheetfile "hdmi-sd-card.kicad_sch")
		(attr smd)
		(fp_rect
			(start -0.925 -0.47)
			(end 0.925 0.47)
			(stroke
				(width 0.05)
				(type default)
			)
			(fill no)
			(layer "F.CrtYd")
		)
		(fp_rect
			(start -0.5 -0.25)
			(end 0.5 0.25)
			(stroke
				(width 0.15)
				(type solid)
			)
			(fill no)
			(layer "F.Fab")
		)
		(fp_text user "License: Apache-2.0"
			(at -0.95 5.169 90)
			(layer "F.Fab")
			(effects
				(font
					(size 0.7 0.7)
					(thickness 0.15)
				)
				(justify left bottom)
			)
		)
		(fp_text user "Author: Antmicro"
			(at -0.95 4.169 90)
			(layer "F.Fab")
			(effects
				(font
					(size 0.7 0.7)
					(thickness 0.15)
				)
				(justify left bottom)
			)
		)
		(fp_text user "${REFERENCE}"
			(at -0.95 3.168 90)
			(layer "F.Fab")
			(effects
				(font
					(size 0.7 0.7)
					(thickness 0.15)
				)
				(justify left bottom)
			)
		)
		(pad "1" smd roundrect
			(at -0.48 0 90)
			(size 0.59 0.64)
			(layers "F.Cu" "F.Mask" "F.Paste")
			(roundrect_rratio 0.25)
			(net 810 "/HDMI + SD Card/HDMI_VDD")
			(pintype "passive")
		)
		(pad "2" smd roundrect
			(at 0.48 0 90)
			(size 0.59 0.64)
			(layers "F.Cu" "F.Mask" "F.Paste")
			(roundrect_rratio 0.25)
			(net 150 "+1V2")
			(pintype "passive")
		)
	)
	(footprint "antmicro-footprints:R_0402_1005Metric"
		(layer "F.Cu")
		(at 118.1 155.65)
		(descr "Resistor SMD 0402")
		(tags "resistor SMD 0402")
		(property "Reference" "R23"
			(at 1.85 0.575 0)
			(layer "F.SilkS")
			(effects
				(font
					(size 0.7 0.7)
					(thickness 0.15)
				)
				(justify left bottom)
			)
		)
		(property "Value" "R_10k_0402"
			(at -1.011843 1.772047 0)
			(layer "F.Fab")
			(effects
				(font
					(size 0.7 0.7)
					(thickness 0.15)
				)
				(justify left bottom)
			)
		)
		(property "Datasheet" "https://www.bourns.com/docs/product-datasheets/cr.pdf"
			(at 0 0 0)
			(layer "F.Fab")
			(hide yes)
			(effects
				(font
					(size 1.27 1.27)
					(thickness 0.15)
				)
			)
		)
		(property "MPN" "CR0402-FX-1002GLF"
			(at 0 0 0)
			(unlocked yes)
			(layer "F.Fab")
			(hide yes)
			(effects
				(font
					(size 1 1)
					(thickness 0.15)
				)
			)
		)
		(property "Manufacturer" "Bourns"
			(at 0 0 0)
			(unlocked yes)
			(layer "F.Fab")
			(hide yes)
			(effects
				(font
					(size 1 1)
					(thickness 0.15)
				)
			)
		)
		(property "License" "Apache-2.0"
			(at 0 0 0)
			(unlocked yes)
			(layer "F.Fab")
			(hide yes)
			(effects
				(font
					(size 1 1)
					(thickness 0.15)
				)
			)
		)
		(property "Author" "Antmicro"
			(at 0 0 0)
			(unlocked yes)
			(layer "F.Fab")
			(hide yes)
			(effects
				(font
					(size 1 1)
					(thickness 0.15)
				)
			)
		)
		(property "Val" "10k"
			(at 0 0 0)
			(unlocked yes)
			(layer "F.Fab")
			(hide yes)
			(effects
				(font
					(size 1 1)
					(thickness 0.15)
				)
			)
		)
		(property "Tolerance" "1%"
			(at 0 0 0)
			(unlocked yes)
			(layer "F.Fab")
			(hide yes)
			(effects
				(font
					(size 1 1)
					(thickness 0.15)
				)
			)
		)
		(sheetname "/HDMI + SD Card/")
		(sheetfile "hdmi-sd-card.kicad_sch")
		(attr smd)
		(fp_rect
			(start -0.925 -0.47)
			(end 0.925 0.47)
			(stroke
				(width 0.05)
				(type default)
			)
			(fill no)
			(layer "F.CrtYd")
		)
		(fp_rect
			(start -0.5 -0.25)
			(end 0.5 0.25)
			(stroke
				(width 0.15)
				(type solid)
			)
			(fill no)
			(layer "F.Fab")
		)
		(fp_text user "License: Apache-2.0"
			(at -0.95 5.169 0)
			(layer "F.Fab")
			(effects
				(font
					(size 0.7 0.7)
					(thickness 0.15)
				)
				(justify left bottom)
			)
		)
		(fp_text user "Author: Antmicro"
			(at -0.95 4.169 0)
			(layer "F.Fab")
			(effects
				(font
					(size 0.7 0.7)
					(thickness 0.15)
				)
				(justify left bottom)
			)
		)
		(fp_text user "${REFERENCE}"
			(at -0.95 3.168 0)
			(layer "F.Fab")
			(effects
				(font
					(size 0.7 0.7)
					(thickness 0.15)
				)
				(justify left bottom)
			)
		)
		(pad "1" smd roundrect
			(at -0.48 0)
			(size 0.59 0.64)
			(layers "F.Cu" "F.Mask" "F.Paste")
			(roundrect_rratio 0.25)
			(net 635 "/FPGA banks HP/SD.CD")
			(pintype "passive")
		)
		(pad "2" smd roundrect
			(at 0.48 0)
			(size 0.59 0.64)
			(layers "F.Cu" "F.Mask" "F.Paste")
			(roundrect_rratio 0.25)
			(net 797 "+1V8")
			(pintype "passive")
		)
	)
	(footprint "antmicro-footprints:R_0402_1005Metric"
		(layer "F.Cu")
		(at 121.681 166.1125 90)
		(descr "Resistor SMD 0402")
		(tags "resistor SMD 0402")
		(property "Reference" "R228"
			(at 0.9125 3.969 90)
			(layer "F.SilkS")
			(effects
				(font
					(size 0.7 0.7)
					(thickness 0.15)
				)
				(justify left bottom)
			)
		)
		(property "Value" "R_64k9_0402"
			(at -1.011843 1.772047 90)
			(layer "F.Fab")
			(effects
				(font
					(size 0.7 0.7)
					(thickness 0.15)
				)
				(justify left bottom)
			)
		)
		(property "Datasheet" "https://www.bourns.com/docs/product-datasheets/cr.pdf"
			(at 0 0 90)
			(layer "F.Fab")
			(hide yes)
			(effects
				(font
					(size 1.27 1.27)
					(thickness 0.15)
				)
			)
		)
		(property "MPN" "CR0402-FX-6492GLF"
			(at 0 0 90)
			(unlocked yes)
			(layer "F.Fab")
			(hide yes)
			(effects
				(font
					(size 1 1)
					(thickness 0.15)
				)
			)
		)
		(property "Manufacturer" "Bourns"
			(at 0 0 90)
			(unlocked yes)
			(layer "F.Fab")
			(hide yes)
			(effects
				(font
					(size 1 1)
					(thickness 0.15)
				)
			)
		)
		(property "License" "Apache-2.0"
			(at 0 0 90)
			(unlocked yes)
			(layer "F.Fab")
			(hide yes)
			(effects
				(font
					(size 1 1)
					(thickness 0.15)
				)
			)
		)
		(property "Author" "Antmicro"
			(at 0 0 90)
			(unlocked yes)
			(layer "F.Fab")
			(hide yes)
			(effects
				(font
					(size 1 1)
					(thickness 0.15)
				)
			)
		)
		(property "Val" "64k9"
			(at 0 0 90)
			(unlocked yes)
			(layer "F.Fab")
			(hide yes)
			(effects
				(font
					(size 1 1)
					(thickness 0.15)
				)
			)
		)
		(property "Tolerance" "1%"
			(at 0 0 90)
			(unlocked yes)
			(layer "F.Fab")
			(hide yes)
			(effects
				(font
					(size 1 1)
					(thickness 0.15)
				)
			)
		)
		(sheetname "/HDMI + SD Card/")
		(sheetfile "hdmi-sd-card.kicad_sch")
		(attr smd exclude_from_bom dnp)
		(fp_rect
			(start -0.925 -0.47)
			(end 0.925 0.47)
			(stroke
				(width 0.05)
				(type default)
			)
			(fill no)
			(layer "F.CrtYd")
		)
		(fp_rect
			(start -0.5 -0.25)
			(end 0.5 0.25)
			(stroke
				(width 0.15)
				(type solid)
			)
			(fill no)
			(layer "F.Fab")
		)
		(fp_text user "Author: Antmicro"
			(at -0.95 4.169 90)
			(layer "F.Fab")
			(effects
				(font
					(size 0.7 0.7)
					(thickness 0.15)
				)
				(justify left bottom)
			)
		)
		(fp_text user "License: Apache-2.0"
			(at -0.95 5.169 90)
			(layer "F.Fab")
			(effects
				(font
					(size 0.7 0.7)
					(thickness 0.15)
				)
				(justify left bottom)
			)
		)
		(fp_text user "${REFERENCE}"
			(at -0.95 3.168 90)
			(layer "F.Fab")
			(effects
				(font
					(size 0.7 0.7)
					(thickness 0.15)
				)
				(justify left bottom)
			)
		)
		(pad "1" smd roundrect
			(at -0.48 0 90)
			(size 0.59 0.64)
			(layers "F.Cu" "F.Mask" "F.Paste")
			(roundrect_rratio 0.25)
			(net 738 "/HDMI + SD Card/~{HDMI_SEL}")
			(pintype "passive")
		)
		(pad "2" smd roundrect
			(at 0.48 0 90)
			(size 0.59 0.64)
			(layers "F.Cu" "F.Mask" "F.Paste")
			(roundrect_rratio 0.25)
			(net 151 "+3V3")
			(pintype "passive")
		)
	)
	(footprint "antmicro-footprints:QFN-36-1EP_6x6mm_P0.5mm_EP3.7x3.7mm"
		(layer "F.Cu")
		(at 159.81 161.799999 -90)
		(property "Reference" "U39"
			(at 4.61 -1.52 0)
			(unlocked yes)
			(layer "F.SilkS")
			(effects
				(font
					(size 0.7 0.7)
					(thickness 0.15)
				)
				(justify left bottom)
			)
		)
		(property "Value" "SI5319C-C-GM-ND"
			(at -3.62 4.605 270)
			(unlocked yes)
			(layer "F.Fab")
			(effects
				(font
					(size 0.7 0.7)
					(thickness 0.15)
				)
				(justify left bottom)
			)
		)
		(property "Datasheet" "https://www.skyworksinc.com/-/media/Skyworks/SL/documents/public/data-sheets/Si5319.pdf"
			(at 0 0 270)
			(layer "F.Fab")
			(hide yes)
			(effects
				(font
					(size 1.27 1.27)
					(thickness 0.15)
				)
			)
		)
		(property "MPN" "SI5319C-C-GM-ND"
			(at 0 0 270)
			(unlocked yes)
			(layer "F.Fab")
			(hide yes)
			(effects
				(font
					(size 1 1)
					(thickness 0.15)
				)
			)
		)
		(property "Manufacturer" "Skyworks Solutions"
			(at 0 0 270)
			(unlocked yes)
			(layer "F.Fab")
			(hide yes)
			(effects
				(font
					(size 1 1)
					(thickness 0.15)
				)
			)
		)
		(property "Author" "Antmicro"
			(at 0 0 270)
			(unlocked yes)
			(layer "F.Fab")
			(hide yes)
			(effects
				(font
					(size 1 1)
					(thickness 0.15)
				)
			)
		)
		(property "License" "Apache-2.0"
			(at 0 0 270)
			(unlocked yes)
			(layer "F.Fab")
			(hide yes)
			(effects
				(font
					(size 1 1)
					(thickness 0.15)
				)
			)
		)
		(sheetname "/FPGA MGT Interface/")
		(sheetfile "fpga-mgt.kicad_sch")
		(attr smd)
		(fp_line
			(start -3.049 3.049)
			(end -2.4 3.049)
			(stroke
				(width 0.15)
				(type solid)
			)
			(layer "F.SilkS")
		)
		(fp_line
			(start 2.4 3.049)
			(end 3.049 3.049)
			(stroke
				(width 0.15)
				(type solid)
			)
			(layer "F.SilkS")
		)
		(fp_line
			(start 3.049 3.049)
			(end 3.049 2.4)
			(stroke
				(width 0.15)
				(type solid)
			)
			(layer "F.SilkS")
		)
		(fp_line
			(start -3.049 2.4)
			(end -3.049 3.049)
			(stroke
				(width 0.15)
				(type solid)
			)
			(layer "F.SilkS")
		)
		(fp_line
			(start -3.049 -2.4)
			(end -3.049 -3.049)
			(stroke
				(width 0.15)
				(type solid)
			)
			(layer "F.SilkS")
		)
		(fp_line
			(start -3.049 -3.049)
			(end -2.4 -3.049)
			(stroke
				(width 0.15)
				(type solid)
			)
			(layer "F.SilkS")
		)
		(fp_line
			(start 2.4 -3.049)
			(end 3.049 -3.049)
			(stroke
				(width 0.15)
				(type solid)
			)
			(layer "F.SilkS")
		)
		(fp_line
			(start 3.049 -3.049)
			(end 3.049 -2.4)
			(stroke
				(width 0.15)
				(type solid)
			)
			(layer "F.SilkS")
		)
		(fp_circle
			(center -3.4 -2.5)
			(end -3.35 -2.5)
			(stroke
				(width 0.15)
				(type solid)
			)
			(fill yes)
			(layer "F.SilkS")
		)
		(fp_circle
			(center -3.4 -2.5)
			(end -3.299 -2.5)
			(stroke
				(width 0.15)
				(type solid)
			)
			(fill no)
			(layer "F.SilkS")
		)
		(fp_poly
			(pts
				(xy -1.49 0.18) (xy -0.18 0.18) (xy -0.18 1.49) (xy -1.49 1.49)
			)
			(stroke
				(width 0.01)
				(type solid)
			)
			(fill yes)
			(layer "F.Paste")
		)
		(fp_poly
			(pts
				(xy 0.18 0.18) (xy 1.49 0.18) (xy 1.49 1.49) (xy 0.18 1.49)
			)
			(stroke
				(width 0.01)
				(type solid)
			)
			(fill yes)
			(layer "F.Paste")
		)
		(fp_poly
			(pts
				(xy -1.49 -1.49) (xy -0.18 -1.49) (xy -0.18 -0.18) (xy -1.49 -0.18)
			)
			(stroke
				(width 0.01)
				(type solid)
			)
			(fill yes)
			(layer "F.Paste")
		)
		(fp_poly
			(pts
				(xy 0.18 -1.49) (xy 1.49 -1.49) (xy 1.49 -0.18) (xy 0.18 -0.18)
			)
			(stroke
				(width 0.01)
				(type solid)
			)
			(fill yes)
			(layer "F.Paste")
		)
		(fp_line
			(start -3.62 3.62)
			(end -3.62 -3.62)
			(stroke
				(width 0.05)
				(type solid)
			)
			(layer "F.CrtYd")
		)
		(fp_line
			(start 3.62 3.62)
			(end -3.62 3.62)
			(stroke
				(width 0.05)
				(type solid)
			)
			(layer "F.CrtYd")
		)
		(fp_line
			(start -3.62 -3.62)
			(end 3.62 -3.62)
			(stroke
				(width 0.05)
				(type solid)
			)
			(layer "F.CrtYd")
		)
		(fp_line
			(start 3.62 -3.62)
			(end 3.62 3.62)
			(stroke
				(width 0.05)
				(type solid)
			)
			(layer "F.CrtYd")
		)
		(fp_line
			(start -3.049 3.049)
			(end -3.049 -3.049)
			(stroke
				(width 0.15)
				(type solid)
			)
			(layer "F.Fab")
		)
		(fp_line
			(start 3.049 3.049)
			(end -3.049 3.049)
			(stroke
				(width 0.15)
				(type solid)
			)
			(layer "F.Fab")
		)
		(fp_line
			(start 3.049 3.049)
			(end 3.049 -3.049)
			(stroke
				(width 0.15)
				(type solid)
			)
			(layer "F.Fab")
		)
		(fp_line
			(start 3.049 -3.049)
			(end -3.049 -3.049)
			(stroke
				(width 0.15)
				(type solid)
			)
			(layer "F.Fab")
		)
		(fp_circle
			(center -3.4 -2.5)
			(end -3.299 -2.5)
			(stroke
				(width 0.15)
				(type solid)
			)
			(fill no)
			(layer "F.Fab")
		)
		(fp_text user "${REFERENCE}"
			(at -3.97 9.005 270)
			(unlocked yes)
			(layer "F.Fab")
			(effects
				(font
					(size 0.7 0.7)
					(thickness 0.15)
				)
				(justify left bottom)
			)
		)
		(fp_text user "License: Apache-2.0"
			(at -3.97 6.605 270)
			(layer "F.Fab")
			(effects
				(font
					(size 0.7 0.7)
					(thickness 0.15)
				)
				(justify left bottom)
			)
		)
		(fp_text user "Author: Antmicro"
			(at -3.97 7.805 270)
			(layer "F.Fab")
			(effects
				(font
					(size 0.7 0.7)
					(thickness 0.15)
				)
				(justify left bottom)
			)
		)
		(pad "1" smd rect
			(at -2.815 -2 270)
			(size 1.1 0.26)
			(layers "F.Cu" "F.Mask" "F.Paste")
			(net 531 "~{SI_5319_RST}")
			(pinfunction "~{RST}")
			(pintype "input")
		)
		(pad "2" smd rect
			(at -2.815 -1.5 270)
			(size 1.1 0.26)
			(layers "F.Cu" "F.Mask" "F.Paste")
			(net 761 "unconnected-(U39-NC-Pad2)")
			(pinfunction "NC")
			(pintype "no_connect")
		)
		(pad "3" smd rect
			(at -2.815 -1 270)
			(size 1.1 0.26)
			(layers "F.Cu" "F.Mask" "F.Paste")
			(net 762 "INT_CB")
			(pinfunction "INT_CB")
			(pintype "output")
		)
		(pad "4" smd rect
			(at -2.815 -0.5 270)
			(size 1.1 0.26)
			(layers "F.Cu" "F.Mask" "F.Paste")
			(net 763 "unconnected-(U39-NC-Pad4)")
			(pinfunction "NC")
			(pintype "no_connect")
		)
		(pad "5" smd rect
			(at -2.815 0 270)
			(size 1.1 0.26)
			(layers "F.Cu" "F.Mask" "F.Paste")
			(net 151 "+3V3")
			(pinfunction "VDD")
			(pintype "power_in")
		)
		(pad "6" smd rect
			(at -2.815 0.5 270)
			(size 1.1 0.26)
			(layers "F.Cu" "F.Mask" "F.Paste")
			(net 764 "/FPGA MGT Interface/XA")
			(pinfunction "XA")
			(pintype "input")
		)
		(pad "7" smd rect
			(at -2.815 1 270)
			(size 1.1 0.26)
			(layers "F.Cu" "F.Mask" "F.Paste")
			(net 765 "/FPGA MGT Interface/XB")
			(pinfunction "XB")
			(pintype "input")
		)
		(pad "8" smd rect
			(at -2.815 1.5 270)
			(size 1.1 0.26)
			(layers "F.Cu" "F.Mask" "F.Paste")
			(net 1 "GND")
			(pinfunction "GND")
			(pintype "power_in")
		)
		(pad "9" smd rect
			(at -2.815 2 270)
			(size 1.1 0.26)
			(layers "F.Cu" "F.Mask" "F.Paste")
			(net 766 "unconnected-(U39-NC-Pad9)")
			(pinfunction "NC")
			(pintype "no_connect")
		)
		(pad "10" smd rect
			(at -2 2.815 270)
			(size 0.26 1.1)
			(layers "F.Cu" "F.Mask" "F.Paste")
			(net 151 "+3V3")
			(pinfunction "VDD")
			(pintype "passive")
		)
		(pad "11" smd rect
			(at -1.5 2.815 270)
			(size 0.26 1.1)
			(layers "F.Cu" "F.Mask" "F.Paste")
			(net 534 "Net-(U39-RATE0)")
			(pinfunction "RATE0")
			(pintype "input")
		)
		(pad "12" smd rect
			(at -1 2.815 270)
			(size 0.26 1.1)
			(layers "F.Cu" "F.Mask" "F.Paste")
			(net 669 "unconnected-(U39-NC-Pad12)")
			(pinfunction "NC")
			(pintype "no_connect")
		)
		(pad "13" smd rect
			(at -0.5 2.815 270)
			(size 0.26 1.1)
			(layers "F.Cu" "F.Mask" "F.Paste")
			(net 670 "unconnected-(U39-NC-Pad13)")
			(pinfunction "NC")
			(pintype "no_connect")
		)
		(pad "14" smd rect
			(at 0 2.815 270)
			(size 0.26 1.1)
			(layers "F.Cu" "F.Mask" "F.Paste")
			(net 706 "unconnected-(U39-NC-Pad14)")
			(pinfunction "NC")
			(pintype "no_connect")
		)
		(pad "15" smd rect
			(at 0.5 2.815 270)
			(size 0.26 1.1)
			(layers "F.Cu" "F.Mask" "F.Paste")
			(net 542 "Net-(U39-RATE1)")
			(pinfunction "RATE1")
			(pintype "input")
		)
		(pad "16" smd rect
			(at 1 2.815 270)
			(size 0.26 1.1)
			(layers "F.Cu" "F.Mask" "F.Paste")
			(net 488 "/FPGA MGT Interface/HDMI_REC_CLK_C_P")
			(pinfunction "CKIN+")
			(pintype "input")
		)
		(pad "17" smd rect
			(at 1.5 2.815 270)
			(size 0.26 1.1)
			(layers "F.Cu" "F.Mask" "F.Paste")
			(net 489 "/FPGA MGT Interface/HDMI_REC_CLK_C_N")
			(pinfunction "CKIN-")
			(pintype "input")
		)
		(pad "18" smd rect
			(at 2 2.815 270)
			(size 0.26 1.1)
			(layers "F.Cu" "F.Mask" "F.Paste")
			(net 767 "LOL")
			(pinfunction "LOL")
			(pintype "output")
		)
		(pad "19" smd rect
			(at 2.815 2 270)
			(size 1.1 0.26)
			(layers "F.Cu" "F.Mask" "F.Paste")
			(net 1 "GND")
			(pinfunction "GND")
			(pintype "passive")
		)
		(pad "20" smd rect
			(at 2.815 1.5 270)
			(size 1.1 0.26)
			(layers "F.Cu" "F.Mask" "F.Paste")
			(net 1 "GND")
			(pinfunction "GND")
			(pintype "passive")
		)
		(pad "21" smd rect
			(at 2.815 1 270)
			(size 1.1 0.26)
			(layers "F.Cu" "F.Mask" "F.Paste")
			(net 708 "Net-(U39-CS)")
			(pinfunction "CS")
			(pintype "input")
		)
		(pad "22" smd rect
			(at 2.815 0.5 270)
			(size 1.1 0.26)
			(layers "F.Cu" "F.Mask" "F.Paste")
			(net 768 "/FPGA MGT Interface/HDMI_CTL.SCL")
			(pinfunction "SCL")
			(pintype "input")
		)
		(pad "23" smd rect
			(at 2.815 0 270)
			(size 1.1 0.26)
			(layers "F.Cu" "F.Mask" "F.Paste")
			(net 769 "/FPGA MGT Interface/HDMI_CTL.SDA")
			(pinfunction "SDA_SDO")
			(pintype "input")
		)
		(pad "24" smd rect
			(at 2.815 -0.5 270)
			(size 1.1 0.26)
			(layers "F.Cu" "F.Mask" "F.Paste")
			(net 1 "GND")
			(pinfunction "A0")
			(pintype "input")
		)
		(pad "25" smd rect
			(at 2.815 -1 270)
			(size 1.1 0.26)
			(layers "F.Cu" "F.Mask" "F.Paste")
			(net 1 "GND")
			(pinfunction "A1")
			(pintype "input")
		)
		(pad "26" smd rect
			(at 2.815 -1.5 270)
			(size 1.1 0.26)
			(layers "F.Cu" "F.Mask" "F.Paste")
			(net 1 "GND")
			(pinfunction "A2_~{SS}")
			(pintype "input")
		)
		(pad "27" smd rect
			(at 2.815 -2 270)
			(size 1.1 0.26)
			(layers "F.Cu" "F.Mask" "F.Paste")
			(net 770 "unconnected-(U39-SDI-Pad27)")
			(pinfunction "SDI")
			(pintype "input+no_connect")
		)
		(pad "28" smd rect
			(at 2 -2.815 270)
			(size 0.26 1.1)
			(layers "F.Cu" "F.Mask" "F.Paste")
			(net 389 "/FPGA MGT Interface/HDMI_SI5319_C_CLK_P")
			(pinfunction "CKOUT+")
			(pintype "output")
		)
		(pad "29" smd rect
			(at 1.5 -2.815 270)
			(size 0.26 1.1)
			(layers "F.Cu" "F.Mask" "F.Paste")
			(net 386 "/FPGA MGT Interface/HDMI_SI5319_C_CLK_N")
			(pinfunction "CKOUT-")
			(pintype "output")
		)
		(pad "30" smd rect
			(at 1 -2.815 270)
			(size 0.26 1.1)
			(layers "F.Cu" "F.Mask" "F.Paste")
			(net 750 "unconnected-(U39-NC-Pad30)")
			(pinfunction "NC")
			(pintype "no_connect")
		)
		(pad "31" smd rect
			(at 0.5 -2.815 270)
			(size 0.26 1.1)
			(layers "F.Cu" "F.Mask" "F.Paste")
			(net 1 "GND")
			(pinfunction "GND")
			(pintype "passive")
		)
		(pad "32" smd rect
			(at 0 -2.815 270)
			(size 0.26 1.1)
			(layers "F.Cu" "F.Mask" "F.Paste")
			(net 151 "+3V3")
			(pinfunction "VDD")
			(pintype "passive")
		)
		(pad "33" smd rect
			(at -0.5 -2.815 270)
			(size 0.26 1.1)
			(layers "F.Cu" "F.Mask" "F.Paste")
			(net 751 "unconnected-(U39-NC-Pad33)")
			(pinfunction "NC")
			(pintype "no_connect")
		)
		(pad "34" smd rect
			(at -1 -2.815 270)
			(size 0.26 1.1)
			(layers "F.Cu" "F.Mask" "F.Paste")
			(net 752 "unconnected-(U39-NC-Pad34)")
			(pinfunction "NC")
			(pintype "no_connect")
		)
		(pad "35" smd rect
			(at -1.5 -2.815 270)
			(size 0.26 1.1)
			(layers "F.Cu" "F.Mask" "F.Paste")
			(net 753 "unconnected-(U39-NC-Pad35)")
			(pinfunction "NC")
			(pintype "no_connect")
		)
		(pad "36" smd rect
			(at -2 -2.815 270)
			(size 0.26 1.1)
			(layers "F.Cu" "F.Mask" "F.Paste")
			(net 1 "GND")
			(pinfunction "CMODE")
			(pintype "input")
		)
		(pad "37" smd rect
			(at 0 0 270)
			(size 3.7 3.7)
			(layers "F.Cu" "F.Mask")
			(net 1 "GND")
			(pinfunction "GND")
			(pintype "passive")
		)
	)
	(footprint "antmicro-footprints:R_0402_1005Metric"
		(layer "F.Cu")
		(at 119.15 150.61 180)
		(descr "Resistor SMD 0402")
		(tags "resistor SMD 0402")
		(property "Reference" "R29"
			(at -5.11 -0.415 0)
			(layer "F.SilkS")
			(effects
				(font
					(size 0.7 0.7)
					(thickness 0.15)
				)
				(justify right bottom)
			)
		)
		(property "Value" "R_49k9_0402"
			(at -1.011843 1.772047 0)
			(layer "F.Fab")
			(effects
				(font
					(size 0.7 0.7)
					(thickness 0.15)
				)
				(justify right bottom)
			)
		)
		(property "Datasheet" "https://www.bourns.com/docs/product-datasheets/cr.pdf"
			(at 0 0 180)
			(layer "F.Fab")
			(hide yes)
			(effects
				(font
					(size 1.27 1.27)
					(thickness 0.15)
				)
			)
		)
		(property "MPN" "CR0402-FX-4992GLF"
			(at 0 0 180)
			(unlocked yes)
			(layer "F.Fab")
			(hide yes)
			(effects
				(font
					(size 1 1)
					(thickness 0.15)
				)
			)
		)
		(property "Manufacturer" "Bourns"
			(at 0 0 180)
			(unlocked yes)
			(layer "F.Fab")
			(hide yes)
			(effects
				(font
					(size 1 1)
					(thickness 0.15)
				)
			)
		)
		(property "License" "Apache-2.0"
			(at 0 0 180)
			(unlocked yes)
			(layer "F.Fab")
			(hide yes)
			(effects
				(font
					(size 1 1)
					(thickness 0.15)
				)
			)
		)
		(property "Author" "Antmicro"
			(at 0 0 180)
			(unlocked yes)
			(layer "F.Fab")
			(hide yes)
			(effects
				(font
					(size 1 1)
					(thickness 0.15)
				)
			)
		)
		(property "Val" "49k9"
			(at 0 0 180)
			(unlocked yes)
			(layer "F.Fab")
			(hide yes)
			(effects
				(font
					(size 1 1)
					(thickness 0.15)
				)
			)
		)
		(property "Tolerance" "1%"
			(at 0 0 180)
			(unlocked yes)
			(layer "F.Fab")
			(hide yes)
			(effects
				(font
					(size 1 1)
					(thickness 0.15)
				)
			)
		)
		(sheetname "/HDMI + SD Card/")
		(sheetfile "hdmi-sd-card.kicad_sch")
		(attr smd)
		(fp_rect
			(start -0.925 -0.47)
			(end 0.925 0.47)
			(stroke
				(width 0.05)
				(type default)
			)
			(fill no)
			(layer "F.CrtYd")
		)
		(fp_rect
			(start -0.5 -0.25)
			(end 0.5 0.25)
			(stroke
				(width 0.15)
				(type solid)
			)
			(fill no)
			(layer "F.Fab")
		)
		(fp_text user "License: Apache-2.0"
			(at -0.95 5.169 180)
			(layer "F.Fab")
			(effects
				(font
					(size 0.7 0.7)
					(thickness 0.15)
				)
				(justify left bottom)
			)
		)
		(fp_text user "${REFERENCE}"
			(at -0.95 3.168 180)
			(layer "F.Fab")
			(effects
				(font
					(size 0.7 0.7)
					(thickness 0.15)
				)
				(justify left bottom)
			)
		)
		(fp_text user "Author: Antmicro"
			(at -0.95 4.169 180)
			(layer "F.Fab")
			(effects
				(font
					(size 0.7 0.7)
					(thickness 0.15)
				)
				(justify left bottom)
			)
		)
		(pad "1" smd roundrect
			(at -0.48 0 180)
			(size 0.59 0.64)
			(layers "F.Cu" "F.Mask" "F.Paste")
			(roundrect_rratio 0.25)
			(net 675 "Net-(L5-Pad2)")
			(pintype "passive")
		)
		(pad "2" smd roundrect
			(at 0.48 0 180)
			(size 0.59 0.64)
			(layers "F.Cu" "F.Mask" "F.Paste")
			(roundrect_rratio 0.25)
			(net 322 "Net-(C300-Pad2)")
			(pintype "passive")
		)
	)
	(footprint "antmicro-footprints:C_0805_2012Metric"
		(layer "F.Cu")
		(at 261.02 172.9095 90)
		(descr "Capacitor SMD 0805")
		(tags "capacitor SMD 0805")
		(property "Reference" "C171"
			(at 1.8595 1.43 90)
			(layer "F.SilkS")
			(effects
				(font
					(size 0.7 0.7)
					(thickness 0.15)
				)
				(justify left bottom)
			)
		)
		(property "Value" "C_22u_25V_0805"
			(at -2.055717 1.963152 90)
			(layer "F.Fab")
			(effects
				(font
					(size 0.7 0.7)
					(thickness 0.15)
				)
				(justify left bottom)
			)
		)
		(property "Datasheet" "https://product.samsungsem.com/mlcc/CL21A226MAYNNN.do"
			(at 0 0 90)
			(layer "F.Fab")
			(hide yes)
			(effects
				(font
					(size 1.27 1.27)
					(thickness 0.15)
				)
			)
		)
		(property "MPN" "CL21A226MAYNNNE"
			(at 0 0 90)
			(unlocked yes)
			(layer "F.Fab")
			(hide yes)
			(effects
				(font
					(size 1 1)
					(thickness 0.15)
				)
			)
		)
		(property "Manufacturer" "Samsung Electro-Mechanics"
			(at 0 0 90)
			(unlocked yes)
			(layer "F.Fab")
			(hide yes)
			(effects
				(font
					(size 1 1)
					(thickness 0.15)
				)
			)
		)
		(property "License" "Apache-2.0"
			(at 0 0 90)
			(unlocked yes)
			(layer "F.Fab")
			(hide yes)
			(effects
				(font
					(size 1 1)
					(thickness 0.15)
				)
			)
		)
		(property "Author" "Antmicro"
			(at 0 0 90)
			(unlocked yes)
			(layer "F.Fab")
			(hide yes)
			(effects
				(font
					(size 1 1)
					(thickness 0.15)
				)
			)
		)
		(property "Val" "22u"
			(at 0 0 90)
			(unlocked yes)
			(layer "F.Fab")
			(hide yes)
			(effects
				(font
					(size 1 1)
					(thickness 0.15)
				)
			)
		)
		(property "Voltage" "25V"
			(at 0 0 90)
			(unlocked yes)
			(layer "F.Fab")
			(hide yes)
			(effects
				(font
					(size 1 1)
					(thickness 0.15)
				)
			)
		)
		(property "Dielectric" "X5R"
			(at 0 0 90)
			(unlocked yes)
			(layer "F.Fab")
			(hide yes)
			(effects
				(font
					(size 1 1)
					(thickness 0.15)
				)
			)
		)
		(property "Public" "False"
			(at 0 0 90)
			(unlocked yes)
			(layer "F.Fab")
			(hide yes)
			(effects
				(font
					(size 1 1)
					(thickness 0.15)
				)
			)
		)
		(sheetname "/Supply/DC-DC AUX, MGT/")
		(sheetfile "dc-dc-aux-mgt.kicad_sch")
		(attr smd)
		(fp_line
			(start -0.3 -0.7)
			(end 0.3 -0.7)
			(stroke
				(width 0.15)
				(type solid)
			)
			(layer "F.SilkS")
		)
		(fp_line
			(start -0.3 0.7)
			(end 0.3 0.7)
			(stroke
				(width 0.15)
				(type solid)
			)
			(layer "F.SilkS")
		)
		(fp_rect
			(start 1.95 -0.9)
			(end -1.95 0.9)
			(stroke
				(width 0.05)
				(type default)
			)
			(fill no)
			(layer "F.CrtYd")
		)
		(fp_rect
			(start -0.95 -0.675)
			(end 0.95 0.675)
			(stroke
				(width 0.15)
				(type solid)
			)
			(fill no)
			(layer "F.Fab")
		)
		(fp_text user "Author: Antmicro"
			(at -1.9 5.947 90)
			(layer "F.Fab")
			(effects
				(font
					(size 0.7 0.7)
					(thickness 0.15)
				)
				(justify left bottom)
			)
		)
		(fp_text user "${REFERENCE}"
			(at -1.9 3.947 90)
			(layer "F.Fab")
			(effects
				(font
					(size 0.7 0.7)
					(thickness 0.15)
				)
				(justify left bottom)
			)
		)
		(fp_text user "License: Apache-2.0"
			(at -1.9 4.947 90)
			(layer "F.Fab")
			(effects
				(font
					(size 0.7 0.7)
					(thickness 0.15)
				)
				(justify left bottom)
			)
		)
		(pad "1" smd roundrect
			(at -1.1 0 90)
			(size 1.2 1.3)
			(layers "F.Cu" "F.Mask" "F.Paste")
			(roundrect_rratio 0.25)
			(net 1 "GND")
			(pintype "passive")
		)
		(pad "2" smd roundrect
			(at 1.1 0 90)
			(size 1.2 1.3)
			(layers "F.Cu" "F.Mask" "F.Paste")
			(roundrect_rratio 0.25)
			(net 35 "VDC")
			(pintype "passive")
		)
	)
	(footprint "antmicro-footprints:C_0603_1608Metric"
		(layer "F.Cu")
		(at 149.224499 193.749 180)
		(descr "Capacitor SMD 0603")
		(tags "capacitor 0603")
		(property "Reference" "C225"
			(at -2.475501 -1.551 0)
			(layer "F.SilkS")
			(effects
				(font
					(size 0.7 0.7)
					(thickness 0.15)
				)
				(justify right bottom)
			)
		)
		(property "Value" "C_10u_25V_0603"
			(at -1.42757 1.770288 0)
			(layer "F.Fab")
			(effects
				(font
					(size 0.7 0.7)
					(thickness 0.15)
				)
				(justify right bottom)
			)
		)
		(property "Datasheet" "https://product.tdk.com/en/search/capacitor/ceramic/mlcc/info?part_no=C1608X5R1E106M080AC"
			(at 0 0 180)
			(layer "F.Fab")
			(hide yes)
			(effects
				(font
					(size 1.27 1.27)
					(thickness 0.15)
				)
			)
		)
		(property "MPN" "C1608X5R1E106M080AC"
			(at 0 0 180)
			(unlocked yes)
			(layer "F.Fab")
			(hide yes)
			(effects
				(font
					(size 1 1)
					(thickness 0.15)
				)
			)
		)
		(property "Manufacturer" "TDK"
			(at 0 0 180)
			(unlocked yes)
			(layer "F.Fab")
			(hide yes)
			(effects
				(font
					(size 1 1)
					(thickness 0.15)
				)
			)
		)
		(property "License" "Apache-2.0"
			(at 0 0 180)
			(unlocked yes)
			(layer "F.Fab")
			(hide yes)
			(effects
				(font
					(size 1 1)
					(thickness 0.15)
				)
			)
		)
		(property "Author" "Antmicro"
			(at 0 0 180)
			(unlocked yes)
			(layer "F.Fab")
			(hide yes)
			(effects
				(font
					(size 1 1)
					(thickness 0.15)
				)
			)
		)
		(property "Val" "10u"
			(at 0 0 180)
			(unlocked yes)
			(layer "F.Fab")
			(hide yes)
			(effects
				(font
					(size 1 1)
					(thickness 0.15)
				)
			)
		)
		(property "Voltage" "25V"
			(at 0 0 180)
			(unlocked yes)
			(layer "F.Fab")
			(hide yes)
			(effects
				(font
					(size 1 1)
					(thickness 0.15)
				)
			)
		)
		(property "Dielectric" ""
			(at 0 0 180)
			(unlocked yes)
			(layer "F.Fab")
			(hide yes)
			(effects
				(font
					(size 1 1)
					(thickness 0.15)
				)
			)
		)
		(sheetname "/PCIe connector/")
		(sheetfile "pcie-connector.kicad_sch")
		(attr smd)
		(fp_line
			(start -0.15 0.4)
			(end 0.15 0.4)
			(stroke
				(width 0.15)
				(type solid)
			)
			(layer "F.SilkS")
		)
		(fp_line
			(start -0.15 -0.4)
			(end 0.15 -0.4)
			(stroke
				(width 0.15)
				(type solid)
			)
			(layer "F.SilkS")
		)
		(fp_rect
			(start -1.25 -0.65)
			(end 1.25 0.65)
			(stroke
				(width 0.05)
				(type solid)
			)
			(fill no)
			(layer "F.CrtYd")
		)
		(fp_rect
			(start -0.8 -0.4)
			(end 0.8 0.4)
			(stroke
				(width 0.15)
				(type solid)
			)
			(fill no)
			(layer "F.Fab")
		)
		(fp_text user "Author: Antmicro"
			(at -1.682 4.894 180)
			(layer "F.Fab")
			(effects
				(font
					(size 0.7 0.7)
					(thickness 0.15)
				)
				(justify left bottom)
			)
		)
		(fp_text user "License: Apache-2.0"
			(at -1.682 5.895 180)
			(layer "F.Fab")
			(effects
				(font
					(size 0.7 0.7)
					(thickness 0.15)
				)
				(justify left bottom)
			)
		)
		(fp_text user "${REFERENCE}"
			(at -1.682 3.895 180)
			(layer "F.Fab")
			(effects
				(font
					(size 0.7 0.7)
					(thickness 0.15)
				)
				(justify left bottom)
			)
		)
		(pad "1" smd roundrect
			(at -0.7 0 180)
			(size 0.8 1)
			(layers "F.Cu" "F.Mask" "F.Paste")
			(roundrect_rratio 0.2)
			(net 1 "GND")
			(pintype "passive")
		)
		(pad "2" smd roundrect
			(at 0.7 0 180)
			(size 0.8 1)
			(layers "F.Cu" "F.Mask" "F.Paste")
			(roundrect_rratio 0.2)
			(net 10 "+12V")
			(pintype "passive")
		)
	)
	(footprint "antmicro-footprints:NetTie-2_SMD_Pad0.127mm"
		(layer "F.Cu")
		(at 246.877 177.55)
		(descr "Net tie, 2 pin, 0.127mm  SMD pads")
		(tags "net tie")
		(property "Reference" "NT1"
			(at -0.128 -1.345 0)
			(layer "F.SilkS")
			(hide yes)
			(effects
				(font
					(size 0.7 0.7)
					(thickness 0.15)
				)
				(justify left bottom)
			)
		)
		(property "Value" "Net-Tie_P0.127mm"
			(at 0 1.199 0)
			(layer "F.Fab")
			(effects
				(font
					(size 0.7 0.7)
					(thickness 0.15)
				)
				(justify left bottom)
			)
		)
		(property "MPN" ""
			(at 0 0 0)
			(unlocked yes)
			(layer "F.Fab")
			(hide yes)
			(effects
				(font
					(size 1 1)
					(thickness 0.15)
				)
			)
		)
		(property "Manufacturer" ""
			(at 0 0 0)
			(unlocked yes)
			(layer "F.Fab")
			(hide yes)
			(effects
				(font
					(size 1 1)
					(thickness 0.15)
				)
			)
		)
		(property "Author" "Antmicro"
			(at 0 0 0)
			(unlocked yes)
			(layer "F.Fab")
			(hide yes)
			(effects
				(font
					(size 1 1)
					(thickness 0.15)
				)
			)
		)
		(property "License" "Apache-2.0"
			(at 0 0 0)
			(unlocked yes)
			(layer "F.Fab")
			(hide yes)
			(effects
				(font
					(size 1 1)
					(thickness 0.15)
				)
			)
		)
		(property ki_fp_filters "Net*Tie*")
		(sheetname "/Supply/DC-DC AUX, MGT/")
		(sheetfile "dc-dc-aux-mgt.kicad_sch")
		(attr through_hole exclude_from_pos_files exclude_from_bom)
		(net_tie_pad_groups "1, 2")
		(fp_poly
			(pts
				(xy -0.0635 -0.0635) (xy 0.0625 -0.0635) (xy 0.0625 0.0635) (xy -0.0635 0.0635)
			)
			(stroke
				(width 0)
				(type solid)
			)
			(fill yes)
			(layer "F.Cu")
		)
		(fp_poly
			(pts
				(xy 0.2 -0.16) (xy 0.29 -0.07) (xy 0.29 0.07) (xy 0.2 0.16) (xy -0.2 0.16) (xy -0.29 0.07) (xy -0.29 -0.06)
				(xy -0.19 -0.16)
			)
			(stroke
				(width 0.05)
				(type solid)
			)
			(fill no)
			(layer "F.CrtYd")
		)
		(fp_text user "License: Apache-2.0"
			(at -0.128 5.6 0)
			(layer "F.Fab")
			(effects
				(font
					(size 0.7 0.7)
					(thickness 0.15)
				)
				(justify left bottom)
			)
		)
		(fp_text user "${REFERENCE}"
			(at -0.128 3.2 0)
			(layer "F.Fab")
			(effects
				(font
					(size 0.7 0.7)
					(thickness 0.15)
				)
				(justify left bottom)
			)
		)
		(fp_text user "Author: Antmicro"
			(at -0.128 4.4 0)
			(layer "F.Fab")
			(effects
				(font
					(size 0.7 0.7)
					(thickness 0.15)
				)
				(justify left bottom)
			)
		)
		(pad "1" smd roundrect
			(at -0.127 0 180)
			(size 0.127 0.127)
			(layers "F.Cu")
			(roundrect_rratio 0.5)
			(chamfer_ratio 0)
			(chamfer top_left bottom_left)
			(net 681 "/Supply/DC-DC AUX, MGT/1V8_SEN_+")
			(pinfunction "1")
			(pintype "passive")
		)
		(pad "2" smd roundrect
			(at 0.126 0)
			(size 0.127 0.127)
			(layers "F.Cu")
			(roundrect_rratio 0.5)
			(chamfer_ratio 0)
			(chamfer top_left bottom_left)
			(net 37 "/Supply/DC-DC AUX, MGT/1V8_local")
			(pinfunction "2")
			(pintype "passive")
		)
	)
	(footprint "antmicro-footprints:R_0603_1608Metric"
		(layer "F.Cu")
		(at 228.875 167.95 90)
		(descr "Resistor SMD 0603")
		(tags "resistor SMD 0603")
		(property "Reference" "R216"
			(at 1.175 0.5 90)
			(layer "F.SilkS")
			(effects
				(font
					(size 0.7 0.7)
					(thickness 0.15)
				)
				(justify left bottom)
			)
		)
		(property "Value" "R_0R_22.4A_0603"
			(at 0 1.6 90)
			(layer "F.Fab")
			(effects
				(font
					(size 0.7 0.7)
					(thickness 0.15)
				)
				(justify left bottom)
			)
		)
		(property "Datasheet" "https://fscdn.rohm.com/en/products/databook/datasheet/passive/resistor/chip_resistor/pmr-jpw-e.pdf"
			(at 0 0 90)
			(layer "F.Fab")
			(hide yes)
			(effects
				(font
					(size 1.27 1.27)
					(thickness 0.15)
				)
			)
		)
		(property "Manufacturer" "ROHM Semiconductor"
			(at 0 0 90)
			(unlocked yes)
			(layer "F.Fab")
			(hide yes)
			(effects
				(font
					(size 1 1)
					(thickness 0.15)
				)
			)
		)
		(property "MPN" "PMR03EZPJ000"
			(at 0 0 90)
			(unlocked yes)
			(layer "F.Fab")
			(hide yes)
			(effects
				(font
					(size 1 1)
					(thickness 0.15)
				)
			)
		)
		(property "Val" "0R"
			(at 0 0 90)
			(unlocked yes)
			(layer "F.Fab")
			(hide yes)
			(effects
				(font
					(size 1 1)
					(thickness 0.15)
				)
			)
		)
		(property "Author" "Antmicro"
			(at 0 0 90)
			(unlocked yes)
			(layer "F.Fab")
			(hide yes)
			(effects
				(font
					(size 1 1)
					(thickness 0.15)
				)
			)
		)
		(property "License" "Apache-2.0"
			(at 0 0 90)
			(unlocked yes)
			(layer "F.Fab")
			(hide yes)
			(effects
				(font
					(size 1 1)
					(thickness 0.15)
				)
			)
		)
		(property "Max. Curr." "22.4A"
			(at 0 0 90)
			(unlocked yes)
			(layer "F.Fab")
			(hide yes)
			(effects
				(font
					(size 1 1)
					(thickness 0.15)
				)
			)
		)
		(sheetname "/Supply/DC-DC VCCINT/")
		(sheetfile "dc-dc-vccint.kicad_sch")
		(attr smd)
		(fp_line
			(start -0.15 -0.4)
			(end 0.15 -0.4)
			(stroke
				(width 0.15)
				(type solid)
			)
			(layer "F.SilkS")
		)
		(fp_line
			(start -0.15 0.4)
			(end 0.15 0.4)
			(stroke
				(width 0.15)
				(type solid)
			)
			(layer "F.SilkS")
		)
		(fp_rect
			(start -1.25 -0.65)
			(end 1.25 0.65)
			(stroke
				(width 0.05)
				(type solid)
			)
			(fill no)
			(layer "F.CrtYd")
		)
		(fp_rect
			(start -0.8 -0.4)
			(end 0.8 0.4)
			(stroke
				(width 0.15)
				(type solid)
			)
			(fill no)
			(layer "F.Fab")
		)
		(fp_text user "License: Apache-2.0"
			(at -1.25 5.9 90)
			(layer "F.Fab")
			(effects
				(font
					(size 0.7 0.7)
					(thickness 0.15)
				)
				(justify left bottom)
			)
		)
		(fp_text user "Author: Antmicro"
			(at -1.25 4.9 90)
			(layer "F.Fab")
			(effects
				(font
					(size 0.7 0.7)
					(thickness 0.15)
				)
				(justify left bottom)
			)
		)
		(fp_text user "${REFERENCE}"
			(at -1.25 3.898 90)
			(layer "F.Fab")
			(effects
				(font
					(size 0.7 0.7)
					(thickness 0.15)
				)
				(justify left bottom)
			)
		)
		(pad "1" smd roundrect
			(at -0.7 0 90)
			(size 0.8 1)
			(layers "F.Cu" "F.Mask" "F.Paste")
			(roundrect_rratio 0.2)
			(net 224 "/Supply/DC-DC VCCINT/0V85_REG1")
			(pintype "passive")
		)
		(pad "2" smd roundrect
			(at 0.7 0 90)
			(size 0.8 1)
			(layers "F.Cu" "F.Mask" "F.Paste")
			(roundrect_rratio 0.2)
			(net 553 "+0V85")
			(pintype "passive")
		)
	)
	(footprint "antmicro-footprints:TP_SMD_1mm"
		(layer "F.Cu")
		(at 109.274499 137.449)
		(property "Reference" "TP22"
			(at 0 -0.731898 0)
			(layer "F.SilkS")
			(hide yes)
			(effects
				(font
					(size 0.7 0.7)
					(thickness 0.15)
				)
				(justify left bottom)
			)
		)
		(property "Value" "TP_1mm_SMD"
			(at 0 1.4 0)
			(layer "F.Fab")
			(effects
				(font
					(size 0.7 0.7)
					(thickness 0.15)
				)
				(justify left bottom)
			)
		)
		(property "MPN" ""
			(at 0 0 0)
			(unlocked yes)
			(layer "F.Fab")
			(hide yes)
			(effects
				(font
					(size 1 1)
					(thickness 0.15)
				)
			)
		)
		(property "Manufacturer" ""
			(at 0 0 0)
			(unlocked yes)
			(layer "F.Fab")
			(hide yes)
			(effects
				(font
					(size 1 1)
					(thickness 0.15)
				)
			)
		)
		(property "Author" "Antmicro"
			(at 0 0 0)
			(unlocked yes)
			(layer "F.Fab")
			(hide yes)
			(effects
				(font
					(size 1 1)
					(thickness 0.15)
				)
			)
		)
		(property "License" "Apache-2.0"
			(at 0 0 0)
			(unlocked yes)
			(layer "F.Fab")
			(hide yes)
			(effects
				(font
					(size 1 1)
					(thickness 0.15)
				)
			)
		)
		(sheetname "/Debug FTDI + VNA/")
		(sheetfile "debug-ftdi.kicad_sch")
		(attr exclude_from_pos_files)
		(fp_circle
			(center 0 0)
			(end 0.6 0)
			(stroke
				(width 0.05)
				(type default)
			)
			(fill no)
			(layer "F.CrtYd")
		)
		(fp_text user "${REFERENCE}"
			(at -0.5 2.8 0)
			(layer "F.Fab")
			(effects
				(font
					(size 0.7 0.7)
					(thickness 0.15)
				)
				(justify left bottom)
			)
		)
		(fp_text user "Author: Antmicro"
			(at -0.5 4 0)
			(layer "F.Fab")
			(effects
				(font
					(size 0.7 0.7)
					(thickness 0.15)
				)
				(justify left bottom)
			)
		)
		(fp_text user "License: Apache-2.0"
			(at -0.5 5.2 0)
			(layer "F.Fab")
			(effects
				(font
					(size 0.7 0.7)
					(thickness 0.15)
				)
				(justify left bottom)
			)
		)
		(pad "1" smd circle
			(at 0 0)
			(size 1 1)
			(layers "F.Cu" "F.Mask")
			(net 2 "/Debug FTDI + VNA/VBUS")
			(pinfunction "1")
			(pintype "passive")
		)
	)
	(footprint "antmicro-footprints:SW_DIP_SPSTx08_Slide_Copal_CVS-08xB_W5.9mm_P1mm"
		(layer "F.Cu")
		(at 243.953 141.601)
		(descr "SMD 8x-dip-switch SPST Copal_CVS-08xB, Slide, row spacing 5.9 mm (232 mils), body size  (see http://www.nidec-copal-electronics.com/e/catalog/switch/cvs.pdf)")
		(tags "SMD DIP Switch SPST Slide 5.9mm 232mil")
		(property "Reference" "SW4"
			(at -3.853 5.999 0)
			(layer "F.SilkS")
			(effects
				(font
					(size 0.7 0.7)
					(thickness 0.15)
				)
				(justify left bottom)
			)
		)
		(property "Value" "SW_CVS-08TB"
			(at -14.59 6.29 0)
			(layer "F.Fab")
			(effects
				(font
					(size 0.7 0.7)
					(thickness 0.15)
				)
				(justify left bottom)
			)
		)
		(property "Datasheet" "https://www.mouser.com/datasheet/2/972/cvs-1827291.pdf"
			(at 0 0 0)
			(layer "F.Fab")
			(hide yes)
			(effects
				(font
					(size 1.27 1.27)
					(thickness 0.15)
				)
			)
		)
		(property "MPN" "CVS-08TB"
			(at 0 0 0)
			(unlocked yes)
			(layer "F.Fab")
			(hide yes)
			(effects
				(font
					(size 1 1)
					(thickness 0.15)
				)
			)
		)
		(property "Manufacturer" "Nidec Components"
			(at 0 0 0)
			(unlocked yes)
			(layer "F.Fab")
			(hide yes)
			(effects
				(font
					(size 1 1)
					(thickness 0.15)
				)
			)
		)
		(property "Author" "Antmicro"
			(at 0 0 0)
			(unlocked yes)
			(layer "F.Fab")
			(hide yes)
			(effects
				(font
					(size 1 1)
					(thickness 0.15)
				)
			)
		)
		(property "License" "Apache-2.0"
			(at 0 0 0)
			(unlocked yes)
			(layer "F.Fab")
			(hide yes)
			(effects
				(font
					(size 1 1)
					(thickness 0.15)
				)
			)
		)
		(property ki_fp_filters "SW?DIP?x2*")
		(sheetname "/Supply/")
		(sheetfile "supply.kicad_sch")
		(attr smd)
		(fp_line
			(start -1.561 -4.912)
			(end 1.56 -4.912)
			(stroke
				(width 0.15)
				(type solid)
			)
			(layer "F.SilkS")
		)
		(fp_line
			(start -1.561 4.91)
			(end 1.56 4.91)
			(stroke
				(width 0.15)
				(type solid)
			)
			(layer "F.SilkS")
		)
		(fp_circle
			(center -3.31 -4.2)
			(end -3.261 -4.2)
			(stroke
				(width 0.15)
				(type solid)
			)
			(fill yes)
			(layer "F.SilkS")
		)
		(fp_rect
			(start -3.601 -5)
			(end 3.598 4.998)
			(stroke
				(width 0.05)
				(type solid)
			)
			(fill no)
			(layer "F.CrtYd")
		)
		(fp_line
			(start -2.351 -3.5)
			(end -1.351 -4.5)
			(stroke
				(width 0.15)
				(type solid)
			)
			(layer "F.Fab")
		)
		(fp_line
			(start -2.351 4.498)
			(end -2.351 -3.5)
			(stroke
				(width 0.15)
				(type solid)
			)
			(layer "F.Fab")
		)
		(fp_line
			(start -1.351 -4.5)
			(end 2.35 -4.5)
			(stroke
				(width 0.15)
				(type solid)
			)
			(layer "F.Fab")
		)
		(fp_line
			(start -1 -3.75)
			(end -1 -3.25)
			(stroke
				(width 0.15)
				(type solid)
			)
			(layer "F.Fab")
		)
		(fp_line
			(start -1 -3.65)
			(end -0.335 -3.65)
			(stroke
				(width 0.15)
				(type solid)
			)
			(layer "F.Fab")
		)
		(fp_line
			(start -1 -3.551)
			(end -0.335 -3.551)
			(stroke
				(width 0.15)
				(type solid)
			)
			(layer "F.Fab")
		)
		(fp_line
			(start -1 -3.451)
			(end -0.335 -3.451)
			(stroke
				(width 0.15)
				(type solid)
			)
			(layer "F.Fab")
		)
		(fp_line
			(start -1 -3.351)
			(end -0.335 -3.351)
			(stroke
				(width 0.15)
				(type solid)
			)
			(layer "F.Fab")
		)
		(fp_line
			(start -1 -3.25)
			(end 0.998 -3.25)
			(stroke
				(width 0.15)
				(type solid)
			)
			(layer "F.Fab")
		)
		(fp_line
			(start -1 -2.75)
			(end -1 -2.25)
			(stroke
				(width 0.15)
				(type solid)
			)
			(layer "F.Fab")
		)
		(fp_line
			(start -1 -2.65)
			(end -0.335 -2.65)
			(stroke
				(width 0.15)
				(type solid)
			)
			(layer "F.Fab")
		)
		(fp_line
			(start -1 -2.551)
			(end -0.335 -2.551)
			(stroke
				(width 0.15)
				(type solid)
			)
			(layer "F.Fab")
		)
		(fp_line
			(start -1 -2.452)
			(end -0.335 -2.452)
			(stroke
				(width 0.15)
				(type solid)
			)
			(layer "F.Fab")
		)
		(fp_line
			(start -1 -2.351)
			(end -0.335 -2.351)
			(stroke
				(width 0.15)
				(type solid)
			)
			(layer "F.Fab")
		)
		(fp_line
			(start -1 -2.25)
			(end 0.998 -2.25)
			(stroke
				(width 0.15)
				(type solid)
			)
			(layer "F.Fab")
		)
		(fp_line
			(start -1 -1.75)
			(end -1 -1.25)
			(stroke
				(width 0.15)
				(type solid)
			)
			(layer "F.Fab")
		)
		(fp_line
			(start -1 -1.651)
			(end -0.335 -1.651)
			(stroke
				(width 0.15)
				(type solid)
			)
			(layer "F.Fab")
		)
		(fp_line
			(start -1 -1.551)
			(end -0.335 -1.551)
			(stroke
				(width 0.15)
				(type solid)
			)
			(layer "F.Fab")
		)
		(fp_line
			(start -1 -1.45)
			(end -0.335 -1.45)
			(stroke
				(width 0.15)
				(type solid)
			)
			(layer "F.Fab")
		)
		(fp_line
			(start -1 -1.351)
			(end -0.335 -1.351)
			(stroke
				(width 0.15)
				(type solid)
			)
			(layer "F.Fab")
		)
		(fp_line
			(start -1 -1.25)
			(end 0.998 -1.25)
			(stroke
				(width 0.15)
				(type solid)
			)
			(layer "F.Fab")
		)
		(fp_line
			(start -1 -0.75)
			(end -1 -0.25)
			(stroke
				(width 0.15)
				(type solid)
			)
			(layer "F.Fab")
		)
		(fp_line
			(start -1 -0.652)
			(end -0.335 -0.652)
			(stroke
				(width 0.15)
				(type solid)
			)
			(layer "F.Fab")
		)
		(fp_line
			(start -1 -0.552)
			(end -0.335 -0.552)
			(stroke
				(width 0.15)
				(type solid)
			)
			(layer "F.Fab")
		)
		(fp_line
			(start -1 -0.452)
			(end -0.335 -0.452)
			(stroke
				(width 0.15)
				(type solid)
			)
			(layer "F.Fab")
		)
		(fp_line
			(start -1 -0.351)
			(end -0.335 -0.351)
			(stroke
				(width 0.15)
				(type solid)
			)
			(layer "F.Fab")
		)
		(fp_line
			(start -1 -0.25)
			(end 0.998 -0.25)
			(stroke
				(width 0.15)
				(type solid)
			)
			(layer "F.Fab")
		)
		(fp_line
			(start -1 0.248)
			(end -1 0.748)
			(stroke
				(width 0.15)
				(type solid)
			)
			(layer "F.Fab")
		)
		(fp_line
			(start -1 0.349)
			(end -0.335 0.349)
			(stroke
				(width 0.15)
				(type solid)
			)
			(layer "F.Fab")
		)
		(fp_line
			(start -1 0.45)
			(end -0.335 0.45)
			(stroke
				(width 0.15)
				(type solid)
			)
			(layer "F.Fab")
		)
		(fp_line
			(start -1 0.55)
			(end -0.335 0.55)
			(stroke
				(width 0.15)
				(type solid)
			)
			(layer "F.Fab")
		)
		(fp_line
			(start -1 0.65)
			(end -0.335 0.65)
			(stroke
				(width 0.15)
				(type solid)
			)
			(layer "F.Fab")
		)
		(fp_line
			(start -1 0.748)
			(end -0.335 0.748)
			(stroke
				(width 0.15)
				(type solid)
			)
			(layer "F.Fab")
		)
		(fp_line
			(start -1 0.748)
			(end 0.998 0.748)
			(stroke
				(width 0.15)
				(type solid)
			)
			(layer "F.Fab")
		)
		(fp_line
			(start -1 1.249)
			(end -1 1.749)
			(stroke
				(width 0.15)
				(type solid)
			)
			(layer "F.Fab")
		)
		(fp_line
			(start -1 1.35)
			(end -0.335 1.35)
			(stroke
				(width 0.15)
				(type solid)
			)
			(layer "F.Fab")
		)
		(fp_line
			(start -1 1.449)
			(end -0.335 1.449)
			(stroke
				(width 0.15)
				(type solid)
			)
			(layer "F.Fab")
		)
		(fp_line
			(start -1 1.55)
			(end -0.335 1.55)
			(stroke
				(width 0.15)
				(type solid)
			)
			(layer "F.Fab")
		)
		(fp_line
			(start -1 1.648)
			(end -0.335 1.648)
			(stroke
				(width 0.15)
				(type solid)
			)
			(layer "F.Fab")
		)
		(fp_line
			(start -1 1.749)
			(end -0.335 1.749)
			(stroke
				(width 0.15)
				(type solid)
			)
			(layer "F.Fab")
		)
		(fp_line
			(start -1 1.749)
			(end 0.998 1.749)
			(stroke
				(width 0.15)
				(type solid)
			)
			(layer "F.Fab")
		)
		(fp_line
			(start -1 2.249)
			(end -1 2.749)
			(stroke
				(width 0.15)
				(type solid)
			)
			(layer "F.Fab")
		)
		(fp_line
			(start -1 2.35)
			(end -0.335 2.35)
			(stroke
				(width 0.15)
				(type solid)
			)
			(layer "F.Fab")
		)
		(fp_line
			(start -1 2.45)
			(end -0.335 2.45)
			(stroke
				(width 0.15)
				(type solid)
			)
			(layer "F.Fab")
		)
		(fp_line
			(start -1 2.548)
			(end -0.335 2.548)
			(stroke
				(width 0.15)
				(type solid)
			)
			(layer "F.Fab")
		)
		(fp_line
			(start -1 2.648)
			(end -0.335 2.648)
			(stroke
				(width 0.15)
				(type solid)
			)
			(layer "F.Fab")
		)
		(fp_line
			(start -1 2.749)
			(end -0.335 2.749)
			(stroke
				(width 0.15)
				(type solid)
			)
			(layer "F.Fab")
		)
		(fp_line
			(start -1 2.749)
			(end 0.998 2.749)
			(stroke
				(width 0.15)
				(type solid)
			)
			(layer "F.Fab")
		)
		(fp_line
			(start -1 3.249)
			(end -1 3.749)
			(stroke
				(width 0.15)
				(type solid)
			)
			(layer "F.Fab")
		)
		(fp_line
			(start -1 3.35)
			(end -0.335 3.35)
			(stroke
				(width 0.15)
				(type solid)
			)
			(layer "F.Fab")
		)
		(fp_line
			(start -1 3.45)
			(end -0.335 3.45)
			(stroke
				(width 0.15)
				(type solid)
			)
			(layer "F.Fab")
		)
		(fp_line
			(start -1 3.548)
			(end -0.335 3.548)
			(stroke
				(width 0.15)
				(type solid)
			)
			(layer "F.Fab")
		)
		(fp_line
			(start -1 3.648)
			(end -0.335 3.648)
			(stroke
				(width 0.15)
				(type solid)
			)
			(layer "F.Fab")
		)
		(fp_line
			(start -1 3.749)
			(end -0.335 3.749)
			(stroke
				(width 0.15)
				(type solid)
			)
			(layer "F.Fab")
		)
		(fp_line
			(start -1 3.749)
			(end 0.998 3.749)
			(stroke
				(width 0.15)
				(type solid)
			)
			(layer "F.Fab")
		)
		(fp_line
			(start -0.335 -3.75)
			(end -0.335 -3.25)
			(stroke
				(width 0.15)
				(type solid)
			)
			(layer "F.Fab")
		)
		(fp_line
			(start -0.335 -2.75)
			(end -0.335 -2.25)
			(stroke
				(width 0.15)
				(type solid)
			)
			(layer "F.Fab")
		)
		(fp_line
			(start -0.335 -1.75)
			(end -0.335 -1.25)
			(stroke
				(width 0.15)
				(type solid)
			)
			(layer "F.Fab")
		)
		(fp_line
			(start -0.335 -0.75)
			(end -0.335 -0.25)
			(stroke
				(width 0.15)
				(type solid)
			)
			(layer "F.Fab")
		)
		(fp_line
			(start -0.335 0.248)
			(end -0.335 0.748)
			(stroke
				(width 0.15)
				(type solid)
			)
			(layer "F.Fab")
		)
		(fp_line
			(start -0.335 1.249)
			(end -0.335 1.749)
			(stroke
				(width 0.15)
				(type solid)
			)
			(layer "F.Fab")
		)
		(fp_line
			(start -0.335 2.249)
			(end -0.335 2.749)
			(stroke
				(width 0.15)
				(type solid)
			)
			(layer "F.Fab")
		)
		(fp_line
			(start -0.335 3.249)
			(end -0.335 3.749)
			(stroke
				(width 0.15)
				(type solid)
			)
			(layer "F.Fab")
		)
		(fp_line
			(start 0.998 -3.75)
			(end -1 -3.75)
			(stroke
				(width 0.15)
				(type solid)
			)
			(layer "F.Fab")
		)
		(fp_line
			(start 0.998 -3.25)
			(end 0.998 -3.75)
			(stroke
				(width 0.15)
				(type solid)
			)
			(layer "F.Fab")
		)
		(fp_line
			(start 0.998 -2.75)
			(end -1 -2.75)
			(stroke
				(width 0.15)
				(type solid)
			)
			(layer "F.Fab")
		)
		(fp_line
			(start 0.998 -2.25)
			(end 0.998 -2.75)
			(stroke
				(width 0.15)
				(type solid)
			)
			(layer "F.Fab")
		)
		(fp_line
			(start 0.998 -1.75)
			(end -1 -1.75)
			(stroke
				(width 0.15)
				(type solid)
			)
			(layer "F.Fab")
		)
		(fp_line
			(start 0.998 -1.25)
			(end 0.998 -1.75)
			(stroke
				(width 0.15)
				(type solid)
			)
			(layer "F.Fab")
		)
		(fp_line
			(start 0.998 -0.75)
			(end -1 -0.75)
			(stroke
				(width 0.15)
				(type solid)
			)
			(layer "F.Fab")
		)
		(fp_line
			(start 0.998 -0.25)
			(end 0.998 -0.75)
			(stroke
				(width 0.15)
				(type solid)
			)
			(layer "F.Fab")
		)
		(fp_line
			(start 0.998 0.248)
			(end -1 0.248)
			(stroke
				(width 0.15)
				(type solid)
			)
			(layer "F.Fab")
		)
		(fp_line
			(start 0.998 0.748)
			(end 0.998 0.248)
			(stroke
				(width 0.15)
				(type solid)
			)
			(layer "F.Fab")
		)
		(fp_line
			(start 0.998 1.249)
			(end -1 1.249)
			(stroke
				(width 0.15)
				(type solid)
			)
			(layer "F.Fab")
		)
		(fp_line
			(start 0.998 1.749)
			(end 0.998 1.249)
			(stroke
				(width 0.15)
				(type solid)
			)
			(layer "F.Fab")
		)
		(fp_line
			(start 0.998 2.249)
			(end -1 2.249)
			(stroke
				(width 0.15)
				(type solid)
			)
			(layer "F.Fab")
		)
		(fp_line
			(start 0.998 2.749)
			(end 0.998 2.249)
			(stroke
				(width 0.15)
				(type solid)
			)
			(layer "F.Fab")
		)
		(fp_line
			(start 0.998 3.249)
			(end -1 3.249)
			(stroke
				(width 0.15)
				(type solid)
			)
			(layer "F.Fab")
		)
		(fp_line
			(start 0.998 3.749)
			(end 0.998 3.249)
			(stroke
				(width 0.15)
				(type solid)
			)
			(layer "F.Fab")
		)
		(fp_line
			(start 2.35 -4.5)
			(end 2.35 4.498)
			(stroke
				(width 0.15)
				(type solid)
			)
			(layer "F.Fab")
		)
		(fp_line
			(start 2.35 4.498)
			(end -2.351 4.498)
			(stroke
				(width 0.15)
				(type solid)
			)
			(layer "F.Fab")
		)
		(fp_text user "Author: Antmicro"
			(at -14.59 8.29 0)
			(layer "F.Fab")
			(effects
				(font
					(size 0.7 0.7)
					(thickness 0.15)
				)
				(justify left bottom)
			)
		)
		(fp_text user "License: Apache-2.0"
			(at -14.59 10.69 0)
			(layer "F.Fab")
			(effects
				(font
					(size 0.7 0.7)
					(thickness 0.15)
				)
				(justify left bottom)
			)
		)
		(fp_text user "${REFERENCE}"
			(at -14.59 11.89 0)
			(layer "F.Fab")
			(effects
				(font
					(size 0.7 0.7)
					(thickness 0.15)
				)
				(justify left bottom)
			)
		)
		(fp_text user "on"
			(at -1.56 0.69 90)
			(layer "F.Fab")
			(effects
				(font
					(size 0.7 0.7)
					(thickness 0.15)
				)
				(justify left bottom)
			)
		)
		(pad "1" smd rect
			(at -2.952 -3.5)
			(size 1.2 0.5)
			(layers "F.Cu" "F.Mask" "F.Paste")
			(net 138 "/Supply/PB_CTRL_OUT")
			(pinfunction "1")
			(pintype "passive")
		)
		(pad "2" smd rect
			(at -2.952 -2.5)
			(size 1.2 0.5)
			(layers "F.Cu" "F.Mask" "F.Paste")
			(net 157 "/Supply/~{PB_CTRL_INT}")
			(pinfunction "2")
			(pintype "passive")
		)
		(pad "3" smd rect
			(at -2.952 -1.5)
			(size 1.2 0.5)
			(layers "F.Cu" "F.Mask" "F.Paste")
			(net 404 "IN1")
			(pinfunction "3")
			(pintype "passive")
		)
		(pad "4" smd rect
			(at -2.952 -0.5)
			(size 1.2 0.5)
			(layers "F.Cu" "F.Mask" "F.Paste")
			(net 405 "IN2")
			(pinfunction "4")
			(pintype "passive")
		)
		(pad "5" smd rect
			(at -2.952 0.498)
			(size 1.2 0.5)
			(layers "F.Cu" "F.Mask" "F.Paste")
			(net 773 "MODE2")
			(pinfunction "5")
			(pintype "passive")
		)
		(pad "6" smd rect
			(at -2.952 1.499)
			(size 1.2 0.5)
			(layers "F.Cu" "F.Mask" "F.Paste")
			(net 626 "USER_IN")
			(pinfunction "6")
			(pintype "passive")
		)
		(pad "7" smd rect
			(at -2.952 2.499)
			(size 1.2 0.5)
			(layers "F.Cu" "F.Mask" "F.Paste")
			(net 749 "/I^{2}C + I3C/PWR.SCL")
			(pinfunction "7")
			(pintype "passive")
		)
		(pad "8" smd rect
			(at -2.952 3.499)
			(size 1.2 0.5)
			(layers "F.Cu" "F.Mask" "F.Paste")
			(net 197 "FTDI_DIS")
			(pinfunction "8")
			(pintype "passive")
		)
		(pad "9" smd rect
			(at 2.95 3.499)
			(size 1.2 0.5)
			(layers "F.Cu" "F.Mask" "F.Paste")
			(net 1 "GND")
			(pinfunction "9")
			(pintype "passive")
		)
		(pad "10" smd rect
			(at 2.95 2.499)
			(size 1.2 0.5)
			(layers "F.Cu" "F.Mask" "F.Paste")
			(net 215 "/Supply/QDCDC2_SCL")
			(pinfunction "10")
			(pintype "passive")
		)
		(pad "11" smd rect
			(at 2.95 1.499)
			(size 1.2 0.5)
			(layers "F.Cu" "F.Mask" "F.Paste")
			(net 486 "Net-(R87-Pad1)")
			(pinfunction "11")
			(pintype "passive")
		)
		(pad "12" smd rect
			(at 2.95 0.498)
			(size 1.2 0.5)
			(layers "F.Cu" "F.Mask" "F.Paste")
			(net 1 "GND")
			(pinfunction "12")
			(pintype "passive")
		)
		(pad "13" smd rect
			(at 2.95 -0.5)
			(size 1.2 0.5)
			(layers "F.Cu" "F.Mask" "F.Paste")
			(net 1 "GND")
			(pinfunction "13")
			(pintype "passive")
		)
		(pad "14" smd rect
			(at 2.95 -1.5)
			(size 1.2 0.5)
			(layers "F.Cu" "F.Mask" "F.Paste")
			(net 1 "GND")
			(pinfunction "14")
			(pintype "passive")
		)
		(pad "15" smd rect
			(at 2.95 -2.5)
			(size 1.2 0.5)
			(layers "F.Cu" "F.Mask" "F.Paste")
			(net 137 "/Supply/~{PB_CTRL_CLR}")
			(pinfunction "15")
			(pintype "passive")
		)
		(pad "16" smd rect
			(at 2.95 -3.5)
			(size 1.2 0.5)
			(layers "F.Cu" "F.Mask" "F.Paste")
			(net 50 "/Supply/SEQ_EN")
			(pinfunction "16")
			(pintype "passive")
		)
		(pad "17" smd rect
			(at -2.15 -4.5)
			(size 0.7 0.7)
			(layers "F.Cu" "F.Mask" "F.Paste")
			(net 1 "GND")
			(pinfunction "17")
			(pintype "power_in")
		)
		(pad "17" smd rect
			(at -2.15 4.498)
			(size 0.7 0.7)
			(layers "F.Cu" "F.Mask" "F.Paste")
			(net 1 "GND")
			(pinfunction "17")
			(pintype "power_in")
		)
		(pad "17" smd rect
			(at 2.148 -4.5)
			(size 0.7 0.7)
			(layers "F.Cu" "F.Mask" "F.Paste")
			(net 1 "GND")
			(pinfunction "17")
			(pintype "power_in")
		)
		(pad "17" smd rect
			(at 2.148 4.498)
			(size 0.7 0.7)
			(layers "F.Cu" "F.Mask" "F.Paste")
			(net 1 "GND")
			(pinfunction "17")
			(pintype "power_in")
		)
	)
	(footprint "antmicro-footprints:VQFN-16-1EP_3x3mm_P0.5mm_EP1.1x1.1mm"
		(layer "F.Cu")
		(at 239.274499 155.3085 180)
		(descr "VQFN, 16 Pin (https://ww1.microchip.com/downloads/en/DeviceDoc/16L_VQFN-WFS_3x3mm_4MX_C04-00508a.pdf), generated with kicad-footprint-generator ipc_noLead_generator.py")
		(tags "VQFN NoLead")
		(property "Reference" "U28"
			(at -1.175501 -3.6165 0)
			(layer "F.SilkS")
			(effects
				(font
					(size 0.7 0.7)
					(thickness 0.15)
				)
				(justify right bottom)
			)
		)
		(property "Value" "PAC1944T-E"
			(at 0 2.797 0)
			(layer "F.Fab")
			(effects
				(font
					(size 0.7 0.7)
					(thickness 0.15)
				)
				(justify right bottom)
			)
		)
		(property "Datasheet" "https://ww1.microchip.com/downloads/aemDocuments/documents/MSLD/ProductDocuments/DataSheets/PAC194X-Family-Data-Sheet-DS20006543.pdf"
			(at 0 0 180)
			(layer "F.Fab")
			(hide yes)
			(effects
				(font
					(size 1.27 1.27)
					(thickness 0.15)
				)
			)
		)
		(property "MPN" "PAC1944T-E/4MX"
			(at 0 0 180)
			(unlocked yes)
			(layer "F.Fab")
			(hide yes)
			(effects
				(font
					(size 1 1)
					(thickness 0.15)
				)
			)
		)
		(property "Manufacturer" "Microchip Technology"
			(at 0 0 180)
			(unlocked yes)
			(layer "F.Fab")
			(hide yes)
			(effects
				(font
					(size 1 1)
					(thickness 0.15)
				)
			)
		)
		(property "Author" "Antmicro"
			(at 0 0 180)
			(unlocked yes)
			(layer "F.Fab")
			(hide yes)
			(effects
				(font
					(size 1 1)
					(thickness 0.15)
				)
			)
		)
		(property "License" "Apache-2.0"
			(at 0 0 180)
			(unlocked yes)
			(layer "F.Fab")
			(hide yes)
			(effects
				(font
					(size 1 1)
					(thickness 0.15)
				)
			)
		)
		(property ki_fp_filters "UQFN*1EP*4x4mm*P0.65mm*")
		(sheetname "/Supply/DC-DC IO/")
		(sheetfile "dc-dc-io.kicad_sch")
		(attr smd)
		(fp_line
			(start 1.61 1.61)
			(end 1.61 1.134)
			(stroke
				(width 0.15)
				(type solid)
			)
			(layer "F.SilkS")
		)
		(fp_line
			(start 1.61 -1.611)
			(end 1.61 -1.135)
			(stroke
				(width 0.15)
				(type solid)
			)
			(layer "F.SilkS")
		)
		(fp_line
			(start 1.134 1.61)
			(end 1.61 1.61)
			(stroke
				(width 0.15)
				(type solid)
			)
			(layer "F.SilkS")
		)
		(fp_line
			(start 1.134 -1.611)
			(end 1.61 -1.611)
			(stroke
				(width 0.15)
				(type solid)
			)
			(layer "F.SilkS")
		)
		(fp_line
			(start -1.135 1.61)
			(end -1.611 1.61)
			(stroke
				(width 0.15)
				(type solid)
			)
			(layer "F.SilkS")
		)
		(fp_line
			(start -1.135 -1.611)
			(end -1.611 -1.611)
			(stroke
				(width 0.15)
				(type solid)
			)
			(layer "F.SilkS")
		)
		(fp_line
			(start -1.611 1.61)
			(end -1.611 1.134)
			(stroke
				(width 0.15)
				(type solid)
			)
			(layer "F.SilkS")
		)
		(fp_circle
			(center -2.3 -0.75)
			(end -2.25 -0.75)
			(stroke
				(width 0.15)
				(type solid)
			)
			(fill yes)
			(layer "F.SilkS")
		)
		(fp_rect
			(start -2 -2)
			(end 1.999 1.999)
			(stroke
				(width 0.05)
				(type solid)
			)
			(fill no)
			(layer "F.CrtYd")
		)
		(fp_line
			(start 1.499 1.499)
			(end -1.5 1.499)
			(stroke
				(width 0.15)
				(type solid)
			)
			(layer "F.Fab")
		)
		(fp_line
			(start 1.499 -1.5)
			(end 1.499 1.499)
			(stroke
				(width 0.15)
				(type solid)
			)
			(layer "F.Fab")
		)
		(fp_line
			(start -0.75 -1.5)
			(end 1.499 -1.5)
			(stroke
				(width 0.15)
				(type solid)
			)
			(layer "F.Fab")
		)
		(fp_line
			(start -1.5 1.499)
			(end -1.5 -0.75)
			(stroke
				(width 0.15)
				(type solid)
			)
			(layer "F.Fab")
		)
		(fp_line
			(start -1.5 -0.75)
			(end -0.75 -1.5)
			(stroke
				(width 0.15)
				(type solid)
			)
			(layer "F.Fab")
		)
		(fp_circle
			(center -2.3 -0.75)
			(end -2.25 -0.75)
			(stroke
				(width 0.15)
				(type solid)
			)
			(fill yes)
			(layer "F.Fab")
		)
		(fp_text user "License: Apache-2.0"
			(at -2.35 7.197 180)
			(layer "F.Fab")
			(effects
				(font
					(size 0.7 0.7)
					(thickness 0.15)
				)
				(justify left bottom)
			)
		)
		(fp_text user "${REFERENCE}"
			(at -2.35 4.797 180)
			(layer "F.Fab")
			(effects
				(font
					(size 0.7 0.7)
					(thickness 0.15)
				)
				(justify left bottom)
			)
		)
		(fp_text user "Author: Antmicro"
			(at -2.35 5.997 180)
			(layer "F.Fab")
			(effects
				(font
					(size 0.7 0.7)
					(thickness 0.15)
				)
				(justify left bottom)
			)
		)
		(pad "" smd roundrect
			(at 0 0 180)
			(size 0.89 0.89)
			(layers "F.Paste")
			(roundrect_rratio 0.25)
		)
		(pad "1" smd roundrect
			(at -1.464 -0.75 180)
			(size 0.775 0.25)
			(layers "F.Cu" "F.Mask" "F.Paste")
			(roundrect_rratio 0.25)
			(net 744 "unconnected-(U28-SLOW{slash}~{ALERT1}-Pad1)")
			(pinfunction "SLOW/~{ALERT1}")
			(pintype "bidirectional+no_connect")
		)
		(pad "2" smd roundrect
			(at -1.464 -0.25 180)
			(size 0.775 0.25)
			(layers "F.Cu" "F.Mask" "F.Paste")
			(roundrect_rratio 0.25)
			(net 38 "+3V3_AON")
			(pinfunction "VDD")
			(pintype "power_in")
		)
		(pad "3" smd roundrect
			(at -1.464 0.247 180)
			(size 0.775 0.25)
			(layers "F.Cu" "F.Mask" "F.Paste")
			(roundrect_rratio 0.25)
			(net 1 "GND")
			(pinfunction "GND")
			(pintype "power_in")
		)
		(pad "4" smd roundrect
			(at -1.464 0.747 180)
			(size 0.775 0.25)
			(layers "F.Cu" "F.Mask" "F.Paste")
			(roundrect_rratio 0.25)
			(net 749 "/I^{2}C + I3C/PWR.SCL")
			(pinfunction "SCL")
			(pintype "input")
		)
		(pad "5" smd roundrect
			(at -0.75 1.461 180)
			(size 0.25 0.775)
			(layers "F.Cu" "F.Mask" "F.Paste")
			(roundrect_rratio 0.25)
			(net 533 "/I^{2}C + I3C/PWR.SDA")
			(pinfunction "SDA")
			(pintype "bidirectional")
		)
		(pad "6" smd roundrect
			(at -0.25 1.461 180)
			(size 0.25 0.775)
			(layers "F.Cu" "F.Mask" "F.Paste")
			(roundrect_rratio 0.25)
			(net 1 "GND")
			(pinfunction "ADDRSEL")
			(pintype "bidirectional")
		)
		(pad "7" smd roundrect
			(at 0.247 1.461 180)
			(size 0.25 0.775)
			(layers "F.Cu" "F.Mask" "F.Paste")
			(roundrect_rratio 0.25)
			(net 819 "/Supply/DC-DC IO/VDDQ_SEN_-")
			(pinfunction "IN3-")
			(pintype "input")
		)
		(pad "8" smd roundrect
			(at 0.747 1.461 180)
			(size 0.25 0.775)
			(layers "F.Cu" "F.Mask" "F.Paste")
			(roundrect_rratio 0.25)
			(net 733 "Net-(U28-IN3+)")
			(pinfunction "IN3+")
			(pintype "input")
		)
		(pad "9" smd roundrect
			(at 1.461 0.747 180)
			(size 0.775 0.25)
			(layers "F.Cu" "F.Mask" "F.Paste")
			(roundrect_rratio 0.25)
			(net 696 "/Supply/DC-DC IO/1V2_SEN_-")
			(pinfunction "IN4-")
			(pintype "input")
		)
		(pad "10" smd roundrect
			(at 1.461 0.247 180)
			(size 0.775 0.25)
			(layers "F.Cu" "F.Mask" "F.Paste")
			(roundrect_rratio 0.25)
			(net 734 "Net-(U28-IN4+)")
			(pinfunction "IN4+")
			(pintype "input")
		)
		(pad "11" smd roundrect
			(at 1.461 -0.25 180)
			(size 0.775 0.25)
			(layers "F.Cu" "F.Mask" "F.Paste")
			(roundrect_rratio 0.25)
			(net 730 "Net-(U28-IN1+)")
			(pinfunction "IN1+")
			(pintype "input")
		)
		(pad "12" smd roundrect
			(at 1.461 -0.75 180)
			(size 0.775 0.25)
			(layers "F.Cu" "F.Mask" "F.Paste")
			(roundrect_rratio 0.25)
			(net 693 "/Supply/DC-DC IO/3V3_SEN_-")
			(pinfunction "IN1-")
			(pintype "input")
		)
		(pad "13" smd roundrect
			(at 0.747 -1.464 180)
			(size 0.25 0.775)
			(layers "F.Cu" "F.Mask" "F.Paste")
			(roundrect_rratio 0.25)
			(net 732 "Net-(U28-IN2+)")
			(pinfunction "IN2+")
			(pintype "input")
		)
		(pad "14" smd roundrect
			(at 0.247 -1.464 180)
			(size 0.25 0.775)
			(layers "F.Cu" "F.Mask" "F.Paste")
			(roundrect_rratio 0.25)
			(net 694 "/Supply/DC-DC IO/5V_SEN_-")
			(pinfunction "IN2-")
			(pintype "input")
		)
		(pad "15" smd roundrect
			(at -0.25 -1.464 180)
			(size 0.25 0.775)
			(layers "F.Cu" "F.Mask" "F.Paste")
			(roundrect_rratio 0.25)
			(net 745 "unconnected-(U28-GPIO{slash}~{ALERT2}-Pad15)")
			(pinfunction "GPIO/~{ALERT2}")
			(pintype "bidirectional+no_connect")
		)
		(pad "16" smd roundrect
			(at -0.75 -1.464 180)
			(size 0.25 0.775)
			(layers "F.Cu" "F.Mask" "F.Paste")
			(roundrect_rratio 0.25)
			(net 720 "Net-(U28-~{PWRDN})")
			(pinfunction "~{PWRDN}")
			(pintype "input")
		)
		(pad "17" smd rect
			(at 0 0 180)
			(size 1.1 1.1)
			(layers "F.Cu" "F.Mask")
			(net 1 "GND")
			(pinfunction "EP")
			(pintype "passive")
		)
	)
	(footprint "antmicro-footprints:R_0402_1005Metric"
		(layer "F.Cu")
		(at 243.051 117.5)
		(descr "Resistor SMD 0402")
		(tags "resistor SMD 0402")
		(property "Reference" "R242"
			(at -3.95 0.1 0)
			(layer "F.SilkS")
			(effects
				(font
					(size 0.7 0.7)
					(thickness 0.15)
				)
				(justify left bottom)
			)
		)
		(property "Value" "R_4k7_0402"
			(at -1.011843 1.772047 0)
			(layer "F.Fab")
			(effects
				(font
					(size 0.7 0.7)
					(thickness 0.15)
				)
				(justify left bottom)
			)
		)
		(property "Datasheet" "https://www.bourns.com/docs/product-datasheets/cr.pdf"
			(at 0 0 0)
			(layer "B.Fab")
			(hide yes)
			(effects
				(font
					(size 1.27 1.27)
					(thickness 0.15)
				)
				(justify mirror)
			)
		)
		(property "MPN" "CR0402-FX-4701GLF"
			(at 0 0 0)
			(unlocked yes)
			(layer "F.Fab")
			(hide yes)
			(effects
				(font
					(size 1 1)
					(thickness 0.15)
				)
			)
		)
		(property "Manufacturer" "Bourns"
			(at 0 0 0)
			(unlocked yes)
			(layer "F.Fab")
			(hide yes)
			(effects
				(font
					(size 1 1)
					(thickness 0.15)
				)
			)
		)
		(property "License" "Apache-2.0"
			(at 0 0 0)
			(unlocked yes)
			(layer "F.Fab")
			(hide yes)
			(effects
				(font
					(size 1 1)
					(thickness 0.15)
				)
			)
		)
		(property "Author" "Antmicro"
			(at 0 0 0)
			(unlocked yes)
			(layer "F.Fab")
			(hide yes)
			(effects
				(font
					(size 1 1)
					(thickness 0.15)
				)
			)
		)
		(property "Val" "4k7"
			(at 0 0 0)
			(unlocked yes)
			(layer "F.Fab")
			(hide yes)
			(effects
				(font
					(size 1 1)
					(thickness 0.15)
				)
			)
		)
		(property "Tolerance" "1%"
			(at 0 0 0)
			(unlocked yes)
			(layer "F.Fab")
			(hide yes)
			(effects
				(font
					(size 1 1)
					(thickness 0.15)
				)
			)
		)
		(sheetname "/DDR5 RDIMM/")
		(sheetfile "ddr5-rdimm.kicad_sch")
		(attr smd)
		(fp_rect
			(start -0.925 -0.47)
			(end 0.925 0.47)
			(stroke
				(width 0.05)
				(type default)
			)
			(fill no)
			(layer "F.CrtYd")
		)
		(fp_rect
			(start -0.5 -0.25)
			(end 0.5 0.25)
			(stroke
				(width 0.15)
				(type solid)
			)
			(fill no)
			(layer "F.Fab")
		)
		(fp_text user "Author: Antmicro"
			(at -0.95 4.169 0)
			(layer "F.Fab")
			(effects
				(font
					(size 0.7 0.7)
					(thickness 0.15)
				)
				(justify left bottom)
			)
		)
		(fp_text user "License: Apache-2.0"
			(at -0.95 5.169 0)
			(layer "F.Fab")
			(effects
				(font
					(size 0.7 0.7)
					(thickness 0.15)
				)
				(justify left bottom)
			)
		)
		(fp_text user "${REFERENCE}"
			(at -0.95 3.168 0)
			(layer "F.Fab")
			(effects
				(font
					(size 0.7 0.7)
					(thickness 0.15)
				)
				(justify left bottom)
			)
		)
		(pad "1" smd roundrect
			(at -0.48 0)
			(size 0.59 0.64)
			(layers "F.Cu" "F.Mask" "F.Paste")
			(roundrect_rratio 0.25)
			(net 1 "GND")
			(pintype "passive")
		)
		(pad "2" smd roundrect
			(at 0.48 0)
			(size 0.59 0.64)
			(layers "F.Cu" "F.Mask" "F.Paste")
			(roundrect_rratio 0.25)
			(net 804 "Net-(D21-C)")
			(pintype "passive")
		)
	)
	(footprint "antmicro-footprints:WSON-8_6x8x0.5mm_P1.27mm"
		(layer "F.Cu")
		(at 213.8995 152.4995 180)
		(property "Reference" "U27"
			(at -6.9005 -3.0505 0)
			(layer "F.SilkS")
			(effects
				(font
					(size 0.7 0.7)
					(thickness 0.15)
				)
				(justify right bottom)
			)
		)
		(property "Value" "W25Q128JWEIQ"
			(at 0 4.3 0)
			(layer "F.Fab")
			(effects
				(font
					(size 0.7 0.7)
					(thickness 0.15)
				)
				(justify right bottom)
			)
		)
		(property "Datasheet" "https://www.winbond.com/resource-files/W25Q128JW_RevG_07292021%20Plus.pdf"
			(at 0 0 180)
			(layer "F.Fab")
			(hide yes)
			(effects
				(font
					(size 1.27 1.27)
					(thickness 0.15)
				)
			)
		)
		(property "Manufacturer" "Winbond"
			(at 0 0 180)
			(unlocked yes)
			(layer "F.Fab")
			(hide yes)
			(effects
				(font
					(size 1 1)
					(thickness 0.15)
				)
			)
		)
		(property "MPN" "W25Q128JWEIQ TR"
			(at 0 0 180)
			(unlocked yes)
			(layer "F.Fab")
			(hide yes)
			(effects
				(font
					(size 1 1)
					(thickness 0.15)
				)
			)
		)
		(property "Author" "Antmicro"
			(at 0 0 180)
			(unlocked yes)
			(layer "F.Fab")
			(hide yes)
			(effects
				(font
					(size 1 1)
					(thickness 0.15)
				)
			)
		)
		(property "License" "Apache-2.0"
			(at 0 0 180)
			(unlocked yes)
			(layer "F.Fab")
			(hide yes)
			(effects
				(font
					(size 1 1)
					(thickness 0.15)
				)
			)
		)
		(sheetname "/HyperRAM + QSPI Flash/")
		(sheetfile "hyperram-flash.kicad_sch")
		(attr smd)
		(fp_line
			(start 4.0005 3)
			(end -3.9995 3)
			(stroke
				(width 0.15)
				(type solid)
			)
			(layer "F.SilkS")
		)
		(fp_line
			(start 4 -3)
			(end -3.975 -3)
			(stroke
				(width 0.15)
				(type solid)
			)
			(layer "F.SilkS")
		)
		(fp_circle
			(center -4.2 -2.4)
			(end -4.149 -2.4)
			(stroke
				(width 0.15)
				(type solid)
			)
			(fill yes)
			(layer "F.SilkS")
		)
		(fp_rect
			(start -4.7 -3.25)
			(end 4.7 3.25)
			(stroke
				(width 0.05)
				(type solid)
			)
			(fill no)
			(layer "F.CrtYd")
		)
		(fp_line
			(start 3.9995 3.0005)
			(end -3.9995 3.0005)
			(stroke
				(width 0.15)
				(type solid)
			)
			(layer "F.Fab")
		)
		(fp_line
			(start 3.9995 -2.9995)
			(end 3.9995 3.0005)
			(stroke
				(width 0.15)
				(type solid)
			)
			(layer "F.Fab")
		)
		(fp_line
			(start -3.0015 -2.9995)
			(end 3.9995 -2.9995)
			(stroke
				(width 0.15)
				(type solid)
			)
			(layer "F.Fab")
		)
		(fp_line
			(start -3.0015 -2.9995)
			(end -3.9995 -1.9995)
			(stroke
				(width 0.15)
				(type solid)
			)
			(layer "F.Fab")
		)
		(fp_line
			(start -3.9995 3.0005)
			(end -3.9995 -1.9995)
			(stroke
				(width 0.15)
				(type solid)
			)
			(layer "F.Fab")
		)
		(fp_text user "${REFERENCE}"
			(at 0 10.903 180)
			(layer "F.Fab")
			(effects
				(font
					(size 0.7 0.7)
					(thickness 0.15)
				)
				(justify left bottom)
			)
		)
		(fp_text user "License: Apache-2.0"
			(at 0 13.303 180)
			(layer "F.Fab")
			(effects
				(font
					(size 0.7 0.7)
					(thickness 0.15)
				)
				(justify left bottom)
			)
		)
		(fp_text user "Author: Antmicro"
			(at 0 12.104 180)
			(layer "F.Fab")
			(effects
				(font
					(size 0.7 0.7)
					(thickness 0.15)
				)
				(justify left bottom)
			)
		)
		(pad "1" smd roundrect
			(at -3.9995 -1.9045 90)
			(size 0.4 1.3)
			(layers "F.Cu" "F.Mask" "F.Paste")
			(roundrect_rratio 0.25)
			(net 350 "/FPGA Config/FLASH.~{CS}")
			(pinfunction "~{CS}")
			(pintype "input")
		)
		(pad "2" smd roundrect
			(at -3.9995 -0.6355 90)
			(size 0.4 1.3)
			(layers "F.Cu" "F.Mask" "F.Paste")
			(roundrect_rratio 0.25)
			(net 282 "/HyperRAM + QSPI Flash/IO1")
			(pinfunction "DO/IO1")
			(pintype "bidirectional")
		)
		(pad "3" smd roundrect
			(at -3.9995 0.6345 90)
			(size 0.4 1.3)
			(layers "F.Cu" "F.Mask" "F.Paste")
			(roundrect_rratio 0.25)
			(net 280 "/HyperRAM + QSPI Flash/IO2")
			(pinfunction "~{WP}/IO2")
			(pintype "bidirectional")
		)
		(pad "4" smd roundrect
			(at -3.9995 1.9045 90)
			(size 0.4 1.3)
			(layers "F.Cu" "F.Mask" "F.Paste")
			(roundrect_rratio 0.25)
			(net 1 "GND")
			(pinfunction "V_{SS}")
			(pintype "power_in")
		)
		(pad "5" smd roundrect
			(at 3.9995 1.8755 90)
			(size 0.4 1.3)
			(layers "F.Cu" "F.Mask" "F.Paste")
			(roundrect_rratio 0.25)
			(net 281 "/HyperRAM + QSPI Flash/IO0")
			(pinfunction "DI/IO0")
			(pintype "bidirectional")
		)
		(pad "6" smd roundrect
			(at 3.9995 0.6035 90)
			(size 0.4 1.3)
			(layers "F.Cu" "F.Mask" "F.Paste")
			(roundrect_rratio 0.25)
			(net 355 "/FPGA Config/FLASH.SCK")
			(pinfunction "SCK")
			(pintype "input")
		)
		(pad "7" smd roundrect
			(at 3.9995 -0.6655 90)
			(size 0.4 1.3)
			(layers "F.Cu" "F.Mask" "F.Paste")
			(roundrect_rratio 0.25)
			(net 279 "/HyperRAM + QSPI Flash/IO3")
			(pinfunction "~{HOLD}/IO3")
			(pintype "bidirectional")
		)
		(pad "8" smd roundrect
			(at 3.9995 -1.9355 90)
			(size 0.4 1.3)
			(layers "F.Cu" "F.Mask" "F.Paste")
			(roundrect_rratio 0.25)
			(net 797 "+1V8")
			(pinfunction "V_{CC}")
			(pintype "power_in")
		)
		(pad "9" smd roundrect
			(at -0.0005 -0.0005 180)
			(size 4.8 4.65)
			(layers "F.Cu" "F.Mask" "F.Paste")
			(roundrect_rratio 0.05)
			(chamfer_ratio 0.1)
			(chamfer top_left)
			(net 642 "unconnected-(U27-EP-Pad9)")
			(pinfunction "EP")
			(pintype "no_connect")
		)
	)
	(footprint "antmicro-footprints:SOT-143-4"
		(layer "F.Cu")
		(at 254.173999 136.2625 -90)
		(descr "http://datasheets.maximintegrated.com/en/ds/MAX6816-MAX6818.pdf")
		(property "Reference" "U26"
			(at -1.0725 -2.866001 90)
			(layer "F.SilkS")
			(effects
				(font
					(size 0.7 0.7)
					(thickness 0.15)
				)
				(justify right bottom)
			)
		)
		(property "Value" "MAX812REUS+T"
			(at 0 2.999 90)
			(layer "F.Fab")
			(effects
				(font
					(size 0.7 0.7)
					(thickness 0.15)
				)
				(justify right bottom)
			)
		)
		(property "Datasheet" "https://datasheets.maximintegrated.com/en/ds/MAX811-MAX812T.pdf"
			(at 0 0 270)
			(layer "F.Fab")
			(hide yes)
			(effects
				(font
					(size 1.27 1.27)
					(thickness 0.15)
				)
			)
		)
		(property "Manufacturer" "Maxim Integrated Products"
			(at 0 0 270)
			(unlocked yes)
			(layer "F.Fab")
			(hide yes)
			(effects
				(font
					(size 1 1)
					(thickness 0.15)
				)
			)
		)
		(property "MPN" "MAX812REUS+T"
			(at 0 0 270)
			(unlocked yes)
			(layer "F.Fab")
			(hide yes)
			(effects
				(font
					(size 1 1)
					(thickness 0.15)
				)
			)
		)
		(property "License" "Apache-2.0"
			(at 0 0 270)
			(unlocked yes)
			(layer "F.Fab")
			(hide yes)
			(effects
				(font
					(size 1 1)
					(thickness 0.15)
				)
			)
		)
		(property "Author" "Antmicro"
			(at 0 0 270)
			(unlocked yes)
			(layer "F.Fab")
			(hide yes)
			(effects
				(font
					(size 1 1)
					(thickness 0.15)
				)
			)
		)
		(sheetname "/Supply/")
		(sheetfile "supply.kicad_sch")
		(attr smd)
		(fp_circle
			(center -2.1 1.7)
			(end -2.05 1.7)
			(stroke
				(width 0.15)
				(type solid)
			)
			(fill yes)
			(layer "F.SilkS")
		)
		(fp_rect
			(start -1.776 -1.896)
			(end 1.773 1.895)
			(stroke
				(width 0.05)
				(type solid)
			)
			(fill no)
			(layer "F.CrtYd")
		)
		(fp_line
			(start -1.46 0.65)
			(end 1.459 0.65)
			(stroke
				(width 0.15)
				(type solid)
			)
			(layer "F.Fab")
		)
		(fp_line
			(start -1.46 0.65)
			(end -1.46 -0.652)
			(stroke
				(width 0.15)
				(type solid)
			)
			(layer "F.Fab")
		)
		(fp_line
			(start 1.459 -0.652)
			(end 1.459 0.65)
			(stroke
				(width 0.15)
				(type solid)
			)
			(layer "F.Fab")
		)
		(fp_line
			(start 1.459 -0.652)
			(end -1.46 -0.652)
			(stroke
				(width 0.15)
				(type solid)
			)
			(layer "F.Fab")
		)
		(fp_text user "License: Apache-2.0"
			(at -1.601 7.4 270)
			(layer "F.Fab")
			(effects
				(font
					(size 0.7 0.7)
					(thickness 0.15)
				)
				(justify left bottom)
			)
		)
		(fp_text user "${REFERENCE}"
			(at -1.601 4.998 270)
			(layer "F.Fab")
			(effects
				(font
					(size 0.7 0.7)
					(thickness 0.15)
				)
				(justify left bottom)
			)
		)
		(fp_text user "Author: Antmicro"
			(at -1.601 6.2 270)
			(layer "F.Fab")
			(effects
				(font
					(size 0.7 0.7)
					(thickness 0.15)
				)
				(justify left bottom)
			)
		)
		(pad "1" smd roundrect
			(at -0.76 0.998 270)
			(size 0.94 1.31)
			(layers "F.Cu" "F.Mask" "F.Paste")
			(roundrect_rratio 0.25)
			(net 1 "GND")
			(pinfunction "GND")
			(pintype "power_in")
		)
		(pad "2" smd roundrect
			(at 0.959 0.998 270)
			(size 0.55 1.31)
			(layers "F.Cu" "F.Mask" "F.Paste")
			(roundrect_rratio 0.25)
			(net 287 "Net-(Q17-G)")
			(pinfunction "~{RST}")
			(pintype "output")
		)
		(pad "3" smd roundrect
			(at 0.959 -1 270)
			(size 0.55 1.31)
			(layers "F.Cu" "F.Mask" "F.Paste")
			(roundrect_rratio 0.25)
			(net 286 "Net-(Q16-D)")
			(pinfunction "~{MR}")
			(pintype "input")
		)
		(pad "4" smd roundrect
			(at -0.96 -1 270)
			(size 0.55 1.31)
			(layers "F.Cu" "F.Mask" "F.Paste")
			(roundrect_rratio 0.25)
			(net 38 "+3V3_AON")
			(pinfunction "VCC")
			(pintype "power_in")
		)
	)
	(footprint "antmicro-footprints:R_0402_1005Metric"
		(layer "F.Cu")
		(at 125.681 168.3125 90)
		(descr "Resistor SMD 0402")
		(tags "resistor SMD 0402")
		(property "Reference" "R217"
			(at -3.825 0.619 90)
			(layer "F.SilkS")
			(effects
				(font
					(size 0.7 0.7)
					(thickness 0.15)
				)
				(justify left bottom)
			)
		)
		(property "Value" "R_64k9_0402"
			(at -1.011843 1.772047 90)
			(layer "F.Fab")
			(effects
				(font
					(size 0.7 0.7)
					(thickness 0.15)
				)
				(justify left bottom)
			)
		)
		(property "Datasheet" "https://www.bourns.com/docs/product-datasheets/cr.pdf"
			(at 0 0 90)
			(layer "F.Fab")
			(hide yes)
			(effects
				(font
					(size 1.27 1.27)
					(thickness 0.15)
				)
			)
		)
		(property "MPN" "CR0402-FX-6492GLF"
			(at 0 0 90)
			(unlocked yes)
			(layer "F.Fab")
			(hide yes)
			(effects
				(font
					(size 1 1)
					(thickness 0.15)
				)
			)
		)
		(property "Manufacturer" "Bourns"
			(at 0 0 90)
			(unlocked yes)
			(layer "F.Fab")
			(hide yes)
			(effects
				(font
					(size 1 1)
					(thickness 0.15)
				)
			)
		)
		(property "License" "Apache-2.0"
			(at 0 0 90)
			(unlocked yes)
			(layer "F.Fab")
			(hide yes)
			(effects
				(font
					(size 1 1)
					(thickness 0.15)
				)
			)
		)
		(property "Author" "Antmicro"
			(at 0 0 90)
			(unlocked yes)
			(layer "F.Fab")
			(hide yes)
			(effects
				(font
					(size 1 1)
					(thickness 0.15)
				)
			)
		)
		(property "Val" "64k9"
			(at 0 0 90)
			(unlocked yes)
			(layer "F.Fab")
			(hide yes)
			(effects
				(font
					(size 1 1)
					(thickness 0.15)
				)
			)
		)
		(property "Tolerance" "1%"
			(at 0 0 90)
			(unlocked yes)
			(layer "F.Fab")
			(hide yes)
			(effects
				(font
					(size 1 1)
					(thickness 0.15)
				)
			)
		)
		(sheetname "/HDMI + SD Card/")
		(sheetfile "hdmi-sd-card.kicad_sch")
		(attr smd exclude_from_bom dnp)
		(fp_rect
			(start -0.925 -0.47)
			(end 0.925 0.47)
			(stroke
				(width 0.05)
				(type default)
			)
			(fill no)
			(layer "F.CrtYd")
		)
		(fp_rect
			(start -0.5 -0.25)
			(end 0.5 0.25)
			(stroke
				(width 0.15)
				(type solid)
			)
			(fill no)
			(layer "F.Fab")
		)
		(fp_text user "Author: Antmicro"
			(at -0.95 4.169 90)
			(layer "F.Fab")
			(effects
				(font
					(size 0.7 0.7)
					(thickness 0.15)
				)
				(justify left bottom)
			)
		)
		(fp_text user "${REFERENCE}"
			(at -0.95 3.168 90)
			(layer "F.Fab")
			(effects
				(font
					(size 0.7 0.7)
					(thickness 0.15)
				)
				(justify left bottom)
			)
		)
		(fp_text user "License: Apache-2.0"
			(at -0.95 5.169 90)
			(layer "F.Fab")
			(effects
				(font
					(size 0.7 0.7)
					(thickness 0.15)
				)
				(justify left bottom)
			)
		)
		(pad "1" smd roundrect
			(at -0.48 0 90)
			(size 0.59 0.64)
			(layers "F.Cu" "F.Mask" "F.Paste")
			(roundrect_rratio 0.25)
			(net 1 "GND")
			(pintype "passive")
		)
		(pad "2" smd roundrect
			(at 0.48 0 90)
			(size 0.59 0.64)
			(layers "F.Cu" "F.Mask" "F.Paste")
			(roundrect_rratio 0.25)
			(net 736 "/HDMI + SD Card/PRE_SEL")
			(pintype "passive")
		)
	)
	(footprint "antmicro-footprints:R_0402_1005Metric"
		(layer "F.Cu")
		(at 121.05 112.736461 -90)
		(descr "Resistor SMD 0402")
		(tags "resistor SMD 0402")
		(property "Reference" "R11"
			(at -1.161461 -1.475 90)
			(layer "F.SilkS")
			(effects
				(font
					(size 0.7 0.7)
					(thickness 0.15)
				)
				(justify right bottom)
			)
		)
		(property "Value" "R_330R_0402"
			(at -1.011843 1.772047 90)
			(layer "F.Fab")
			(effects
				(font
					(size 0.7 0.7)
					(thickness 0.15)
				)
				(justify right bottom)
			)
		)
		(property "Datasheet" "https://www.bourns.com/docs/product-datasheets/cr.pdf"
			(at 0 0 270)
			(layer "F.Fab")
			(hide yes)
			(effects
				(font
					(size 1.27 1.27)
					(thickness 0.15)
				)
			)
		)
		(property "Manufacturer" "Bourns"
			(at 0 0 270)
			(unlocked yes)
			(layer "F.Fab")
			(hide yes)
			(effects
				(font
					(size 1 1)
					(thickness 0.15)
				)
			)
		)
		(property "MPN" "CR0402-FX-3300GLF"
			(at 0 0 270)
			(unlocked yes)
			(layer "F.Fab")
			(hide yes)
			(effects
				(font
					(size 1 1)
					(thickness 0.15)
				)
			)
		)
		(property "Val" "330R"
			(at 0 0 270)
			(unlocked yes)
			(layer "F.Fab")
			(hide yes)
			(effects
				(font
					(size 1 1)
					(thickness 0.15)
				)
			)
		)
		(property "License" "Apache-2.0"
			(at 0 0 270)
			(unlocked yes)
			(layer "F.Fab")
			(hide yes)
			(effects
				(font
					(size 1 1)
					(thickness 0.15)
				)
			)
		)
		(property "Author" "Antmicro"
			(at 0 0 270)
			(unlocked yes)
			(layer "F.Fab")
			(hide yes)
			(effects
				(font
					(size 1 1)
					(thickness 0.15)
				)
			)
		)
		(property "Tolerance" "1%"
			(at 0 0 270)
			(unlocked yes)
			(layer "F.Fab")
			(hide yes)
			(effects
				(font
					(size 1 1)
					(thickness 0.15)
				)
			)
		)
		(sheetname "/FPGA Config/")
		(sheetfile "fpga-config.kicad_sch")
		(attr smd)
		(fp_rect
			(start -0.925 -0.47)
			(end 0.925 0.47)
			(stroke
				(width 0.05)
				(type default)
			)
			(fill no)
			(layer "F.CrtYd")
		)
		(fp_rect
			(start -0.5 -0.25)
			(end 0.5 0.25)
			(stroke
				(width 0.15)
				(type solid)
			)
			(fill no)
			(layer "F.Fab")
		)
		(fp_text user "Author: Antmicro"
			(at -0.95 4.169 270)
			(layer "F.Fab")
			(effects
				(font
					(size 0.7 0.7)
					(thickness 0.15)
				)
				(justify left bottom)
			)
		)
		(fp_text user "${REFERENCE}"
			(at -0.95 3.168 270)
			(layer "F.Fab")
			(effects
				(font
					(size 0.7 0.7)
					(thickness 0.15)
				)
				(justify left bottom)
			)
		)
		(fp_text user "License: Apache-2.0"
			(at -0.95 5.169 270)
			(layer "F.Fab")
			(effects
				(font
					(size 0.7 0.7)
					(thickness 0.15)
				)
				(justify left bottom)
			)
		)
		(pad "1" smd roundrect
			(at -0.48 0 270)
			(size 0.59 0.64)
			(layers "F.Cu" "F.Mask" "F.Paste")
			(roundrect_rratio 0.25)
			(net 783 "Net-(D1-C)")
			(pintype "passive")
		)
		(pad "2" smd roundrect
			(at 0.48 0 270)
			(size 0.59 0.64)
			(layers "F.Cu" "F.Mask" "F.Paste")
			(roundrect_rratio 0.25)
			(net 266 "Net-(Q1-D)")
			(pintype "passive")
		)
	)
	(footprint "antmicro-footprints:C_0603_1608Metric"
		(layer "F.Cu")
		(at 152.91 188.535 180)
		(descr "Capacitor SMD 0603")
		(tags "capacitor 0603")
		(property "Reference" "C180"
			(at -4.04 -0.365 0)
			(layer "F.SilkS")
			(effects
				(font
					(size 0.7 0.7)
					(thickness 0.15)
				)
				(justify right bottom)
			)
		)
		(property "Value" "C_1u_25V_0603"
			(at -1.42757 1.770288 0)
			(layer "F.Fab")
			(effects
				(font
					(size 0.7 0.7)
					(thickness 0.15)
				)
				(justify right bottom)
			)
		)
		(property "Datasheet" "https://product.samsungsem.com/mlcc/CL10A105KA8NNN.do"
			(at 0 0 180)
			(layer "F.Fab")
			(hide yes)
			(effects
				(font
					(size 1.27 1.27)
					(thickness 0.15)
				)
			)
		)
		(property "Manufacturer" "Samsung Electro-Mechanics"
			(at 0 0 180)
			(unlocked yes)
			(layer "F.Fab")
			(hide yes)
			(effects
				(font
					(size 1 1)
					(thickness 0.15)
				)
			)
		)
		(property "MPN" "CL10A105KA8NNNC"
			(at 0 0 180)
			(unlocked yes)
			(layer "F.Fab")
			(hide yes)
			(effects
				(font
					(size 1 1)
					(thickness 0.15)
				)
			)
		)
		(property "Val" "1u"
			(at 0 0 180)
			(unlocked yes)
			(layer "F.Fab")
			(hide yes)
			(effects
				(font
					(size 1 1)
					(thickness 0.15)
				)
			)
		)
		(property "License" "Apache-2.0"
			(at 0 0 180)
			(unlocked yes)
			(layer "F.Fab")
			(hide yes)
			(effects
				(font
					(size 1 1)
					(thickness 0.15)
				)
			)
		)
		(property "Author" "Antmicro"
			(at 0 0 180)
			(unlocked yes)
			(layer "F.Fab")
			(hide yes)
			(effects
				(font
					(size 1 1)
					(thickness 0.15)
				)
			)
		)
		(property "Voltage" "25V"
			(at 0 0 180)
			(unlocked yes)
			(layer "F.Fab")
			(hide yes)
			(effects
				(font
					(size 1 1)
					(thickness 0.15)
				)
			)
		)
		(property "Dielectric" ""
			(at 0 0 180)
			(unlocked yes)
			(layer "F.Fab")
			(hide yes)
			(effects
				(font
					(size 1 1)
					(thickness 0.15)
				)
			)
		)
		(sheetname "/Supply/")
		(sheetfile "supply.kicad_sch")
		(attr smd)
		(fp_line
			(start -0.15 0.4)
			(end 0.15 0.4)
			(stroke
				(width 0.15)
				(type solid)
			)
			(layer "F.SilkS")
		)
		(fp_line
			(start -0.15 -0.4)
			(end 0.15 -0.4)
			(stroke
				(width 0.15)
				(type solid)
			)
			(layer "F.SilkS")
		)
		(fp_rect
			(start -1.25 -0.65)
			(end 1.25 0.65)
			(stroke
				(width 0.05)
				(type solid)
			)
			(fill no)
			(layer "F.CrtYd")
		)
		(fp_rect
			(start -0.8 -0.4)
			(end 0.8 0.4)
			(stroke
				(width 0.15)
				(type solid)
			)
			(fill no)
			(layer "F.Fab")
		)
		(fp_text user "License: Apache-2.0"
			(at -1.682 5.895 180)
			(layer "F.Fab")
			(effects
				(font
					(size 0.7 0.7)
					(thickness 0.15)
				)
				(justify left bottom)
			)
		)
		(fp_text user "${REFERENCE}"
			(at -1.682 3.895 180)
			(layer "F.Fab")
			(effects
				(font
					(size 0.7 0.7)
					(thickness 0.15)
				)
				(justify left bottom)
			)
		)
		(fp_text user "Author: Antmicro"
			(at -1.682 4.894 180)
			(layer "F.Fab")
			(effects
				(font
					(size 0.7 0.7)
					(thickness 0.15)
				)
				(justify left bottom)
			)
		)
		(pad "1" smd roundrect
			(at -0.7 0 180)
			(size 0.8 1)
			(layers "F.Cu" "F.Mask" "F.Paste")
			(roundrect_rratio 0.2)
			(net 1 "GND")
			(pintype "passive")
		)
		(pad "2" smd roundrect
			(at 0.7 0 180)
			(size 0.8 1)
			(layers "F.Cu" "F.Mask" "F.Paste")
			(roundrect_rratio 0.2)
			(net 35 "VDC")
			(pintype "passive")
		)
	)
	(footprint "antmicro-footprints:TP_SMD_1mm"
		(layer "F.Cu")
		(at 244.125 147.65)
		(property "Reference" "TP9"
			(at 0 -0.731898 0)
			(layer "F.SilkS")
			(hide yes)
			(effects
				(font
					(size 0.7 0.7)
					(thickness 0.15)
				)
				(justify left bottom)
			)
		)
		(property "Value" "TP_1mm_SMD"
			(at 0 1.4 0)
			(layer "F.Fab")
			(effects
				(font
					(size 0.7 0.7)
					(thickness 0.15)
				)
				(justify left bottom)
			)
		)
		(property "MPN" ""
			(at 0 0 0)
			(unlocked yes)
			(layer "F.Fab")
			(hide yes)
			(effects
				(font
					(size 1 1)
					(thickness 0.15)
				)
			)
		)
		(property "Manufacturer" ""
			(at 0 0 0)
			(unlocked yes)
			(layer "F.Fab")
			(hide yes)
			(effects
				(font
					(size 1 1)
					(thickness 0.15)
				)
			)
		)
		(property "Author" "Antmicro"
			(at 0 0 0)
			(unlocked yes)
			(layer "F.Fab")
			(hide yes)
			(effects
				(font
					(size 1 1)
					(thickness 0.15)
				)
			)
		)
		(property "License" "Apache-2.0"
			(at 0 0 0)
			(unlocked yes)
			(layer "F.Fab")
			(hide yes)
			(effects
				(font
					(size 1 1)
					(thickness 0.15)
				)
			)
		)
		(sheetname "/Supply/DC-DC IO/")
		(sheetfile "dc-dc-io.kicad_sch")
		(attr exclude_from_pos_files)
		(fp_circle
			(center 0 0)
			(end 0.6 0)
			(stroke
				(width 0.05)
				(type default)
			)
			(fill no)
			(layer "F.CrtYd")
		)
		(fp_text user "${REFERENCE}"
			(at -0.5 2.8 0)
			(layer "F.Fab")
			(effects
				(font
					(size 0.7 0.7)
					(thickness 0.15)
				)
				(justify left bottom)
			)
		)
		(fp_text user "Author: Antmicro"
			(at -0.5 4 0)
			(layer "F.Fab")
			(effects
				(font
					(size 0.7 0.7)
					(thickness 0.15)
				)
				(justify left bottom)
			)
		)
		(fp_text user "License: Apache-2.0"
			(at -0.5 5.2 0)
			(layer "F.Fab")
			(effects
				(font
					(size 0.7 0.7)
					(thickness 0.15)
				)
				(justify left bottom)
			)
		)
		(pad "1" smd circle
			(at 0 0)
			(size 1 1)
			(layers "F.Cu" "F.Mask")
			(net 687 "VDDQ")
			(pinfunction "1")
			(pintype "passive")
		)
	)
	(footprint "antmicro-footprints:R_0402_1005Metric"
		(layer "F.Cu")
		(at 146.174499 173.234 90)
		(descr "Resistor SMD 0402")
		(tags "resistor SMD 0402")
		(property "Reference" "R93"
			(at -3.116 0.485501 90)
			(layer "F.SilkS")
			(effects
				(font
					(size 0.7 0.7)
					(thickness 0.15)
				)
				(justify left bottom)
			)
		)
		(property "Value" "R_0R_0402"
			(at -1.011843 1.772047 90)
			(layer "F.Fab")
			(effects
				(font
					(size 0.7 0.7)
					(thickness 0.15)
				)
				(justify left bottom)
			)
		)
		(property "Datasheet" "https://industrial.panasonic.com/cdbs/www-data/pdf/RDA0000/AOA0000C301.pdf"
			(at 0 0 90)
			(layer "F.Fab")
			(hide yes)
			(effects
				(font
					(size 1.27 1.27)
					(thickness 0.15)
				)
			)
		)
		(property "Manufacturer" "Panasonic"
			(at 0 0 90)
			(unlocked yes)
			(layer "F.Fab")
			(hide yes)
			(effects
				(font
					(size 1 1)
					(thickness 0.15)
				)
			)
		)
		(property "MPN" "ERJ2GE0R00X"
			(at 0 0 90)
			(unlocked yes)
			(layer "F.Fab")
			(hide yes)
			(effects
				(font
					(size 1 1)
					(thickness 0.15)
				)
			)
		)
		(property "Val" "0R"
			(at 0 0 90)
			(unlocked yes)
			(layer "F.Fab")
			(hide yes)
			(effects
				(font
					(size 1 1)
					(thickness 0.15)
				)
			)
		)
		(property "License" "Apache-2.0"
			(at 0 0 90)
			(unlocked yes)
			(layer "F.Fab")
			(hide yes)
			(effects
				(font
					(size 1 1)
					(thickness 0.15)
				)
			)
		)
		(property "Author" "Antmicro"
			(at 0 0 90)
			(unlocked yes)
			(layer "F.Fab")
			(hide yes)
			(effects
				(font
					(size 1 1)
					(thickness 0.15)
				)
			)
		)
		(property "Tolerance" "~"
			(at 0 0 90)
			(unlocked yes)
			(layer "F.Fab")
			(hide yes)
			(effects
				(font
					(size 1 1)
					(thickness 0.15)
				)
			)
		)
		(property "Current" "1A"
			(at 0 0 90)
			(unlocked yes)
			(layer "F.Fab")
			(hide yes)
			(effects
				(font
					(size 1 1)
					(thickness 0.15)
				)
			)
		)
		(sheetname "/Debug FTDI + VNA/")
		(sheetfile "debug-ftdi.kicad_sch")
		(attr smd)
		(fp_rect
			(start -0.925 -0.47)
			(end 0.925 0.47)
			(stroke
				(width 0.05)
				(type default)
			)
			(fill no)
			(layer "F.CrtYd")
		)
		(fp_rect
			(start -0.5 -0.25)
			(end 0.5 0.25)
			(stroke
				(width 0.15)
				(type solid)
			)
			(fill no)
			(layer "F.Fab")
		)
		(fp_text user "Author: Antmicro"
			(at -0.95 4.169 90)
			(layer "F.Fab")
			(effects
				(font
					(size 0.7 0.7)
					(thickness 0.15)
				)
				(justify left bottom)
			)
		)
		(fp_text user "${REFERENCE}"
			(at -0.95 3.168 90)
			(layer "F.Fab")
			(effects
				(font
					(size 0.7 0.7)
					(thickness 0.15)
				)
				(justify left bottom)
			)
		)
		(fp_text user "License: Apache-2.0"
			(at -0.95 5.169 90)
			(layer "F.Fab")
			(effects
				(font
					(size 0.7 0.7)
					(thickness 0.15)
				)
				(justify left bottom)
			)
		)
		(pad "1" smd roundrect
			(at -0.48 0 90)
			(size 0.59 0.64)
			(layers "F.Cu" "F.Mask" "F.Paste")
			(roundrect_rratio 0.25)
			(net 527 "/Debug FTDI + VNA/FTDI.SDA")
			(pintype "passive")
		)
		(pad "2" smd roundrect
			(at 0.48 0 90)
			(size 0.59 0.64)
			(layers "F.Cu" "F.Mask" "F.Paste")
			(roundrect_rratio 0.25)
			(net 139 "/Debug FTDI + VNA/FTDI_SDA_IN")
			(pintype "passive")
		)
	)
	(footprint "antmicro-footprints:R_0603_1608Metric"
		(layer "F.Cu")
		(at 230.45 167.95 90)
		(descr "Resistor SMD 0603")
		(tags "resistor SMD 0603")
		(property "Reference" "R211"
			(at 1.2 0.55 90)
			(layer "F.SilkS")
			(effects
				(font
					(size 0.7 0.7)
					(thickness 0.15)
				)
				(justify left bottom)
			)
		)
		(property "Value" "R_0R_22.4A_0603"
			(at 0 1.6 90)
			(layer "F.Fab")
			(effects
				(font
					(size 0.7 0.7)
					(thickness 0.15)
				)
				(justify left bottom)
			)
		)
		(property "Datasheet" "https://fscdn.rohm.com/en/products/databook/datasheet/passive/resistor/chip_resistor/pmr-jpw-e.pdf"
			(at 0 0 90)
			(layer "F.Fab")
			(hide yes)
			(effects
				(font
					(size 1.27 1.27)
					(thickness 0.15)
				)
			)
		)
		(property "Manufacturer" "ROHM Semiconductor"
			(at 0 0 90)
			(unlocked yes)
			(layer "F.Fab")
			(hide yes)
			(effects
				(font
					(size 1 1)
					(thickness 0.15)
				)
			)
		)
		(property "MPN" "PMR03EZPJ000"
			(at 0 0 90)
			(unlocked yes)
			(layer "F.Fab")
			(hide yes)
			(effects
				(font
					(size 1 1)
					(thickness 0.15)
				)
			)
		)
		(property "Val" "0R"
			(at 0 0 90)
			(unlocked yes)
			(layer "F.Fab")
			(hide yes)
			(effects
				(font
					(size 1 1)
					(thickness 0.15)
				)
			)
		)
		(property "Author" "Antmicro"
			(at 0 0 90)
			(unlocked yes)
			(layer "F.Fab")
			(hide yes)
			(effects
				(font
					(size 1 1)
					(thickness 0.15)
				)
			)
		)
		(property "License" "Apache-2.0"
			(at 0 0 90)
			(unlocked yes)
			(layer "F.Fab")
			(hide yes)
			(effects
				(font
					(size 1 1)
					(thickness 0.15)
				)
			)
		)
		(property "Max. Curr." "22.4A"
			(at 0 0 90)
			(unlocked yes)
			(layer "F.Fab")
			(hide yes)
			(effects
				(font
					(size 1 1)
					(thickness 0.15)
				)
			)
		)
		(sheetname "/Supply/DC-DC VCCINT/")
		(sheetfile "dc-dc-vccint.kicad_sch")
		(attr smd)
		(fp_line
			(start -0.15 -0.4)
			(end 0.15 -0.4)
			(stroke
				(width 0.15)
				(type solid)
			)
			(layer "F.SilkS")
		)
		(fp_line
			(start -0.15 0.4)
			(end 0.15 0.4)
			(stroke
				(width 0.15)
				(type solid)
			)
			(layer "F.SilkS")
		)
		(fp_rect
			(start -1.25 -0.65)
			(end 1.25 0.65)
			(stroke
				(width 0.05)
				(type solid)
			)
			(fill no)
			(layer "F.CrtYd")
		)
		(fp_rect
			(start -0.8 -0.4)
			(end 0.8 0.4)
			(stroke
				(width 0.15)
				(type solid)
			)
			(fill no)
			(layer "F.Fab")
		)
		(fp_text user "License: Apache-2.0"
			(at -1.25 5.9 90)
			(layer "F.Fab")
			(effects
				(font
					(size 0.7 0.7)
					(thickness 0.15)
				)
				(justify left bottom)
			)
		)
		(fp_text user "${REFERENCE}"
			(at -1.25 3.898 90)
			(layer "F.Fab")
			(effects
				(font
					(size 0.7 0.7)
					(thickness 0.15)
				)
				(justify left bottom)
			)
		)
		(fp_text user "Author: Antmicro"
			(at -1.25 4.9 90)
			(layer "F.Fab")
			(effects
				(font
					(size 0.7 0.7)
					(thickness 0.15)
				)
				(justify left bottom)
			)
		)
		(pad "1" smd roundrect
			(at -0.7 0 90)
			(size 0.8 1)
			(layers "F.Cu" "F.Mask" "F.Paste")
			(roundrect_rratio 0.2)
			(net 224 "/Supply/DC-DC VCCINT/0V85_REG1")
			(pintype "passive")
		)
		(pad "2" smd roundrect
			(at 0.7 0 90)
			(size 0.8 1)
			(layers "F.Cu" "F.Mask" "F.Paste")
			(roundrect_rratio 0.2)
			(net 553 "+0V85")
			(pintype "passive")
		)
	)
	(footprint "antmicro-footprints:TP_SMD_1mm"
		(layer "F.Cu")
		(at 244.025 165.825)
		(property "Reference" "TP15"
			(at 0 -0.731898 0)
			(layer "F.SilkS")
			(hide yes)
			(effects
				(font
					(size 0.7 0.7)
					(thickness 0.15)
				)
				(justify left bottom)
			)
		)
		(property "Value" "TP_1mm_SMD"
			(at 0 1.4 0)
			(layer "F.Fab")
			(effects
				(font
					(size 0.7 0.7)
					(thickness 0.15)
				)
				(justify left bottom)
			)
		)
		(property "MPN" ""
			(at 0 0 0)
			(unlocked yes)
			(layer "F.Fab")
			(hide yes)
			(effects
				(font
					(size 1 1)
					(thickness 0.15)
				)
			)
		)
		(property "Manufacturer" ""
			(at 0 0 0)
			(unlocked yes)
			(layer "F.Fab")
			(hide yes)
			(effects
				(font
					(size 1 1)
					(thickness 0.15)
				)
			)
		)
		(property "Author" "Antmicro"
			(at 0 0 0)
			(unlocked yes)
			(layer "F.Fab")
			(hide yes)
			(effects
				(font
					(size 1 1)
					(thickness 0.15)
				)
			)
		)
		(property "License" "Apache-2.0"
			(at 0 0 0)
			(unlocked yes)
			(layer "F.Fab")
			(hide yes)
			(effects
				(font
					(size 1 1)
					(thickness 0.15)
				)
			)
		)
		(sheetname "/Supply/DC-DC AUX, MGT/")
		(sheetfile "dc-dc-aux-mgt.kicad_sch")
		(attr exclude_from_pos_files)
		(fp_circle
			(center 0 0)
			(end 0.6 0)
			(stroke
				(width 0.05)
				(type default)
			)
			(fill no)
			(layer "F.CrtYd")
		)
		(fp_text user "License: Apache-2.0"
			(at -0.5 5.2 0)
			(layer "F.Fab")
			(effects
				(font
					(size 0.7 0.7)
					(thickness 0.15)
				)
				(justify left bottom)
			)
		)
		(fp_text user "${REFERENCE}"
			(at -0.5 2.8 0)
			(layer "F.Fab")
			(effects
				(font
					(size 0.7 0.7)
					(thickness 0.15)
				)
				(justify left bottom)
			)
		)
		(fp_text user "Author: Antmicro"
			(at -0.5 4 0)
			(layer "F.Fab")
			(effects
				(font
					(size 0.7 0.7)
					(thickness 0.15)
				)
				(justify left bottom)
			)
		)
		(pad "1" smd circle
			(at 0 0)
			(size 1 1)
			(layers "F.Cu" "F.Mask")
			(net 820 "+0V9_MGTAVCC")
			(pinfunction "1")
			(pintype "passive")
		)
	)
	(footprint "antmicro-footprints:FBGA-25-24_6x8mm_Layout5x5_P1mm"
		(layer "F.Cu")
		(at 167.1 152.5 -90)
		(property "Reference" "U1"
			(at 0 -4.5 90)
			(layer "F.SilkS")
			(effects
				(font
					(size 0.7 0.7)
					(thickness 0.15)
				)
				(justify right bottom)
			)
		)
		(property "Value" "IS66WVH16M8DALL-166B1LI"
			(at 0.1 5.3 90)
			(layer "F.Fab")
			(effects
				(font
					(size 0.7 0.7)
					(thickness 0.15)
				)
				(justify right bottom)
			)
		)
		(property "Datasheet" "https://www.issi.com/WW/pdf/66-67WVH16M8DALL-BLL.pdf"
			(at 0 0 270)
			(layer "F.Fab")
			(hide yes)
			(effects
				(font
					(size 1.27 1.27)
					(thickness 0.15)
				)
			)
		)
		(property "Manufacturer" "ISSI"
			(at 0 0 270)
			(unlocked yes)
			(layer "F.Fab")
			(hide yes)
			(effects
				(font
					(size 1 1)
					(thickness 0.15)
				)
			)
		)
		(property "MPN" "IS66WVH16M8DALL-166B1LI"
			(at 0 0 270)
			(unlocked yes)
			(layer "F.Fab")
			(hide yes)
			(effects
				(font
					(size 1 1)
					(thickness 0.15)
				)
			)
		)
		(property "Author" "Antmicro"
			(at 0 0 270)
			(unlocked yes)
			(layer "F.Fab")
			(hide yes)
			(effects
				(font
					(size 1 1)
					(thickness 0.15)
				)
			)
		)
		(property "License" "Apache-2.0"
			(at 0 0 270)
			(unlocked yes)
			(layer "F.Fab")
			(hide yes)
			(effects
				(font
					(size 1 1)
					(thickness 0.15)
				)
			)
		)
		(sheetname "/HyperRAM + QSPI Flash/")
		(sheetfile "hyperram-flash.kicad_sch")
		(attr smd)
		(fp_line
			(start -3.121 4.12)
			(end -3.121 2.12)
			(stroke
				(width 0.15)
				(type solid)
			)
			(layer "F.SilkS")
		)
		(fp_line
			(start -1.621 4.12)
			(end -3.121 4.12)
			(stroke
				(width 0.15)
				(type solid)
			)
			(layer "F.SilkS")
		)
		(fp_line
			(start 1.62 4.12)
			(end 3.12 4.12)
			(stroke
				(width 0.15)
				(type solid)
			)
			(layer "F.SilkS")
		)
		(fp_line
			(start 3.12 4.12)
			(end 3.12 2.12)
			(stroke
				(width 0.15)
				(type solid)
			)
			(layer "F.SilkS")
		)
		(fp_line
			(start -3.121 -3)
			(end -3.121 -2.121)
			(stroke
				(width 0.15)
				(type solid)
			)
			(layer "F.SilkS")
		)
		(fp_line
			(start -2 -4.121)
			(end -3.121 -3)
			(stroke
				(width 0.15)
				(type solid)
			)
			(layer "F.SilkS")
		)
		(fp_line
			(start -1.621 -4.121)
			(end -2 -4.121)
			(stroke
				(width 0.15)
				(type solid)
			)
			(layer "F.SilkS")
		)
		(fp_line
			(start 1.62 -4.121)
			(end 3.12 -4.121)
			(stroke
				(width 0.15)
				(type solid)
			)
			(layer "F.SilkS")
		)
		(fp_line
			(start 1.62 -4.121)
			(end 3.12 -4.121)
			(stroke
				(width 0.15)
				(type solid)
			)
			(layer "F.SilkS")
		)
		(fp_line
			(start 1.62 -4.121)
			(end 3.12 -4.121)
			(stroke
				(width 0.15)
				(type solid)
			)
			(layer "F.SilkS")
		)
		(fp_line
			(start 3.12 -4.121)
			(end 3.12 -2.121)
			(stroke
				(width 0.15)
				(type solid)
			)
			(layer "F.SilkS")
		)
		(fp_line
			(start 3.12 -4.121)
			(end 3.12 -2.121)
			(stroke
				(width 0.15)
				(type solid)
			)
			(layer "F.SilkS")
		)
		(fp_line
			(start 3.12 -4.121)
			(end 3.12 -2.121)
			(stroke
				(width 0.15)
				(type solid)
			)
			(layer "F.SilkS")
		)
		(fp_circle
			(center -3.6 -3.9)
			(end -3.5 -3.9)
			(stroke
				(width 0.15)
				(type solid)
			)
			(fill yes)
			(layer "F.SilkS")
		)
		(fp_line
			(start -3.25 4.24)
			(end -3.25 -4.25)
			(stroke
				(width 0.05)
				(type solid)
			)
			(layer "F.CrtYd")
		)
		(fp_line
			(start 3.24 4.24)
			(end -3.25 4.24)
			(stroke
				(width 0.05)
				(type solid)
			)
			(layer "F.CrtYd")
		)
		(fp_line
			(start -3.25 -4.25)
			(end 3.24 -4.25)
			(stroke
				(width 0.05)
				(type solid)
			)
			(layer "F.CrtYd")
		)
		(fp_line
			(start 3.24 -4.25)
			(end 3.24 4.24)
			(stroke
				(width 0.05)
				(type solid)
			)
			(layer "F.CrtYd")
		)
		(fp_line
			(start -3 4)
			(end 3 4)
			(stroke
				(width 0.15)
				(type solid)
			)
			(layer "F.Fab")
		)
		(fp_line
			(start 3 4)
			(end 3 -4)
			(stroke
				(width 0.15)
				(type solid)
			)
			(layer "F.Fab")
		)
		(fp_line
			(start -3 -3)
			(end -3 4)
			(stroke
				(width 0.15)
				(type solid)
			)
			(layer "F.Fab")
		)
		(fp_line
			(start -2 -4)
			(end -3 -3)
			(stroke
				(width 0.15)
				(type solid)
			)
			(layer "F.Fab")
		)
		(fp_line
			(start 3 -4)
			(end -2 -4)
			(stroke
				(width 0.15)
				(type solid)
			)
			(layer "F.Fab")
		)
		(fp_text user "License: Apache-2.0"
			(at -3.25 10.759 270)
			(layer "F.Fab")
			(effects
				(font
					(size 0.7 0.7)
					(thickness 0.15)
				)
				(justify left bottom)
			)
		)
		(fp_text user "${REFERENCE}"
			(at -3.25 8.359 270)
			(layer "F.Fab")
			(effects
				(font
					(size 0.7 0.7)
					(thickness 0.15)
				)
				(justify left bottom)
			)
		)
		(fp_text user "Author: Antmicro"
			(at -3.25 9.559 270)
			(layer "F.Fab")
			(effects
				(font
					(size 0.7 0.7)
					(thickness 0.15)
				)
				(justify left bottom)
			)
		)
		(pad "A2" smd circle
			(at -1 -2 270)
			(size 0.4 0.4)
			(layers "F.Cu" "F.Mask" "F.Paste")
			(net 303 "unconnected-(U1-NC-PadA2)")
			(pinfunction "NC")
			(pintype "no_connect")
		)
		(pad "A3" smd circle
			(at 0 -2 270)
			(size 0.4 0.4)
			(layers "F.Cu" "F.Mask" "F.Paste")
			(net 618 "/FPGA banks HP/HyperRAM.~{CS}")
			(pinfunction "~{CS}")
			(pintype "input")
		)
		(pad "A4" smd circle
			(at 1 -2 270)
			(size 0.4 0.4)
			(layers "F.Cu" "F.Mask" "F.Paste")
			(net 623 "/FPGA banks HP/HyperRAM.~{RESET}")
			(pinfunction "~{RESET}")
			(pintype "input")
		)
		(pad "A5" smd circle
			(at 2 -2 270)
			(size 0.4 0.4)
			(layers "F.Cu" "F.Mask" "F.Paste")
			(net 304 "unconnected-(U1-NC-PadA5)")
			(pinfunction "NC")
			(pintype "no_connect")
		)
		(pad "B1" smd circle
			(at -2 -1 270)
			(size 0.4 0.4)
			(layers "F.Cu" "F.Mask" "F.Paste")
			(net 617 "/FPGA banks HP/HyperRAM.CK_N")
			(pinfunction "CK-")
			(pintype "input")
		)
		(pad "B2" smd circle
			(at -1 -1 270)
			(size 0.4 0.4)
			(layers "F.Cu" "F.Mask" "F.Paste")
			(net 616 "/FPGA banks HP/HyperRAM.CK_P")
			(pinfunction "CK+")
			(pintype "input")
		)
		(pad "B3" smd circle
			(at 0 -1 270)
			(size 0.4 0.4)
			(layers "F.Cu" "F.Mask" "F.Paste")
			(net 1 "GND")
			(pinfunction "VSS")
			(pintype "power_in")
		)
		(pad "B4" smd circle
			(at 1 -1 270)
			(size 0.4 0.4)
			(layers "F.Cu" "F.Mask" "F.Paste")
			(net 797 "+1V8")
			(pinfunction "VCC")
			(pintype "power_in")
		)
		(pad "B5" smd circle
			(at 2 -1 270)
			(size 0.4 0.4)
			(layers "F.Cu" "F.Mask" "F.Paste")
			(net 305 "unconnected-(U1-NC-PadB5)")
			(pinfunction "NC")
			(pintype "no_connect")
		)
		(pad "C1" smd circle
			(at -2 0 270)
			(size 0.4 0.4)
			(layers "F.Cu" "F.Mask" "F.Paste")
			(net 1 "GND")
			(pinfunction "VSSQ")
			(pintype "power_in")
		)
		(pad "C2" smd circle
			(at -1 0 270)
			(size 0.4 0.4)
			(layers "F.Cu" "F.Mask" "F.Paste")
			(net 306 "unconnected-(U1-NC-PadC2)")
			(pinfunction "NC")
			(pintype "no_connect")
		)
		(pad "C3" smd circle
			(at 0 0 270)
			(size 0.4 0.4)
			(layers "F.Cu" "F.Mask" "F.Paste")
			(net 624 "/FPGA banks HP/HyperRAM.RWDS")
			(pinfunction "RWDS")
			(pintype "bidirectional")
		)
		(pad "C4" smd circle
			(at 1 0 270)
			(size 0.4 0.4)
			(layers "F.Cu" "F.Mask" "F.Paste")
			(net 615 "/FPGA banks HP/HyperRAM.DQ2")
			(pinfunction "DQ2")
			(pintype "bidirectional")
		)
		(pad "C5" smd circle
			(at 2 0 270)
			(size 0.4 0.4)
			(layers "F.Cu" "F.Mask" "F.Paste")
			(net 307 "unconnected-(U1-NC-PadC5)")
			(pinfunction "NC")
			(pintype "no_connect")
		)
		(pad "D1" smd circle
			(at -2 1 270)
			(size 0.4 0.4)
			(layers "F.Cu" "F.Mask" "F.Paste")
			(net 797 "+1V8")
			(pinfunction "VCCQ")
			(pintype "power_in")
		)
		(pad "D2" smd circle
			(at -1 1 270)
			(size 0.4 0.4)
			(layers "F.Cu" "F.Mask" "F.Paste")
			(net 620 "/FPGA banks HP/HyperRAM.DQ1")
			(pinfunction "DQ1")
			(pintype "bidirectional")
		)
		(pad "D3" smd circle
			(at 0 1 270)
			(size 0.4 0.4)
			(layers "F.Cu" "F.Mask" "F.Paste")
			(net 622 "/FPGA banks HP/HyperRAM.DQ0")
			(pinfunction "DQ0")
			(pintype "bidirectional")
		)
		(pad "D4" smd circle
			(at 1 1 270)
			(size 0.4 0.4)
			(layers "F.Cu" "F.Mask" "F.Paste")
			(net 613 "/FPGA banks HP/HyperRAM.DQ3")
			(pinfunction "DQ3")
			(pintype "bidirectional")
		)
		(pad "D5" smd circle
			(at 2 1 270)
			(size 0.4 0.4)
			(layers "F.Cu" "F.Mask" "F.Paste")
			(net 621 "/FPGA banks HP/HyperRAM.DQ4")
			(pinfunction "DQ4")
			(pintype "bidirectional")
		)
		(pad "E1" smd circle
			(at -2 2 270)
			(size 0.4 0.4)
			(layers "F.Cu" "F.Mask" "F.Paste")
			(net 610 "/FPGA banks HP/HyperRAM.DQ7")
			(pinfunction "DQ7")
			(pintype "bidirectional")
		)
		(pad "E2" smd circle
			(at -1 2 270)
			(size 0.4 0.4)
			(layers "F.Cu" "F.Mask" "F.Paste")
			(net 614 "/FPGA banks HP/HyperRAM.DQ6")
			(pinfunction "DQ6")
			(pintype "bidirectional")
		)
		(pad "E3" smd circle
			(at 0 2 270)
			(size 0.4 0.4)
			(layers "F.Cu" "F.Mask" "F.Paste")
			(net 619 "/FPGA banks HP/HyperRAM.DQ5")
			(pinfunction "DQ5")
			(pintype "bidirectional")
		)
		(pad "E4" smd circle
			(at 1 2 270)
			(size 0.4 0.4)
			(layers "F.Cu" "F.Mask" "F.Paste")
			(net 797 "+1V8")
			(pinfunction "VCCQ")
			(pintype "passive")
		)
		(pad "E5" smd circle
			(at 2 2 270)
			(size 0.4 0.4)
			(layers "F.Cu" "F.Mask" "F.Paste")
			(net 1 "GND")
			(pinfunction "VSSQ")
			(pintype "passive")
		)
	)
	(footprint "antmicro-footprints:R_0402_1005Metric"
		(layer "F.Cu")
		(at 125.681 166.1125 90)
		(descr "Resistor SMD 0402")
		(tags "resistor SMD 0402")
		(property "Reference" "R226"
			(at 0.9125 3.969 90)
			(layer "F.SilkS")
			(effects
				(font
					(size 0.7 0.7)
					(thickness 0.15)
				)
				(justify left bottom)
			)
		)
		(property "Value" "R_64k9_0402"
			(at -1.011843 1.772047 90)
			(layer "F.Fab")
			(effects
				(font
					(size 0.7 0.7)
					(thickness 0.15)
				)
				(justify left bottom)
			)
		)
		(property "Datasheet" "https://www.bourns.com/docs/product-datasheets/cr.pdf"
			(at 0 0 90)
			(layer "F.Fab")
			(hide yes)
			(effects
				(font
					(size 1.27 1.27)
					(thickness 0.15)
				)
			)
		)
		(property "MPN" "CR0402-FX-6492GLF"
			(at 0 0 90)
			(unlocked yes)
			(layer "F.Fab")
			(hide yes)
			(effects
				(font
					(size 1 1)
					(thickness 0.15)
				)
			)
		)
		(property "Manufacturer" "Bourns"
			(at 0 0 90)
			(unlocked yes)
			(layer "F.Fab")
			(hide yes)
			(effects
				(font
					(size 1 1)
					(thickness 0.15)
				)
			)
		)
		(property "License" "Apache-2.0"
			(at 0 0 90)
			(unlocked yes)
			(layer "F.Fab")
			(hide yes)
			(effects
				(font
					(size 1 1)
					(thickness 0.15)
				)
			)
		)
		(property "Author" "Antmicro"
			(at 0 0 90)
			(unlocked yes)
			(layer "F.Fab")
			(hide yes)
			(effects
				(font
					(size 1 1)
					(thickness 0.15)
				)
			)
		)
		(property "Val" "64k9"
			(at 0 0 90)
			(unlocked yes)
			(layer "F.Fab")
			(hide yes)
			(effects
				(font
					(size 1 1)
					(thickness 0.15)
				)
			)
		)
		(property "Tolerance" "1%"
			(at 0 0 90)
			(unlocked yes)
			(layer "F.Fab")
			(hide yes)
			(effects
				(font
					(size 1 1)
					(thickness 0.15)
				)
			)
		)
		(sheetname "/HDMI + SD Card/")
		(sheetfile "hdmi-sd-card.kicad_sch")
		(attr smd exclude_from_bom dnp)
		(fp_rect
			(start -0.925 -0.47)
			(end 0.925 0.47)
			(stroke
				(width 0.05)
				(type default)
			)
			(fill no)
			(layer "F.CrtYd")
		)
		(fp_rect
			(start -0.5 -0.25)
			(end 0.5 0.25)
			(stroke
				(width 0.15)
				(type solid)
			)
			(fill no)
			(layer "F.Fab")
		)
		(fp_text user "Author: Antmicro"
			(at -0.95 4.169 90)
			(layer "F.Fab")
			(effects
				(font
					(size 0.7 0.7)
					(thickness 0.15)
				)
				(justify left bottom)
			)
		)
		(fp_text user "${REFERENCE}"
			(at -0.95 3.168 90)
			(layer "F.Fab")
			(effects
				(font
					(size 0.7 0.7)
					(thickness 0.15)
				)
				(justify left bottom)
			)
		)
		(fp_text user "License: Apache-2.0"
			(at -0.95 5.169 90)
			(layer "F.Fab")
			(effects
				(font
					(size 0.7 0.7)
					(thickness 0.15)
				)
				(justify left bottom)
			)
		)
		(pad "1" smd roundrect
			(at -0.48 0 90)
			(size 0.59 0.64)
			(layers "F.Cu" "F.Mask" "F.Paste")
			(roundrect_rratio 0.25)
			(net 736 "/HDMI + SD Card/PRE_SEL")
			(pintype "passive")
		)
		(pad "2" smd roundrect
			(at 0.48 0 90)
			(size 0.59 0.64)
			(layers "F.Cu" "F.Mask" "F.Paste")
			(roundrect_rratio 0.25)
			(net 151 "+3V3")
			(pintype "passive")
		)
	)
	(footprint "antmicro-footprints:NetTie-2_SMD_Pad0.127mm"
		(layer "F.Cu")
		(at 256.113 148.15 180)
		(descr "Net tie, 2 pin, 0.127mm  SMD pads")
		(tags "net tie")
		(property "Reference" "NT15"
			(at -0.128 -1.345 0)
			(layer "F.SilkS")
			(hide yes)
			(effects
				(font
					(size 0.7 0.7)
					(thickness 0.15)
				)
				(justify right bottom)
			)
		)
		(property "Value" "Net-Tie_P0.127mm"
			(at 0 1.199 0)
			(layer "F.Fab")
			(effects
				(font
					(size 0.7 0.7)
					(thickness 0.15)
				)
				(justify right bottom)
			)
		)
		(property "MPN" ""
			(at 0 0 180)
			(unlocked yes)
			(layer "F.Fab")
			(hide yes)
			(effects
				(font
					(size 1 1)
					(thickness 0.15)
				)
			)
		)
		(property "Manufacturer" ""
			(at 0 0 180)
			(unlocked yes)
			(layer "F.Fab")
			(hide yes)
			(effects
				(font
					(size 1 1)
					(thickness 0.15)
				)
			)
		)
		(property "Author" "Antmicro"
			(at 0 0 180)
			(unlocked yes)
			(layer "F.Fab")
			(hide yes)
			(effects
				(font
					(size 1 1)
					(thickness 0.15)
				)
			)
		)
		(property "License" "Apache-2.0"
			(at 0 0 180)
			(unlocked yes)
			(layer "F.Fab")
			(hide yes)
			(effects
				(font
					(size 1 1)
					(thickness 0.15)
				)
			)
		)
		(property ki_fp_filters "Net*Tie*")
		(sheetname "/Supply/DC-DC IO/")
		(sheetfile "dc-dc-io.kicad_sch")
		(attr through_hole exclude_from_pos_files exclude_from_bom)
		(net_tie_pad_groups "1, 2")
		(fp_poly
			(pts
				(xy -0.0635 -0.0635) (xy 0.0625 -0.0635) (xy 0.0625 0.0635) (xy -0.0635 0.0635)
			)
			(stroke
				(width 0)
				(type solid)
			)
			(fill yes)
			(layer "F.Cu")
		)
		(fp_poly
			(pts
				(xy 0.2 -0.16) (xy 0.29 -0.07) (xy 0.29 0.07) (xy 0.2 0.16) (xy -0.2 0.16) (xy -0.29 0.07) (xy -0.29 -0.06)
				(xy -0.19 -0.16)
			)
			(stroke
				(width 0.05)
				(type solid)
			)
			(fill no)
			(layer "F.CrtYd")
		)
		(fp_text user "Author: Antmicro"
			(at -0.128 4.4 180)
			(layer "F.Fab")
			(effects
				(font
					(size 0.7 0.7)
					(thickness 0.15)
				)
				(justify left bottom)
			)
		)
		(fp_text user "${REFERENCE}"
			(at -0.128 3.2 180)
			(layer "F.Fab")
			(effects
				(font
					(size 0.7 0.7)
					(thickness 0.15)
				)
				(justify left bottom)
			)
		)
		(fp_text user "License: Apache-2.0"
			(at -0.128 5.6 180)
			(layer "F.Fab")
			(effects
				(font
					(size 0.7 0.7)
					(thickness 0.15)
				)
				(justify left bottom)
			)
		)
		(pad "1" smd roundrect
			(at -0.127 0)
			(size 0.127 0.127)
			(layers "F.Cu")
			(roundrect_rratio 0.5)
			(chamfer_ratio 0)
			(chamfer top_left bottom_left)
			(net 819 "/Supply/DC-DC IO/VDDQ_SEN_-")
			(pinfunction "1")
			(pintype "passive")
		)
		(pad "2" smd roundrect
			(at 0.126 0 180)
			(size 0.127 0.127)
			(layers "F.Cu")
			(roundrect_rratio 0.5)
			(chamfer_ratio 0)
			(chamfer top_left bottom_left)
			(net 687 "VDDQ")
			(pinfunction "2")
			(pintype "passive")
		)
	)
	(footprint "antmicro-footprints:C_0402_1005Metric"
		(layer "F.Cu")
		(at 256.825 128.925 90)
		(descr "Capacitor SMD 0402")
		(tags "capacitor SMD 0402")
		(property "Reference" "C194"
			(at -1.225 1.475 90)
			(layer "F.SilkS")
			(effects
				(font
					(size 0.7 0.7)
					(thickness 0.15)
				)
				(justify left bottom)
			)
		)
		(property "Value" "C_1u_0402"
			(at -1.022927 2.155213 90)
			(layer "F.Fab")
			(effects
				(font
					(size 0.7 0.7)
					(thickness 0.15)
				)
				(justify left bottom)
			)
		)
		(property "Datasheet" "https://product.tdk.com/en/search/capacitor/ceramic/mlcc/info?part_no=C1005X6S1A105K050BC"
			(at 0 0 90)
			(layer "F.Fab")
			(hide yes)
			(effects
				(font
					(size 1.27 1.27)
					(thickness 0.15)
				)
			)
		)
		(property "Manufacturer" "TDK"
			(at 0 0 90)
			(unlocked yes)
			(layer "F.Fab")
			(hide yes)
			(effects
				(font
					(size 1 1)
					(thickness 0.15)
				)
			)
		)
		(property "MPN" "C1005X6S1A105K050BC"
			(at 0 0 90)
			(unlocked yes)
			(layer "F.Fab")
			(hide yes)
			(effects
				(font
					(size 1 1)
					(thickness 0.15)
				)
			)
		)
		(property "Val" "1u"
			(at 0 0 90)
			(unlocked yes)
			(layer "F.Fab")
			(hide yes)
			(effects
				(font
					(size 1 1)
					(thickness 0.15)
				)
			)
		)
		(property "License" "Apache-2.0"
			(at 0 0 90)
			(unlocked yes)
			(layer "F.Fab")
			(hide yes)
			(effects
				(font
					(size 1 1)
					(thickness 0.15)
				)
			)
		)
		(property "Author" "Antmicro"
			(at 0 0 90)
			(unlocked yes)
			(layer "F.Fab")
			(hide yes)
			(effects
				(font
					(size 1 1)
					(thickness 0.15)
				)
			)
		)
		(property "Voltage" ""
			(at 0 0 90)
			(unlocked yes)
			(layer "F.Fab")
			(hide yes)
			(effects
				(font
					(size 1 1)
					(thickness 0.15)
				)
			)
		)
		(property "Dielectric" ""
			(at 0 0 90)
			(unlocked yes)
			(layer "F.Fab")
			(hide yes)
			(effects
				(font
					(size 1 1)
					(thickness 0.15)
				)
			)
		)
		(sheetname "/Supply/")
		(sheetfile "supply.kicad_sch")
		(attr smd)
		(fp_rect
			(start -0.925 -0.47)
			(end 0.925 0.47)
			(stroke
				(width 0.05)
				(type default)
			)
			(fill no)
			(layer "F.CrtYd")
		)
		(fp_line
			(start 0.504 -0.25)
			(end 0.504 0.248)
			(stroke
				(width 0.15)
				(type solid)
			)
			(layer "F.Fab")
		)
		(fp_line
			(start -0.494 -0.25)
			(end 0.504 -0.25)
			(stroke
				(width 0.15)
				(type solid)
			)
			(layer "F.Fab")
		)
		(fp_line
			(start 0.504 0.248)
			(end -0.494 0.248)
			(stroke
				(width 0.15)
				(type solid)
			)
			(layer "F.Fab")
		)
		(fp_line
			(start -0.494 0.248)
			(end -0.494 -0.25)
			(stroke
				(width 0.15)
				(type solid)
			)
			(layer "F.Fab")
		)
		(fp_text user "${REFERENCE}"
			(at -0.939 4.599 90)
			(layer "F.Fab")
			(effects
				(font
					(size 0.7 0.7)
					(thickness 0.15)
				)
				(justify left bottom)
			)
		)
		(fp_text user "Author: Antmicro"
			(at -0.939 3.399 90)
			(layer "F.Fab")
			(effects
				(font
					(size 0.7 0.7)
					(thickness 0.15)
				)
				(justify left bottom)
			)
		)
		(fp_text user "License: Apache-2.0"
			(at -0.939 5.799 90)
			(layer "F.Fab")
			(effects
				(font
					(size 0.7 0.7)
					(thickness 0.15)
				)
				(justify left bottom)
			)
		)
		(pad "1" smd roundrect
			(at -0.48 0 90)
			(size 0.59 0.64)
			(layers "F.Cu" "F.Mask" "F.Paste")
			(roundrect_rratio 0.25)
			(net 1 "GND")
			(pintype "passive")
		)
		(pad "2" smd roundrect
			(at 0.48 0 90)
			(size 0.59 0.64)
			(layers "F.Cu" "F.Mask" "F.Paste")
			(roundrect_rratio 0.25)
			(net 38 "+3V3_AON")
			(pintype "passive")
		)
	)
	(footprint "antmicro-footprints:C_Pol_EIA-D"
		(layer "F.Cu")
		(at 211.600002 160.4 90)
		(property "Reference" "C32"
			(at -6 2.434998 90)
			(layer "F.SilkS")
			(effects
				(font
					(size 0.7 0.7)
					(thickness 0.15)
				)
				(justify left bottom)
			)
		)
		(property "Value" "C_Pol_1m_2.5V_KEMET-T520-D"
			(at 0 3.4 90)
			(layer "F.Fab")
			(effects
				(font
					(size 0.7 0.7)
					(thickness 0.15)
				)
				(justify left bottom)
			)
		)
		(property "Datasheet" "https://www.kemet.com/en/us/capacitors/product/T520D108M2R5ATE030.html"
			(at 0 0 90)
			(layer "F.Fab")
			(hide yes)
			(effects
				(font
					(size 1.27 1.27)
					(thickness 0.15)
				)
			)
		)
		(property "MPN" "T520D108M2R5ATE030"
			(at 0 0 90)
			(unlocked yes)
			(layer "F.Fab")
			(hide yes)
			(effects
				(font
					(size 1 1)
					(thickness 0.15)
				)
			)
		)
		(property "Manufacturer" "KEMET"
			(at 0 0 90)
			(unlocked yes)
			(layer "F.Fab")
			(hide yes)
			(effects
				(font
					(size 1 1)
					(thickness 0.15)
				)
			)
		)
		(property "License" "Apache-2.0"
			(at 0 0 90)
			(unlocked yes)
			(layer "F.Fab")
			(hide yes)
			(effects
				(font
					(size 1 1)
					(thickness 0.15)
				)
			)
		)
		(property "Author" "Antmicro"
			(at 0 0 90)
			(unlocked yes)
			(layer "F.Fab")
			(hide yes)
			(effects
				(font
					(size 1 1)
					(thickness 0.15)
				)
			)
		)
		(property "Val" "1000u"
			(at 0 0 90)
			(unlocked yes)
			(layer "F.Fab")
			(hide yes)
			(effects
				(font
					(size 1 1)
					(thickness 0.15)
				)
			)
		)
		(property "Voltage" "2.5V"
			(at 0 0 90)
			(unlocked yes)
			(layer "F.Fab")
			(hide yes)
			(effects
				(font
					(size 1 1)
					(thickness 0.15)
				)
			)
		)
		(property "Dielectric" "template_dielectric"
			(at 0 0 90)
			(unlocked yes)
			(layer "F.Fab")
			(hide yes)
			(effects
				(font
					(size 1 1)
					(thickness 0.15)
				)
			)
		)
		(sheetname "/FPGA power/")
		(sheetfile "fpga-power.kicad_sch")
		(attr smd)
		(fp_line
			(start 3.6 -2.2)
			(end 3.6 -1.6)
			(stroke
				(width 0.15)
				(type solid)
			)
			(layer "F.SilkS")
		)
		(fp_line
			(start -3.58 -2.2)
			(end 3.6 -2.2)
			(stroke
				(width 0.15)
				(type solid)
			)
			(layer "F.SilkS")
		)
		(fp_line
			(start -4.1 -2.025)
			(end -4.1 -1.625)
			(stroke
				(width 0.12)
				(type solid)
			)
			(layer "F.SilkS")
		)
		(fp_line
			(start -4.3 -1.825)
			(end -3.9 -1.825)
			(stroke
				(width 0.12)
				(type solid)
			)
			(layer "F.SilkS")
		)
		(fp_line
			(start -3.58 -1.6)
			(end -3.58 -2.2)
			(stroke
				(width 0.15)
				(type solid)
			)
			(layer "F.SilkS")
		)
		(fp_line
			(start 3.6 1.6)
			(end 3.6 2.2)
			(stroke
				(width 0.15)
				(type solid)
			)
			(layer "F.SilkS")
		)
		(fp_line
			(start 3.6 2.2)
			(end -3.58 2.2)
			(stroke
				(width 0.15)
				(type solid)
			)
			(layer "F.SilkS")
		)
		(fp_line
			(start -3.58 2.2)
			(end -3.58 1.6)
			(stroke
				(width 0.15)
				(type solid)
			)
			(layer "F.SilkS")
		)
		(fp_line
			(start 3.77 -2.4)
			(end 3.77 -1.51)
			(stroke
				(width 0.05)
				(type solid)
			)
			(layer "F.CrtYd")
		)
		(fp_line
			(start -3.775 -2.4)
			(end 3.77 -2.4)
			(stroke
				(width 0.05)
				(type solid)
			)
			(layer "F.CrtYd")
		)
		(fp_line
			(start -3.775 -2.4)
			(end -3.775 -1.5)
			(stroke
				(width 0.05)
				(type solid)
			)
			(layer "F.CrtYd")
		)
		(fp_line
			(start 4.505 -1.51)
			(end 4.505 1.5)
			(stroke
				(width 0.05)
				(type solid)
			)
			(layer "F.CrtYd")
		)
		(fp_line
			(start 3.77 -1.51)
			(end 4.505 -1.51)
			(stroke
				(width 0.05)
				(type solid)
			)
			(layer "F.CrtYd")
		)
		(fp_line
			(start -3.775 -1.5)
			(end -4.505 -1.5)
			(stroke
				(width 0.05)
				(type solid)
			)
			(layer "F.CrtYd")
		)
		(fp_line
			(start 4.505 1.51)
			(end 3.77 1.51)
			(stroke
				(width 0.05)
				(type solid)
			)
			(layer "F.CrtYd")
		)
		(fp_line
			(start 3.77 1.51)
			(end 3.77 2.4)
			(stroke
				(width 0.05)
				(type solid)
			)
			(layer "F.CrtYd")
		)
		(fp_line
			(start -3.77 1.51)
			(end -4.505 1.51)
			(stroke
				(width 0.05)
				(type solid)
			)
			(layer "F.CrtYd")
		)
		(fp_line
			(start -4.505 1.51)
			(end -4.505 -1.5)
			(stroke
				(width 0.05)
				(type solid)
			)
			(layer "F.CrtYd")
		)
		(fp_line
			(start 3.77 2.4)
			(end -3.77 2.4)
			(stroke
				(width 0.05)
				(type solid)
			)
			(layer "F.CrtYd")
		)
		(fp_line
			(start -3.77 2.4)
			(end -3.77 1.51)
			(stroke
				(width 0.05)
				(type solid)
			)
			(layer "F.CrtYd")
		)
		(fp_rect
			(start -3.65 -2.15)
			(end 3.65 2.15)
			(stroke
				(width 0.15)
				(type solid)
			)
			(fill no)
			(layer "F.Fab")
		)
		(fp_text user "License: Apache-2.0"
			(at -4.5 6.6 90)
			(layer "F.Fab")
			(effects
				(font
					(size 0.7 0.7)
					(thickness 0.15)
				)
				(justify left bottom)
			)
		)
		(fp_text user "${REFERENCE}"
			(at -4.5 5.6 90)
			(layer "F.Fab")
			(effects
				(font
					(size 0.7 0.7)
					(thickness 0.15)
				)
				(justify left bottom)
			)
		)
		(fp_text user "Author: Antmicro"
			(at -4.5 7.6 90)
			(layer "F.Fab")
			(effects
				(font
					(size 0.7 0.7)
					(thickness 0.15)
				)
				(justify left bottom)
			)
		)
		(pad "1" smd roundrect
			(at -3.1 0 90)
			(size 2.31 2.52)
			(layers "F.Cu" "F.Mask" "F.Paste")
			(roundrect_rratio 0.1)
			(net 553 "+0V85")
			(pintype "passive")
		)
		(pad "2" smd roundrect
			(at 3.1 0 90)
			(size 2.31 2.52)
			(layers "F.Cu" "F.Mask" "F.Paste")
			(roundrect_rratio 0.1)
			(net 1 "GND")
			(pintype "passive")
		)
	)
	(footprint "antmicro-footprints:R_0402_1005Metric"
		(layer "F.Cu")
		(at 108.324499 148.564 90)
		(descr "Resistor SMD 0402")
		(tags "resistor SMD 0402")
		(property "Reference" "R90"
			(at -3.186 0.425501 90)
			(layer "F.SilkS")
			(effects
				(font
					(size 0.7 0.7)
					(thickness 0.15)
				)
				(justify left bottom)
			)
		)
		(property "Value" "R_330R_0402"
			(at -1.011843 1.772047 90)
			(layer "F.Fab")
			(effects
				(font
					(size 0.7 0.7)
					(thickness 0.15)
				)
				(justify left bottom)
			)
		)
		(property "Datasheet" "https://www.bourns.com/docs/product-datasheets/cr.pdf"
			(at 0 0 90)
			(layer "F.Fab")
			(hide yes)
			(effects
				(font
					(size 1.27 1.27)
					(thickness 0.15)
				)
			)
		)
		(property "Manufacturer" "Bourns"
			(at 0 0 90)
			(unlocked yes)
			(layer "F.Fab")
			(hide yes)
			(effects
				(font
					(size 1 1)
					(thickness 0.15)
				)
			)
		)
		(property "MPN" "CR0402-FX-3300GLF"
			(at 0 0 90)
			(unlocked yes)
			(layer "F.Fab")
			(hide yes)
			(effects
				(font
					(size 1 1)
					(thickness 0.15)
				)
			)
		)
		(property "Val" "330R"
			(at 0 0 90)
			(unlocked yes)
			(layer "F.Fab")
			(hide yes)
			(effects
				(font
					(size 1 1)
					(thickness 0.15)
				)
			)
		)
		(property "License" "Apache-2.0"
			(at 0 0 90)
			(unlocked yes)
			(layer "F.Fab")
			(hide yes)
			(effects
				(font
					(size 1 1)
					(thickness 0.15)
				)
			)
		)
		(property "Author" "Antmicro"
			(at 0 0 90)
			(unlocked yes)
			(layer "F.Fab")
			(hide yes)
			(effects
				(font
					(size 1 1)
					(thickness 0.15)
				)
			)
		)
		(property "Tolerance" "1%"
			(at 0 0 90)
			(unlocked yes)
			(layer "F.Fab")
			(hide yes)
			(effects
				(font
					(size 1 1)
					(thickness 0.15)
				)
			)
		)
		(sheetname "/Debug FTDI + VNA/")
		(sheetfile "debug-ftdi.kicad_sch")
		(attr smd)
		(fp_rect
			(start -0.925 -0.47)
			(end 0.925 0.47)
			(stroke
				(width 0.05)
				(type default)
			)
			(fill no)
			(layer "F.CrtYd")
		)
		(fp_rect
			(start -0.5 -0.25)
			(end 0.5 0.25)
			(stroke
				(width 0.15)
				(type solid)
			)
			(fill no)
			(layer "F.Fab")
		)
		(fp_text user "Author: Antmicro"
			(at -0.95 4.169 90)
			(layer "F.Fab")
			(effects
				(font
					(size 0.7 0.7)
					(thickness 0.15)
				)
				(justify left bottom)
			)
		)
		(fp_text user "${REFERENCE}"
			(at -0.95 3.168 90)
			(layer "F.Fab")
			(effects
				(font
					(size 0.7 0.7)
					(thickness 0.15)
				)
				(justify left bottom)
			)
		)
		(fp_text user "License: Apache-2.0"
			(at -0.95 5.169 90)
			(layer "F.Fab")
			(effects
				(font
					(size 0.7 0.7)
					(thickness 0.15)
				)
				(justify left bottom)
			)
		)
		(pad "1" smd roundrect
			(at -0.48 0 90)
			(size 0.59 0.64)
			(layers "F.Cu" "F.Mask" "F.Paste")
			(roundrect_rratio 0.25)
			(net 1 "GND")
			(pintype "passive")
		)
		(pad "2" smd roundrect
			(at 0.48 0 90)
			(size 0.59 0.64)
			(layers "F.Cu" "F.Mask" "F.Paste")
			(roundrect_rratio 0.25)
			(net 321 "Net-(C133-Pad1)")
			(pintype "passive")
		)
	)
	(footprint "antmicro-footprints:C_0402_1005Metric"
		(layer "F.Cu")
		(at 150.375499 171.167 90)
		(descr "Capacitor SMD 0402")
		(tags "capacitor SMD 0402")
		(property "Reference" "C131"
			(at -1.213 1.954501 90)
			(layer "F.SilkS")
			(effects
				(font
					(size 0.7 0.7)
					(thickness 0.15)
				)
				(justify left bottom)
			)
		)
		(property "Value" "C_100n_0402"
			(at -1.022927 2.155213 90)
			(layer "F.Fab")
			(effects
				(font
					(size 0.7 0.7)
					(thickness 0.15)
				)
				(justify left bottom)
			)
		)
		(property "Datasheet" "https://www.murata.com/products/productdetail?partno=GRM155R61H104KE14%23"
			(at 0 0 90)
			(layer "F.Fab")
			(hide yes)
			(effects
				(font
					(size 1.27 1.27)
					(thickness 0.15)
				)
			)
		)
		(property "MPN" "GRM155R61H104KE14D"
			(at 0 0 90)
			(unlocked yes)
			(layer "F.Fab")
			(hide yes)
			(effects
				(font
					(size 1 1)
					(thickness 0.15)
				)
			)
		)
		(property "Manufacturer" "Murata"
			(at 0 0 90)
			(unlocked yes)
			(layer "F.Fab")
			(hide yes)
			(effects
				(font
					(size 1 1)
					(thickness 0.15)
				)
			)
		)
		(property "License" "Apache-2.0"
			(at 0 0 90)
			(unlocked yes)
			(layer "F.Fab")
			(hide yes)
			(effects
				(font
					(size 1 1)
					(thickness 0.15)
				)
			)
		)
		(property "Author" "Antmicro"
			(at 0 0 90)
			(unlocked yes)
			(layer "F.Fab")
			(hide yes)
			(effects
				(font
					(size 1 1)
					(thickness 0.15)
				)
			)
		)
		(property "Val" "100n"
			(at 0 0 90)
			(unlocked yes)
			(layer "F.Fab")
			(hide yes)
			(effects
				(font
					(size 1 1)
					(thickness 0.15)
				)
			)
		)
		(property "Voltage" "50V"
			(at 0 0 90)
			(unlocked yes)
			(layer "F.Fab")
			(hide yes)
			(effects
				(font
					(size 1 1)
					(thickness 0.15)
				)
			)
		)
		(property "Dielectric" "X5R"
			(at 0 0 90)
			(unlocked yes)
			(layer "F.Fab")
			(hide yes)
			(effects
				(font
					(size 1 1)
					(thickness 0.15)
				)
			)
		)
		(sheetname "/Debug FTDI + VNA/")
		(sheetfile "debug-ftdi.kicad_sch")
		(attr smd)
		(fp_rect
			(start -0.925 -0.47)
			(end 0.925 0.47)
			(stroke
				(width 0.05)
				(type default)
			)
			(fill no)
			(layer "F.CrtYd")
		)
		(fp_line
			(start 0.504 -0.25)
			(end 0.504 0.248)
			(stroke
				(width 0.15)
				(type solid)
			)
			(layer "F.Fab")
		)
		(fp_line
			(start -0.494 -0.25)
			(end 0.504 -0.25)
			(stroke
				(width 0.15)
				(type solid)
			)
			(layer "F.Fab")
		)
		(fp_line
			(start 0.504 0.248)
			(end -0.494 0.248)
			(stroke
				(width 0.15)
				(type solid)
			)
			(layer "F.Fab")
		)
		(fp_line
			(start -0.494 0.248)
			(end -0.494 -0.25)
			(stroke
				(width 0.15)
				(type solid)
			)
			(layer "F.Fab")
		)
		(fp_text user "License: Apache-2.0"
			(at -0.939 5.799 90)
			(layer "F.Fab")
			(effects
				(font
					(size 0.7 0.7)
					(thickness 0.15)
				)
				(justify left bottom)
			)
		)
		(fp_text user "${REFERENCE}"
			(at -0.939 4.599 90)
			(layer "F.Fab")
			(effects
				(font
					(size 0.7 0.7)
					(thickness 0.15)
				)
				(justify left bottom)
			)
		)
		(fp_text user "Author: Antmicro"
			(at -0.939 3.399 90)
			(layer "F.Fab")
			(effects
				(font
					(size 0.7 0.7)
					(thickness 0.15)
				)
				(justify left bottom)
			)
		)
		(pad "1" smd roundrect
			(at -0.48 0 90)
			(size 0.59 0.64)
			(layers "F.Cu" "F.Mask" "F.Paste")
			(roundrect_rratio 0.25)
			(net 1 "GND")
			(pintype "passive")
		)
		(pad "2" smd roundrect
			(at 0.48 0 90)
			(size 0.59 0.64)
			(layers "F.Cu" "F.Mask" "F.Paste")
			(roundrect_rratio 0.25)
			(net 38 "+3V3_AON")
			(pintype "passive")
		)
	)
	(footprint "antmicro-footprints:TP_SMD_1mm"
		(layer "F.Cu")
		(at 244.025 153.025)
		(property "Reference" "TP13"
			(at 0 -0.731898 0)
			(layer "F.SilkS")
			(hide yes)
			(effects
				(font
					(size 0.7 0.7)
					(thickness 0.15)
				)
				(justify left bottom)
			)
		)
		(property "Value" "TP_1mm_SMD"
			(at 0 1.4 0)
			(layer "F.Fab")
			(effects
				(font
					(size 0.7 0.7)
					(thickness 0.15)
				)
				(justify left bottom)
			)
		)
		(property "MPN" ""
			(at 0 0 0)
			(unlocked yes)
			(layer "F.Fab")
			(hide yes)
			(effects
				(font
					(size 1 1)
					(thickness 0.15)
				)
			)
		)
		(property "Manufacturer" ""
			(at 0 0 0)
			(unlocked yes)
			(layer "F.Fab")
			(hide yes)
			(effects
				(font
					(size 1 1)
					(thickness 0.15)
				)
			)
		)
		(property "Author" "Antmicro"
			(at 0 0 0)
			(unlocked yes)
			(layer "F.Fab")
			(hide yes)
			(effects
				(font
					(size 1 1)
					(thickness 0.15)
				)
			)
		)
		(property "License" "Apache-2.0"
			(at 0 0 0)
			(unlocked yes)
			(layer "F.Fab")
			(hide yes)
			(effects
				(font
					(size 1 1)
					(thickness 0.15)
				)
			)
		)
		(sheetname "/Supply/DC-DC IO/")
		(sheetfile "dc-dc-io.kicad_sch")
		(attr exclude_from_pos_files)
		(fp_circle
			(center 0 0)
			(end 0.6 0)
			(stroke
				(width 0.05)
				(type default)
			)
			(fill no)
			(layer "F.CrtYd")
		)
		(fp_text user "${REFERENCE}"
			(at -0.5 2.8 0)
			(layer "F.Fab")
			(effects
				(font
					(size 0.7 0.7)
					(thickness 0.15)
				)
				(justify left bottom)
			)
		)
		(fp_text user "License: Apache-2.0"
			(at -0.5 5.2 0)
			(layer "F.Fab")
			(effects
				(font
					(size 0.7 0.7)
					(thickness 0.15)
				)
				(justify left bottom)
			)
		)
		(fp_text user "Author: Antmicro"
			(at -0.5 4 0)
			(layer "F.Fab")
			(effects
				(font
					(size 0.7 0.7)
					(thickness 0.15)
				)
				(justify left bottom)
			)
		)
		(pad "1" smd circle
			(at 0 0)
			(size 1 1)
			(layers "F.Cu" "F.Mask")
			(net 152 "+5V")
			(pinfunction "1")
			(pintype "passive")
		)
	)
	(footprint "antmicro-footprints:SC70-3"
		(layer "F.Cu")
		(at 250.274499 140.6)
		(property "Reference" "Q10"
			(at 0.505501 1.11 90)
			(layer "F.SilkS")
			(effects
				(font
					(size 0.7 0.7)
					(thickness 0.15)
				)
				(justify left bottom)
			)
		)
		(property "Value" "BSS138PW"
			(at 0 2.3 0)
			(layer "F.Fab")
			(effects
				(font
					(size 0.7 0.7)
					(thickness 0.15)
				)
				(justify left bottom)
			)
		)
		(property "Datasheet" "https://assets.nexperia.com/documents/data-sheet/BSS138PW.pdf"
			(at 0 0 0)
			(layer "F.Fab")
			(hide yes)
			(effects
				(font
					(size 1.27 1.27)
					(thickness 0.15)
				)
			)
		)
		(property "MPN" "BSS138PW"
			(at 0 0 0)
			(unlocked yes)
			(layer "F.Fab")
			(hide yes)
			(effects
				(font
					(size 1 1)
					(thickness 0.15)
				)
			)
		)
		(property "Manufacturer" "Nexperia"
			(at 0 0 0)
			(unlocked yes)
			(layer "F.Fab")
			(hide yes)
			(effects
				(font
					(size 1 1)
					(thickness 0.15)
				)
			)
		)
		(property "Author" "Antmicro"
			(at 0 0 0)
			(unlocked yes)
			(layer "F.Fab")
			(hide yes)
			(effects
				(font
					(size 1 1)
					(thickness 0.15)
				)
			)
		)
		(property "License" "Apache-2.0"
			(at 0 0 0)
			(unlocked yes)
			(layer "F.Fab")
			(hide yes)
			(effects
				(font
					(size 1 1)
					(thickness 0.15)
				)
			)
		)
		(sheetname "/DDR5 RDIMM/")
		(sheetfile "ddr5-rdimm.kicad_sch")
		(attr smd)
		(fp_line
			(start -0.3 -1)
			(end 0.627 -0.999)
			(stroke
				(width 0.15)
				(type solid)
			)
			(layer "F.SilkS")
		)
		(fp_line
			(start -0.3 1)
			(end 0.627 1.001)
			(stroke
				(width 0.15)
				(type solid)
			)
			(layer "F.SilkS")
		)
		(fp_line
			(start 0.627 -0.6)
			(end 0.627 -0.999)
			(stroke
				(width 0.15)
				(type solid)
			)
			(layer "F.SilkS")
		)
		(fp_line
			(start 0.627 0.6)
			(end 0.627 1.001)
			(stroke
				(width 0.15)
				(type solid)
			)
			(layer "F.SilkS")
		)
		(fp_line
			(start -1.4 1)
			(end -1.4 -1)
			(stroke
				(width 0.05)
				(type solid)
			)
			(layer "F.CrtYd")
		)
		(fp_line
			(start -0.9 -1.3)
			(end -0.9 -1)
			(stroke
				(width 0.05)
				(type solid)
			)
			(layer "F.CrtYd")
		)
		(fp_line
			(start -0.9 -1.3)
			(end 0.9 -1.3)
			(stroke
				(width 0.05)
				(type solid)
			)
			(layer "F.CrtYd")
		)
		(fp_line
			(start -0.9 -1)
			(end -1.4 -1)
			(stroke
				(width 0.05)
				(type solid)
			)
			(layer "F.CrtYd")
		)
		(fp_line
			(start -0.9 1)
			(end -1.4 1)
			(stroke
				(width 0.05)
				(type solid)
			)
			(layer "F.CrtYd")
		)
		(fp_line
			(start -0.9 1.3)
			(end -0.9 1)
			(stroke
				(width 0.05)
				(type solid)
			)
			(layer "F.CrtYd")
		)
		(fp_line
			(start 0.9 -1.3)
			(end 0.9 -0.4)
			(stroke
				(width 0.05)
				(type solid)
			)
			(layer "F.CrtYd")
		)
		(fp_line
			(start 0.9 -0.4)
			(end 1.4 -0.4)
			(stroke
				(width 0.05)
				(type solid)
			)
			(layer "F.CrtYd")
		)
		(fp_line
			(start 0.9 0.4)
			(end 0.9 1.3)
			(stroke
				(width 0.05)
				(type solid)
			)
			(layer "F.CrtYd")
		)
		(fp_line
			(start 0.9 1.3)
			(end -0.9 1.3)
			(stroke
				(width 0.05)
				(type solid)
			)
			(layer "F.CrtYd")
		)
		(fp_line
			(start 1.4 -0.4)
			(end 1.4 0.4)
			(stroke
				(width 0.05)
				(type solid)
			)
			(layer "F.CrtYd")
		)
		(fp_line
			(start 1.4 0.4)
			(end 0.9 0.4)
			(stroke
				(width 0.05)
				(type solid)
			)
			(layer "F.CrtYd")
		)
		(fp_rect
			(start -0.623 -0.999)
			(end 0.627 1.001)
			(stroke
				(width 0.15)
				(type solid)
			)
			(fill no)
			(layer "F.Fab")
		)
		(fp_text user "License: Apache-2.0"
			(at -1.45 6.782 0)
			(layer "F.Fab")
			(effects
				(font
					(size 0.7 0.7)
					(thickness 0.15)
				)
				(justify left bottom)
			)
		)
		(fp_text user "Author: Antmicro"
			(at -1.45 5.782 0)
			(layer "F.Fab")
			(effects
				(font
					(size 0.7 0.7)
					(thickness 0.15)
				)
				(justify left bottom)
			)
		)
		(fp_text user "${REFERENCE}"
			(at -1.45 4.783 0)
			(layer "F.Fab")
			(effects
				(font
					(size 0.7 0.7)
					(thickness 0.15)
				)
				(justify left bottom)
			)
		)
		(pad "1" smd rect
			(at -1.051 -0.65 90)
			(size 0.6 0.6)
			(layers "F.Cu" "F.Mask" "F.Paste")
			(net 180 "HOT_SWAP_GREEN")
			(pinfunction "G")
			(pintype "passive")
		)
		(pad "2" smd rect
			(at -1.051 0.65 90)
			(size 0.6 0.6)
			(layers "F.Cu" "F.Mask" "F.Paste")
			(net 1 "GND")
			(pinfunction "S")
			(pintype "passive")
		)
		(pad "3" smd rect
			(at 1.05 0 90)
			(size 0.6 0.6)
			(layers "F.Cu" "F.Mask" "F.Paste")
			(net 278 "Net-(Q10-D)")
			(pinfunction "D")
			(pintype "passive")
		)
	)
	(footprint "antmicro-footprints:NetTie-2_SMD_Pad0.127mm"
		(layer "F.Cu")
		(at 257.174 179.775)
		(descr "Net tie, 2 pin, 0.127mm  SMD pads")
		(tags "net tie")
		(property "Reference" "NT4"
			(at -0.128 -1.345 0)
			(layer "F.SilkS")
			(hide yes)
			(effects
				(font
					(size 0.7 0.7)
					(thickness 0.15)
				)
				(justify left bottom)
			)
		)
		(property "Value" "Net-Tie_P0.127mm"
			(at 0 1.199 0)
			(layer "F.Fab")
			(effects
				(font
					(size 0.7 0.7)
					(thickness 0.15)
				)
				(justify left bottom)
			)
		)
		(property "MPN" ""
			(at 0 0 0)
			(unlocked yes)
			(layer "F.Fab")
			(hide yes)
			(effects
				(font
					(size 1 1)
					(thickness 0.15)
				)
			)
		)
		(property "Manufacturer" ""
			(at 0 0 0)
			(unlocked yes)
			(layer "F.Fab")
			(hide yes)
			(effects
				(font
					(size 1 1)
					(thickness 0.15)
				)
			)
		)
		(property "Author" "Antmicro"
			(at 0 0 0)
			(unlocked yes)
			(layer "F.Fab")
			(hide yes)
			(effects
				(font
					(size 1 1)
					(thickness 0.15)
				)
			)
		)
		(property "License" "Apache-2.0"
			(at 0 0 0)
			(unlocked yes)
			(layer "F.Fab")
			(hide yes)
			(effects
				(font
					(size 1 1)
					(thickness 0.15)
				)
			)
		)
		(property ki_fp_filters "Net*Tie*")
		(sheetname "/Supply/DC-DC AUX, MGT/")
		(sheetfile "dc-dc-aux-mgt.kicad_sch")
		(attr through_hole exclude_from_pos_files exclude_from_bom)
		(net_tie_pad_groups "1, 2")
		(fp_poly
			(pts
				(xy -0.0635 -0.0635) (xy 0.0625 -0.0635) (xy 0.0625 0.0635) (xy -0.0635 0.0635)
			)
			(stroke
				(width 0)
				(type solid)
			)
			(fill yes)
			(layer "F.Cu")
		)
		(fp_poly
			(pts
				(xy 0.2 -0.16) (xy 0.29 -0.07) (xy 0.29 0.07) (xy 0.2 0.16) (xy -0.2 0.16) (xy -0.29 0.07) (xy -0.29 -0.06)
				(xy -0.19 -0.16)
			)
			(stroke
				(width 0.05)
				(type solid)
			)
			(fill no)
			(layer "F.CrtYd")
		)
		(fp_text user "${REFERENCE}"
			(at -0.128 3.2 0)
			(layer "F.Fab")
			(effects
				(font
					(size 0.7 0.7)
					(thickness 0.15)
				)
				(justify left bottom)
			)
		)
		(fp_text user "License: Apache-2.0"
			(at -0.128 5.6 0)
			(layer "F.Fab")
			(effects
				(font
					(size 0.7 0.7)
					(thickness 0.15)
				)
				(justify left bottom)
			)
		)
		(fp_text user "Author: Antmicro"
			(at -0.128 4.4 0)
			(layer "F.Fab")
			(effects
				(font
					(size 0.7 0.7)
					(thickness 0.15)
				)
				(justify left bottom)
			)
		)
		(pad "1" smd roundrect
			(at -0.127 0 180)
			(size 0.127 0.127)
			(layers "F.Cu")
			(roundrect_rratio 0.5)
			(chamfer_ratio 0)
			(chamfer top_left bottom_left)
			(net 684 "/Supply/DC-DC AUX, MGT/MGTAVCCAUX_SEN_+")
			(pinfunction "1")
			(pintype "passive")
		)
		(pad "2" smd roundrect
			(at 0.126 0)
			(size 0.127 0.127)
			(layers "F.Cu")
			(roundrect_rratio 0.5)
			(chamfer_ratio 0)
			(chamfer top_left bottom_left)
			(net 225 "/Supply/DC-DC AUX, MGT/MGTAVCCAUX_local")
			(pinfunction "2")
			(pintype "passive")
		)
	)
	(footprint "antmicro-footprints:R_0402_1005Metric"
		(layer "F.Cu")
		(at 121.1 162.15 180)
		(descr "Resistor SMD 0402")
		(tags "resistor SMD 0402")
		(property "Reference" "R80"
			(at 0.9 -1.05 0)
			(layer "F.SilkS")
			(effects
				(font
					(size 0.7 0.7)
					(thickness 0.15)
				)
				(justify right bottom)
			)
		)
		(property "Value" "R_10k_0402"
			(at -1.011843 1.772047 0)
			(layer "F.Fab")
			(effects
				(font
					(size 0.7 0.7)
					(thickness 0.15)
				)
				(justify right bottom)
			)
		)
		(property "Datasheet" "https://www.bourns.com/docs/product-datasheets/cr.pdf"
			(at 0 0 180)
			(layer "F.Fab")
			(hide yes)
			(effects
				(font
					(size 1.27 1.27)
					(thickness 0.15)
				)
			)
		)
		(property "MPN" "CR0402-FX-1002GLF"
			(at 0 0 180)
			(unlocked yes)
			(layer "F.Fab")
			(hide yes)
			(effects
				(font
					(size 1 1)
					(thickness 0.15)
				)
			)
		)
		(property "Manufacturer" "Bourns"
			(at 0 0 180)
			(unlocked yes)
			(layer "F.Fab")
			(hide yes)
			(effects
				(font
					(size 1 1)
					(thickness 0.15)
				)
			)
		)
		(property "License" "Apache-2.0"
			(at 0 0 180)
			(unlocked yes)
			(layer "F.Fab")
			(hide yes)
			(effects
				(font
					(size 1 1)
					(thickness 0.15)
				)
			)
		)
		(property "Author" "Antmicro"
			(at 0 0 180)
			(unlocked yes)
			(layer "F.Fab")
			(hide yes)
			(effects
				(font
					(size 1 1)
					(thickness 0.15)
				)
			)
		)
		(property "Val" "10k"
			(at 0 0 180)
			(unlocked yes)
			(layer "F.Fab")
			(hide yes)
			(effects
				(font
					(size 1 1)
					(thickness 0.15)
				)
			)
		)
		(property "Tolerance" "1%"
			(at 0 0 180)
			(unlocked yes)
			(layer "F.Fab")
			(hide yes)
			(effects
				(font
					(size 1 1)
					(thickness 0.15)
				)
			)
		)
		(sheetname "/HDMI + SD Card/")
		(sheetfile "hdmi-sd-card.kicad_sch")
		(attr smd)
		(fp_rect
			(start -0.925 -0.47)
			(end 0.925 0.47)
			(stroke
				(width 0.05)
				(type default)
			)
			(fill no)
			(layer "F.CrtYd")
		)
		(fp_rect
			(start -0.5 -0.25)
			(end 0.5 0.25)
			(stroke
				(width 0.15)
				(type solid)
			)
			(fill no)
			(layer "F.Fab")
		)
		(fp_text user "License: Apache-2.0"
			(at -0.95 5.169 180)
			(layer "F.Fab")
			(effects
				(font
					(size 0.7 0.7)
					(thickness 0.15)
				)
				(justify left bottom)
			)
		)
		(fp_text user "Author: Antmicro"
			(at -0.95 4.169 180)
			(layer "F.Fab")
			(effects
				(font
					(size 0.7 0.7)
					(thickness 0.15)
				)
				(justify left bottom)
			)
		)
		(fp_text user "${REFERENCE}"
			(at -0.95 3.168 180)
			(layer "F.Fab")
			(effects
				(font
					(size 0.7 0.7)
					(thickness 0.15)
				)
				(justify left bottom)
			)
		)
		(pad "1" smd roundrect
			(at -0.48 0 180)
			(size 0.59 0.64)
			(layers "F.Cu" "F.Mask" "F.Paste")
			(roundrect_rratio 0.25)
			(net 663 "Net-(U43-ST)")
			(pintype "passive")
		)
		(pad "2" smd roundrect
			(at 0.48 0 180)
			(size 0.59 0.64)
			(layers "F.Cu" "F.Mask" "F.Paste")
			(roundrect_rratio 0.25)
			(net 797 "+1V8")
			(pintype "passive")
		)
	)
	(footprint "antmicro-footprints:USB-C_Receptacle_GCT_USB4105-GF-A"
		(layer "F.Cu")
		(at 102.825 143.765 -90)
		(property "Reference" "J3"
			(at 6.084 2.600501 0)
			(layer "F.SilkS")
			(effects
				(font
					(size 0.7 0.7)
					(thickness 0.15)
				)
				(justify left bottom)
			)
		)
		(property "Value" "USB-C_GCT_USB4105-GF-A"
			(at 0 5 90)
			(layer "F.Fab")
			(effects
				(font
					(size 0.7 0.7)
					(thickness 0.15)
				)
				(justify right bottom)
			)
		)
		(property "Datasheet" "https://gct.co/files/drawings/usb4105.pdf"
			(at 0 0 270)
			(layer "F.Fab")
			(hide yes)
			(effects
				(font
					(size 1.27 1.27)
					(thickness 0.15)
				)
			)
		)
		(property "Manufacturer" "GCT"
			(at 0 0 270)
			(unlocked yes)
			(layer "F.Fab")
			(hide yes)
			(effects
				(font
					(size 1 1)
					(thickness 0.15)
				)
			)
		)
		(property "MPN" "USB4105-GF-A"
			(at 0 0 270)
			(unlocked yes)
			(layer "F.Fab")
			(hide yes)
			(effects
				(font
					(size 1 1)
					(thickness 0.15)
				)
			)
		)
		(property "Author" "Antmicro"
			(at 0 0 270)
			(unlocked yes)
			(layer "F.Fab")
			(hide yes)
			(effects
				(font
					(size 1 1)
					(thickness 0.15)
				)
			)
		)
		(property "License" "Apache-2.0"
			(at 0 0 270)
			(unlocked yes)
			(layer "F.Fab")
			(hide yes)
			(effects
				(font
					(size 1 1)
					(thickness 0.15)
				)
			)
		)
		(sheetname "/Debug FTDI + VNA/")
		(sheetfile "debug-ftdi.kicad_sch")
		(attr smd)
		(fp_line
			(start -4.79 3.854)
			(end 4.788 3.854)
			(stroke
				(width 0.15)
				(type solid)
			)
			(layer "F.SilkS")
		)
		(fp_line
			(start 4.788 3.854)
			(end 4.788 2.575)
			(stroke
				(width 0.15)
				(type solid)
			)
			(layer "F.SilkS")
		)
		(fp_line
			(start -4.79 2.575)
			(end -4.79 3.854)
			(stroke
				(width 0.15)
				(type solid)
			)
			(layer "F.SilkS")
		)
		(fp_line
			(start -4.79 -1.395)
			(end -4.79 -0.145)
			(stroke
				(width 0.15)
				(type solid)
			)
			(layer "F.SilkS")
		)
		(fp_line
			(start 4.788 -1.395)
			(end 4.788 -0.145)
			(stroke
				(width 0.15)
				(type solid)
			)
			(layer "F.SilkS")
		)
		(fp_circle
			(center -3.8 -4.27071)
			(end -3.75 -4.22071)
			(stroke
				(width 0.15)
				(type solid)
			)
			(fill yes)
			(layer "F.SilkS")
		)
		(fp_rect
			(start -5.1 -4.4)
			(end 5.1 3.9)
			(stroke
				(width 0.05)
				(type solid)
			)
			(fill no)
			(layer "F.CrtYd")
		)
		(fp_line
			(start -4.79 3.854)
			(end -4.79 -3.676)
			(stroke
				(width 0.15)
				(type solid)
			)
			(layer "F.Fab")
		)
		(fp_line
			(start -4.702 3.854)
			(end 4.788 3.854)
			(stroke
				(width 0.15)
				(type solid)
			)
			(layer "F.Fab")
		)
		(fp_line
			(start 4.788 3.854)
			(end -4.79 3.854)
			(stroke
				(width 0.15)
				(type solid)
			)
			(layer "F.Fab")
		)
		(fp_line
			(start -4.79 -3.676)
			(end 4.788 -3.676)
			(stroke
				(width 0.15)
				(type solid)
			)
			(layer "F.Fab")
		)
		(fp_line
			(start 4.788 -3.676)
			(end 4.788 3.854)
			(stroke
				(width 0.15)
				(type solid)
			)
			(layer "F.Fab")
		)
		(fp_text user "${REFERENCE}"
			(at -4.79 6.853 270)
			(layer "F.Fab")
			(effects
				(font
					(size 0.7 0.7)
					(thickness 0.15)
				)
				(justify left bottom)
			)
		)
		(fp_text user "Author: Antmicro"
			(at -4.79 7.853 270)
			(layer "F.Fab")
			(effects
				(font
					(size 0.7 0.7)
					(thickness 0.15)
				)
				(justify left bottom)
			)
		)
		(fp_text user "PCB-EDGE"
			(at -4.79 5.853 270)
			(layer "F.Fab")
			(effects
				(font
					(size 0.7 0.7)
					(thickness 0.15)
				)
				(justify left bottom)
			)
		)
		(fp_text user "License: Apache-2.0"
			(at -4.79 8.855 270)
			(layer "F.Fab")
			(effects
				(font
					(size 0.7 0.7)
					(thickness 0.15)
				)
				(justify left bottom)
			)
		)
		(pad "" np_thru_hole circle
			(at -2.891 -2.426 270)
			(size 0.65 0.65)
			(drill 0.65)
			(layers "*.Cu" "*.Mask")
		)
		(pad "" np_thru_hole circle
			(at 2.89 -2.426 270)
			(size 0.65 0.65)
			(drill 0.65)
			(layers "*.Cu" "*.Mask")
		)
		(pad "A1" smd roundrect
			(at -3.202 -3.5 270)
			(size 0.6 1.15)
			(layers "F.Cu" "F.Mask" "F.Paste")
			(roundrect_rratio 0.25)
			(net 1 "GND")
			(pinfunction "GND")
			(pintype "power_in")
		)
		(pad "A4" smd roundrect
			(at -2.4 -3.5 270)
			(size 0.6 1.15)
			(layers "F.Cu" "F.Mask" "F.Paste")
			(roundrect_rratio 0.25)
			(net 2 "/Debug FTDI + VNA/VBUS")
			(pinfunction "VBUS")
			(pintype "passive")
		)
		(pad "A5" smd roundrect
			(at -1.25 -3.5 270)
			(size 0.3 1.15)
			(layers "F.Cu" "F.Mask" "F.Paste")
			(roundrect_rratio 0.25)
			(net 363 "/Debug FTDI + VNA/CC1")
			(pinfunction "CC_{1}")
			(pintype "bidirectional")
		)
		(pad "A6" smd roundrect
			(at -0.25 -3.5 270)
			(size 0.3 1.15)
			(layers "F.Cu" "F.Mask" "F.Paste")
			(roundrect_rratio 0.25)
			(net 364 "/Debug FTDI + VNA/DBG_USB_P")
			(pinfunction "D_{A}+")
			(pintype "bidirectional")
		)
		(pad "A7" smd roundrect
			(at 0.248 -3.5 270)
			(size 0.3 1.15)
			(layers "F.Cu" "F.Mask" "F.Paste")
			(roundrect_rratio 0.25)
			(net 365 "/Debug FTDI + VNA/DBG_USB_N")
			(pinfunction "D_{A}-")
			(pintype "bidirectional")
		)
		(pad "A8" smd roundrect
			(at 1.249 -3.5 270)
			(size 0.3 1.15)
			(layers "F.Cu" "F.Mask" "F.Paste")
			(roundrect_rratio 0.25)
			(net 243 "unconnected-(J3-SBU_{1}-PadA8)")
			(pinfunction "SBU_{1}")
			(pintype "bidirectional+no_connect")
		)
		(pad "A9" smd roundrect
			(at 2.398 -3.5 270)
			(size 0.6 1.15)
			(layers "F.Cu" "F.Mask" "F.Paste")
			(roundrect_rratio 0.25)
			(net 2 "/Debug FTDI + VNA/VBUS")
			(pinfunction "VBUS")
			(pintype "passive")
		)
		(pad "A12" smd roundrect
			(at 3.2 -3.5 270)
			(size 0.6 1.15)
			(layers "F.Cu" "F.Mask" "F.Paste")
			(roundrect_rratio 0.25)
			(net 1 "GND")
			(pinfunction "GND")
			(pintype "passive")
		)
		(pad "B1" smd roundrect
			(at 3.2 -3.5 270)
			(size 0.6 1.15)
			(layers "F.Cu" "F.Mask" "F.Paste")
			(roundrect_rratio 0.25)
			(net 1 "GND")
			(pinfunction "GND")
			(pintype "passive")
		)
		(pad "B4" smd roundrect
			(at 2.398 -3.5 270)
			(size 0.6 1.15)
			(layers "F.Cu" "F.Mask" "F.Paste")
			(roundrect_rratio 0.25)
			(net 2 "/Debug FTDI + VNA/VBUS")
			(pinfunction "VBUS")
			(pintype "passive")
		)
		(pad "B5" smd roundrect
			(at 1.749 -3.5 270)
			(size 0.3 1.15)
			(layers "F.Cu" "F.Mask" "F.Paste")
			(roundrect_rratio 0.25)
			(net 366 "/Debug FTDI + VNA/CC2")
			(pinfunction "CC_{2}")
			(pintype "bidirectional")
		)
		(pad "B6" smd roundrect
			(at 0.748 -3.5 270)
			(size 0.3 1.15)
			(layers "F.Cu" "F.Mask" "F.Paste")
			(roundrect_rratio 0.25)
			(net 364 "/Debug FTDI + VNA/DBG_USB_P")
			(pinfunction "D_{B}+")
			(pintype "bidirectional")
		)
		(pad "B7" smd roundrect
			(at -0.75 -3.5 270)
			(size 0.3 1.15)
			(layers "F.Cu" "F.Mask" "F.Paste")
			(roundrect_rratio 0.25)
			(net 365 "/Debug FTDI + VNA/DBG_USB_N")
			(pinfunction "D_{B}-")
			(pintype "bidirectional")
		)
		(pad "B8" smd roundrect
			(at -1.75 -3.5 270)
			(size 0.3 1.15)
			(layers "F.Cu" "F.Mask" "F.Paste")
			(roundrect_rratio 0.25)
			(net 245 "unconnected-(J3-SBU_{2}-PadB8)")
			(pinfunction "SBU_{2}")
			(pintype "bidirectional+no_connect")
		)
		(pad "B9" smd roundrect
			(at -2.4 -3.5 270)
			(size 0.6 1.15)
			(layers "F.Cu" "F.Mask" "F.Paste")
			(roundrect_rratio 0.25)
			(net 2 "/Debug FTDI + VNA/VBUS")
			(pinfunction "VBUS")
			(pintype "passive")
		)
		(pad "B12" smd roundrect
			(at -3.202 -3.5 270)
			(size 0.6 1.15)
			(layers "F.Cu" "F.Mask" "F.Paste")
			(roundrect_rratio 0.25)
			(net 1 "GND")
			(pinfunction "GND")
			(pintype "passive")
		)
		(pad "SH" thru_hole oval
			(at -4.321 -2.926 270)
			(size 1.05 2.1)
			(drill oval 0.6 1.7)
			(layers "*.Cu" "*.Mask")
			(remove_unused_layers no)
			(net 321 "Net-(C133-Pad1)")
			(pinfunction "SH")
			(pintype "passive")
		)
		(pad "SH" thru_hole oval
			(at -4.321 1.255 270)
			(size 1 2)
			(drill oval 0.6 1.4)
			(layers "*.Cu" "*.Mask")
			(remove_unused_layers no)
			(net 321 "Net-(C133-Pad1)")
			(pinfunction "SH")
			(pintype "passive")
		)
		(pad "SH" thru_hole oval
			(at 4.32 -2.926 270)
			(size 1.05 2.1)
			(drill oval 0.6 1.7)
			(layers "*.Cu" "*.Mask")
			(remove_unused_layers no)
			(net 321 "Net-(C133-Pad1)")
			(pinfunction "SH")
			(pintype "passive")
		)
		(pad "SH" thru_hole oval
			(at 4.32 1.255 270)
			(size 1 2)
			(drill oval 0.6 1.4)
			(layers "*.Cu" "*.Mask")
			(remove_unused_layers no)
			(net 321 "Net-(C133-Pad1)")
			(pinfunction "SH")
			(pintype "passive")
		)
	)
	(footprint "antmicro-footprints:DHVQFN-14-1EP_2.5x3mm"
		(layer "F.Cu")
		(at 137.024499 170.149 -90)
		(property "Reference" "U7"
			(at 1.9 3.4 0)
			(layer "F.SilkS")
			(effects
				(font
					(size 0.7 0.7)
					(thickness 0.15)
				)
				(justify left bottom)
			)
		)
		(property "Value" "TXU0304BQAR"
			(at 0 2.898 90)
			(layer "F.Fab")
			(effects
				(font
					(size 0.7 0.7)
					(thickness 0.15)
				)
				(justify right bottom)
			)
		)
		(property "Datasheet" "https://www.ti.com/lit/ds/symlink/txu0304.pdf?ts=1637748643258&ref_url=https%253A%252F%252Fwww.ti.com%252Fproduct%252FTXU0304"
			(at 0 0 270)
			(layer "F.Fab")
			(hide yes)
			(effects
				(font
					(size 1.27 1.27)
					(thickness 0.15)
				)
			)
		)
		(property "MPN" "TXU0304BQAR"
			(at 0 0 270)
			(unlocked yes)
			(layer "F.Fab")
			(hide yes)
			(effects
				(font
					(size 1 1)
					(thickness 0.15)
				)
			)
		)
		(property "Manufacturer" "Texas Instruments"
			(at 0 0 270)
			(unlocked yes)
			(layer "F.Fab")
			(hide yes)
			(effects
				(font
					(size 1 1)
					(thickness 0.15)
				)
			)
		)
		(property "Author" "Antmicro"
			(at 0 0 270)
			(unlocked yes)
			(layer "F.Fab")
			(hide yes)
			(effects
				(font
					(size 1 1)
					(thickness 0.15)
				)
			)
		)
		(property "License" "Apache-2.0"
			(at 0 0 270)
			(unlocked yes)
			(layer "F.Fab")
			(hide yes)
			(effects
				(font
					(size 1 1)
					(thickness 0.15)
				)
			)
		)
		(sheetname "/Debug FTDI + VNA/")
		(sheetfile "debug-ftdi.kicad_sch")
		(attr smd)
		(fp_line
			(start -1.35 1.6)
			(end -0.5 1.6)
			(stroke
				(width 0.15)
				(type solid)
			)
			(layer "F.SilkS")
		)
		(fp_line
			(start -1.35 1.6)
			(end -1.35 1.25)
			(stroke
				(width 0.15)
				(type solid)
			)
			(layer "F.SilkS")
		)
		(fp_line
			(start 0.5 1.6)
			(end 1.35 1.6)
			(stroke
				(width 0.15)
				(type solid)
			)
			(layer "F.SilkS")
		)
		(fp_line
			(start 1.35 1.6)
			(end 1.35 1.25)
			(stroke
				(width 0.15)
				(type solid)
			)
			(layer "F.SilkS")
		)
		(fp_line
			(start -1.35 -1.6)
			(end -1.35 -1.25)
			(stroke
				(width 0.15)
				(type solid)
			)
			(layer "F.SilkS")
		)
		(fp_line
			(start -1.35 -1.6)
			(end -0.5 -1.6)
			(stroke
				(width 0.15)
				(type solid)
			)
			(layer "F.SilkS")
		)
		(fp_line
			(start 1.35 -1.6)
			(end 1.35 -1.25)
			(stroke
				(width 0.15)
				(type solid)
			)
			(layer "F.SilkS")
		)
		(fp_line
			(start 1.35 -1.6)
			(end 0.5 -1.6)
			(stroke
				(width 0.15)
				(type solid)
			)
			(layer "F.SilkS")
		)
		(fp_circle
			(center -0.7 -1.85)
			(end -0.65 -1.85)
			(stroke
				(width 0.15)
				(type solid)
			)
			(fill yes)
			(layer "F.SilkS")
		)
		(fp_rect
			(start -1.8 -2)
			(end 1.8 2)
			(stroke
				(width 0.05)
				(type solid)
			)
			(fill no)
			(layer "F.CrtYd")
		)
		(fp_line
			(start -1.25 1.499)
			(end -1.25 -1.25)
			(stroke
				(width 0.15)
				(type solid)
			)
			(layer "F.Fab")
		)
		(fp_line
			(start 1.249 1.499)
			(end -1.25 1.499)
			(stroke
				(width 0.15)
				(type solid)
			)
			(layer "F.Fab")
		)
		(fp_line
			(start -1.25 -1.25)
			(end -1 -1.5)
			(stroke
				(width 0.15)
				(type solid)
			)
			(layer "F.Fab")
		)
		(fp_line
			(start -1 -1.5)
			(end 1.249 -1.5)
			(stroke
				(width 0.15)
				(type solid)
			)
			(layer "F.Fab")
		)
		(fp_line
			(start 1.249 -1.5)
			(end 1.249 1.499)
			(stroke
				(width 0.15)
				(type solid)
			)
			(layer "F.Fab")
		)
		(fp_text user "${REFERENCE}"
			(at -1.841 4.897 270)
			(layer "F.Fab")
			(effects
				(font
					(size 0.7 0.7)
					(thickness 0.15)
				)
				(justify left bottom)
			)
		)
		(fp_text user "License: Apache-2.0"
			(at -1.841 6.097 270)
			(layer "F.Fab")
			(effects
				(font
					(size 0.7 0.7)
					(thickness 0.15)
				)
				(justify left bottom)
			)
		)
		(fp_text user "Author: Antmicro"
			(at -1.841 7.296 270)
			(layer "F.Fab")
			(effects
				(font
					(size 0.7 0.7)
					(thickness 0.15)
				)
				(justify left bottom)
			)
		)
		(pad "1" smd oval
			(at -0.25 -1.5 270)
			(size 0.3 0.8)
			(layers "F.Cu" "F.Mask" "F.Paste")
			(net 6 "/Debug FTDI + VNA/FTDI_3V3")
			(pinfunction "VCCA")
			(pintype "power_in")
		)
		(pad "2" smd oval
			(at -1.25 -1)
			(size 0.3 0.8)
			(layers "F.Cu" "F.Mask" "F.Paste")
			(net 788 "/Debug FTDI + VNA/FTDI_JTAG_TMS")
			(pinfunction "A1")
			(pintype "input")
		)
		(pad "3" smd oval
			(at -1.25 -0.5)
			(size 0.3 0.8)
			(layers "F.Cu" "F.Mask" "F.Paste")
			(net 781 "/Debug FTDI + VNA/FTDI_JTAG_TCK")
			(pinfunction "A2")
			(pintype "input")
		)
		(pad "4" smd oval
			(at -1.25 0)
			(size 0.3 0.8)
			(layers "F.Cu" "F.Mask" "F.Paste")
			(net 786 "/Debug FTDI + VNA/FTDI_JTAG_TDI")
			(pinfunction "A3")
			(pintype "input")
		)
		(pad "5" smd oval
			(at -1.25 0.5)
			(size 0.3 0.8)
			(layers "F.Cu" "F.Mask" "F.Paste")
			(net 787 "/Debug FTDI + VNA/FTDI_JTAG_TDO")
			(pinfunction "A4Y")
			(pintype "output")
		)
		(pad "6" smd oval
			(at -1.25 1)
			(size 0.3 0.8)
			(layers "F.Cu" "F.Mask" "F.Paste")
			(net 414 "unconnected-(U7-NC-Pad6)")
			(pinfunction "NC")
			(pintype "no_connect")
		)
		(pad "7" smd oval
			(at -0.25 1.5 270)
			(size 0.3 0.8)
			(layers "F.Cu" "F.Mask" "F.Paste")
			(net 1 "GND")
			(pinfunction "GND")
			(pintype "passive")
		)
		(pad "8" smd oval
			(at 0.25 1.5 270)
			(size 0.3 0.8)
			(layers "F.Cu" "F.Mask" "F.Paste")
			(net 197 "FTDI_DIS")
			(pinfunction "OE")
			(pintype "tri_state")
		)
		(pad "9" smd oval
			(at 1.25 1)
			(size 0.3 0.8)
			(layers "F.Cu" "F.Mask" "F.Paste")
			(net 415 "unconnected-(U7-NC-Pad9)")
			(pinfunction "NC")
			(pintype "no_connect")
		)
		(pad "10" smd oval
			(at 1.25 0.5)
			(size 0.3 0.8)
			(layers "F.Cu" "F.Mask" "F.Paste")
			(net 300 "Net-(U7-B4)")
			(pinfunction "B4")
			(pintype "input")
		)
		(pad "11" smd oval
			(at 1.25 0)
			(size 0.3 0.8)
			(layers "F.Cu" "F.Mask" "F.Paste")
			(net 299 "Net-(U7-B3Y)")
			(pinfunction "B3Y")
			(pintype "output")
		)
		(pad "12" smd oval
			(at 1.25 -0.5)
			(size 0.3 0.8)
			(layers "F.Cu" "F.Mask" "F.Paste")
			(net 298 "Net-(U7-B2Y)")
			(pinfunction "B2Y")
			(pintype "output")
		)
		(pad "13" smd oval
			(at 1.25 -1)
			(size 0.3 0.8)
			(layers "F.Cu" "F.Mask" "F.Paste")
			(net 296 "Net-(U7-B1Y)")
			(pinfunction "B1Y")
			(pintype "output")
		)
		(pad "14" smd oval
			(at 0.25 -1.5 270)
			(size 0.3 0.8)
			(layers "F.Cu" "F.Mask" "F.Paste")
			(net 797 "+1V8")
			(pinfunction "VCCB")
			(pintype "power_in")
		)
		(pad "15" smd rect
			(at 0 0 270)
			(size 1 1.5)
			(layers "F.Cu" "F.Mask" "F.Paste")
			(net 1 "GND")
			(pinfunction "GND")
			(pintype "power_in")
		)
	)
	(footprint "antmicro-footprints:R_0402_1005Metric"
		(layer "F.Cu")
		(at 134.124499 170.164 90)
		(descr "Resistor SMD 0402")
		(tags "resistor SMD 0402")
		(property "Reference" "R51"
			(at 0.839 0.425501 90)
			(layer "F.SilkS")
			(effects
				(font
					(size 0.7 0.7)
					(thickness 0.15)
				)
				(justify left bottom)
			)
		)
		(property "Value" "R_47k_0402"
			(at -1.011843 1.772047 90)
			(layer "F.Fab")
			(effects
				(font
					(size 0.7 0.7)
					(thickness 0.15)
				)
				(justify left bottom)
			)
		)
		(property "Datasheet" "https://www.bourns.com/docs/product-datasheets/cr.pdf"
			(at 0 0 90)
			(layer "F.Fab")
			(hide yes)
			(effects
				(font
					(size 1.27 1.27)
					(thickness 0.15)
				)
			)
		)
		(property "Manufacturer" "Bourns"
			(at 0 0 90)
			(unlocked yes)
			(layer "F.Fab")
			(hide yes)
			(effects
				(font
					(size 1 1)
					(thickness 0.15)
				)
			)
		)
		(property "MPN" "CR0402-FX-4702GLF"
			(at 0 0 90)
			(unlocked yes)
			(layer "F.Fab")
			(hide yes)
			(effects
				(font
					(size 1 1)
					(thickness 0.15)
				)
			)
		)
		(property "Val" "47k"
			(at 0 0 90)
			(unlocked yes)
			(layer "F.Fab")
			(hide yes)
			(effects
				(font
					(size 1 1)
					(thickness 0.15)
				)
			)
		)
		(property "License" "Apache-2.0"
			(at 0 0 90)
			(unlocked yes)
			(layer "F.Fab")
			(hide yes)
			(effects
				(font
					(size 1 1)
					(thickness 0.15)
				)
			)
		)
		(property "Author" "Antmicro"
			(at 0 0 90)
			(unlocked yes)
			(layer "F.Fab")
			(hide yes)
			(effects
				(font
					(size 1 1)
					(thickness 0.15)
				)
			)
		)
		(property "Tolerance" "1%"
			(at 0 0 90)
			(unlocked yes)
			(layer "F.Fab")
			(hide yes)
			(effects
				(font
					(size 1 1)
					(thickness 0.15)
				)
			)
		)
		(sheetname "/Debug FTDI + VNA/")
		(sheetfile "debug-ftdi.kicad_sch")
		(attr smd)
		(fp_rect
			(start -0.925 -0.47)
			(end 0.925 0.47)
			(stroke
				(width 0.05)
				(type default)
			)
			(fill no)
			(layer "F.CrtYd")
		)
		(fp_rect
			(start -0.5 -0.25)
			(end 0.5 0.25)
			(stroke
				(width 0.15)
				(type solid)
			)
			(fill no)
			(layer "F.Fab")
		)
		(fp_text user "Author: Antmicro"
			(at -0.95 4.169 90)
			(layer "F.Fab")
			(effects
				(font
					(size 0.7 0.7)
					(thickness 0.15)
				)
				(justify left bottom)
			)
		)
		(fp_text user "${REFERENCE}"
			(at -0.95 3.168 90)
			(layer "F.Fab")
			(effects
				(font
					(size 0.7 0.7)
					(thickness 0.15)
				)
				(justify left bottom)
			)
		)
		(fp_text user "License: Apache-2.0"
			(at -0.95 5.169 90)
			(layer "F.Fab")
			(effects
				(font
					(size 0.7 0.7)
					(thickness 0.15)
				)
				(justify left bottom)
			)
		)
		(pad "1" smd roundrect
			(at -0.48 0 90)
			(size 0.59 0.64)
			(layers "F.Cu" "F.Mask" "F.Paste")
			(roundrect_rratio 0.25)
			(net 197 "FTDI_DIS")
			(pintype "passive")
		)
		(pad "2" smd roundrect
			(at 0.48 0 90)
			(size 0.59 0.64)
			(layers "F.Cu" "F.Mask" "F.Paste")
			(roundrect_rratio 0.25)
			(net 797 "+1V8")
			(pintype "passive")
		)
	)
	(footprint "antmicro-footprints:R_0402_1005Metric"
		(layer "F.Cu")
		(at 254.02 177.6095 180)
		(descr "Resistor SMD 0402")
		(tags "resistor SMD 0402")
		(property "Reference" "R152"
			(at 0.57 -1.4905 0)
			(layer "F.SilkS")
			(effects
				(font
					(size 0.7 0.7)
					(thickness 0.15)
				)
				(justify right bottom)
			)
		)
		(property "Value" "R_0R_0402"
			(at -1.011843 1.772047 0)
			(layer "F.Fab")
			(effects
				(font
					(size 0.7 0.7)
					(thickness 0.15)
				)
				(justify right bottom)
			)
		)
		(property "Datasheet" "https://industrial.panasonic.com/cdbs/www-data/pdf/RDA0000/AOA0000C301.pdf"
			(at 0 0 180)
			(layer "F.Fab")
			(hide yes)
			(effects
				(font
					(size 1.27 1.27)
					(thickness 0.15)
				)
			)
		)
		(property "Manufacturer" "Panasonic"
			(at 0 0 180)
			(unlocked yes)
			(layer "F.Fab")
			(hide yes)
			(effects
				(font
					(size 1 1)
					(thickness 0.15)
				)
			)
		)
		(property "MPN" "ERJ2GE0R00X"
			(at 0 0 180)
			(unlocked yes)
			(layer "F.Fab")
			(hide yes)
			(effects
				(font
					(size 1 1)
					(thickness 0.15)
				)
			)
		)
		(property "Val" "0R"
			(at 0 0 180)
			(unlocked yes)
			(layer "F.Fab")
			(hide yes)
			(effects
				(font
					(size 1 1)
					(thickness 0.15)
				)
			)
		)
		(property "License" "Apache-2.0"
			(at 0 0 180)
			(unlocked yes)
			(layer "F.Fab")
			(hide yes)
			(effects
				(font
					(size 1 1)
					(thickness 0.15)
				)
			)
		)
		(property "Author" "Antmicro"
			(at 0 0 180)
			(unlocked yes)
			(layer "F.Fab")
			(hide yes)
			(effects
				(font
					(size 1 1)
					(thickness 0.15)
				)
			)
		)
		(property "Tolerance" "~"
			(at 0 0 180)
			(unlocked yes)
			(layer "F.Fab")
			(hide yes)
			(effects
				(font
					(size 1 1)
					(thickness 0.15)
				)
			)
		)
		(property "Current" "1A"
			(at 0 0 180)
			(unlocked yes)
			(layer "F.Fab")
			(hide yes)
			(effects
				(font
					(size 1 1)
					(thickness 0.15)
				)
			)
		)
		(sheetname "/Supply/DC-DC AUX, MGT/")
		(sheetfile "dc-dc-aux-mgt.kicad_sch")
		(attr smd)
		(fp_rect
			(start -0.925 -0.47)
			(end 0.925 0.47)
			(stroke
				(width 0.05)
				(type default)
			)
			(fill no)
			(layer "F.CrtYd")
		)
		(fp_rect
			(start -0.5 -0.25)
			(end 0.5 0.25)
			(stroke
				(width 0.15)
				(type solid)
			)
			(fill no)
			(layer "F.Fab")
		)
		(fp_text user "${REFERENCE}"
			(at -0.95 3.168 180)
			(layer "F.Fab")
			(effects
				(font
					(size 0.7 0.7)
					(thickness 0.15)
				)
				(justify left bottom)
			)
		)
		(fp_text user "License: Apache-2.0"
			(at -0.95 5.169 180)
			(layer "F.Fab")
			(effects
				(font
					(size 0.7 0.7)
					(thickness 0.15)
				)
				(justify left bottom)
			)
		)
		(fp_text user "Author: Antmicro"
			(at -0.95 4.169 180)
			(layer "F.Fab")
			(effects
				(font
					(size 0.7 0.7)
					(thickness 0.15)
				)
				(justify left bottom)
			)
		)
		(pad "1" smd roundrect
			(at -0.48 0 180)
			(size 0.59 0.64)
			(layers "F.Cu" "F.Mask" "F.Paste")
			(roundrect_rratio 0.25)
			(net 712 "/Supply/DC-DC AUX, MGT/FB1")
			(pintype "passive")
		)
		(pad "2" smd roundrect
			(at 0.48 0 180)
			(size 0.59 0.64)
			(layers "F.Cu" "F.Mask" "F.Paste")
			(roundrect_rratio 0.25)
			(net 37 "/Supply/DC-DC AUX, MGT/1V8_local")
			(pintype "passive")
		)
	)
	(footprint "antmicro-footprints:SOT-23-6"
		(layer "F.Cu")
		(at 242.447 126.6561 180)
		(property "Reference" "U17"
			(at 1.666258 1.3561 90)
			(layer "F.SilkS")
			(effects
				(font
					(size 0.7 0.7)
					(thickness 0.15)
				)
				(justify right bottom)
			)
		)
		(property "Value" "LTC4412IS6"
			(at -1.75 2.75 0)
			(layer "F.Fab")
			(effects
				(font
					(size 0.7 0.7)
					(thickness 0.15)
				)
				(justify right bottom)
			)
		)
		(property "Datasheet" "https://www.mouser.com/datasheet/2/308/NCV8187_D-1813214.pdf"
			(at 0 0 180)
			(layer "F.Fab")
			(hide yes)
			(effects
				(font
					(size 1.27 1.27)
					(thickness 0.15)
				)
			)
		)
		(property "MPN" "LTC4412IS6#TRMPBF"
			(at 0 0 180)
			(unlocked yes)
			(layer "F.Fab")
			(hide yes)
			(effects
				(font
					(size 1 1)
					(thickness 0.15)
				)
			)
		)
		(property "Manufacturer" "Analog Devices"
			(at 0 0 180)
			(unlocked yes)
			(layer "F.Fab")
			(hide yes)
			(effects
				(font
					(size 1 1)
					(thickness 0.15)
				)
			)
		)
		(property "Author" "Antmicro"
			(at 0 0 180)
			(unlocked yes)
			(layer "F.Fab")
			(hide yes)
			(effects
				(font
					(size 1 1)
					(thickness 0.15)
				)
			)
		)
		(property "License" "Apache-2.0"
			(at 0 0 180)
			(unlocked yes)
			(layer "F.Fab")
			(hide yes)
			(effects
				(font
					(size 1 1)
					(thickness 0.15)
				)
			)
		)
		(sheetname "/Supply/")
		(sheetfile "supply.kicad_sch")
		(attr smd)
		(fp_line
			(start 1.45 0.643)
			(end 1.45 0.343)
			(stroke
				(width 0.12)
				(type solid)
			)
			(layer "F.SilkS")
		)
		(fp_line
			(start 1.45 -0.757)
			(end 1.45 -0.457)
			(stroke
				(width 0.12)
				(type solid)
			)
			(layer "F.SilkS")
		)
		(fp_line
			(start 1.3 0.643)
			(end 1.45 0.643)
			(stroke
				(width 0.12)
				(type solid)
			)
			(layer "F.SilkS")
		)
		(fp_line
			(start 1.3 -0.757)
			(end 1.45 -0.757)
			(stroke
				(width 0.12)
				(type solid)
			)
			(layer "F.SilkS")
		)
		(fp_line
			(start -1.3 -0.757)
			(end -1.45 -0.757)
			(stroke
				(width 0.12)
				(type solid)
			)
			(layer "F.SilkS")
		)
		(fp_line
			(start -1.45 0.643)
			(end -1.45 0.343)
			(stroke
				(width 0.12)
				(type solid)
			)
			(layer "F.SilkS")
		)
		(fp_line
			(start -1.45 -0.757)
			(end -1.45 -0.457)
			(stroke
				(width 0.12)
				(type solid)
			)
			(layer "F.SilkS")
		)
		(fp_rect
			(start -1.55 -1.85)
			(end 1.55 1.75)
			(stroke
				(width 0.05)
				(type solid)
			)
			(fill no)
			(layer "F.CrtYd")
		)
		(fp_line
			(start 1.5 0.643)
			(end -1.5 0.643)
			(stroke
				(width 0.1)
				(type solid)
			)
			(layer "F.Fab")
		)
		(fp_line
			(start 1.5 -0.757)
			(end 1.5 0.643)
			(stroke
				(width 0.1)
				(type solid)
			)
			(layer "F.Fab")
		)
		(fp_line
			(start -1.5 0.643)
			(end -1.5 -0.757)
			(stroke
				(width 0.1)
				(type solid)
			)
			(layer "F.Fab")
		)
		(fp_line
			(start -1.5 -0.757)
			(end 1.5 -0.757)
			(stroke
				(width 0.1)
				(type solid)
			)
			(layer "F.Fab")
		)
		(fp_text user "."
			(at -1.4 1.2 0)
			(layer "F.SilkS")
			(effects
				(font
					(size 1 1)
					(thickness 0.15)
				)
			)
		)
		(fp_text user "Author: Antmicro"
			(at -1.829 5.25 180)
			(layer "F.Fab")
			(effects
				(font
					(size 0.7 0.7)
					(thickness 0.15)
				)
				(justify left bottom)
			)
		)
		(fp_text user "License: Apache-2.0"
			(at -1.75 6.5 180)
			(layer "F.Fab")
			(effects
				(font
					(size 0.7 0.7)
					(thickness 0.15)
				)
				(justify left bottom)
			)
		)
		(fp_text user "${REFERENCE}"
			(at -1.75 4 180)
			(layer "F.Fab")
			(effects
				(font
					(size 0.7 0.7)
					(thickness 0.15)
				)
				(justify left bottom)
			)
		)
		(pad "1" smd roundrect
			(at -0.954 1.1 180)
			(size 0.55 1)
			(layers "F.Cu" "F.Mask" "F.Paste")
			(roundrect_rratio 0.15)
			(net 323 "/Supply/12V_aux_fused")
			(pinfunction "IN")
			(pintype "power_in")
		)
		(pad "2" smd roundrect
			(at -0.003 1.1 180)
			(size 0.55 1)
			(layers "F.Cu" "F.Mask" "F.Paste")
			(roundrect_rratio 0.15)
			(net 1 "GND")
			(pinfunction "GND")
			(pintype "power_in")
		)
		(pad "3" smd roundrect
			(at 0.947 1.1 180)
			(size 0.55 1)
			(layers "F.Cu" "F.Mask" "F.Paste")
			(roundrect_rratio 0.15)
			(net 1 "GND")
			(pinfunction "CTL")
			(pintype "input")
		)
		(pad "4" smd roundrect
			(at 0.947 -1.214 180)
			(size 0.55 1)
			(layers "F.Cu" "F.Mask" "F.Paste")
			(roundrect_rratio 0.15)
			(net 428 "unconnected-(U17-STAT-Pad4)")
			(pinfunction "STAT")
			(pintype "output+no_connect")
		)
		(pad "5" smd roundrect
			(at -0.003 -1.214 180)
			(size 0.55 1)
			(layers "F.Cu" "F.Mask" "F.Paste")
			(roundrect_rratio 0.15)
			(net 284 "Net-(Q12-G)")
			(pinfunction "GATE")
			(pintype "output")
		)
		(pad "6" smd roundrect
			(at -0.954 -1.214 180)
			(size 0.55 1)
			(layers "F.Cu" "F.Mask" "F.Paste")
			(roundrect_rratio 0.15)
			(net 35 "VDC")
			(pinfunction "SENSE")
			(pintype "input")
		)
	)
	(footprint "antmicro-footprints:C_0603_1608Metric"
		(layer "F.Cu")
		(at 242.4 129.356099)
		(descr "Capacitor SMD 0603")
		(tags "capacitor 0603")
		(property "Reference" "C179"
			(at -4.416258 0.393901 0)
			(layer "F.SilkS")
			(effects
				(font
					(size 0.7 0.7)
					(thickness 0.15)
				)
				(justify left bottom)
			)
		)
		(property "Value" "C_1u_25V_0603"
			(at -1.42757 1.770288 0)
			(layer "F.Fab")
			(effects
				(font
					(size 0.7 0.7)
					(thickness 0.15)
				)
				(justify left bottom)
			)
		)
		(property "Datasheet" "https://product.samsungsem.com/mlcc/CL10A105KA8NNN.do"
			(at 0 0 0)
			(layer "F.Fab")
			(hide yes)
			(effects
				(font
					(size 1.27 1.27)
					(thickness 0.15)
				)
			)
		)
		(property "Manufacturer" "Samsung Electro-Mechanics"
			(at 0 0 0)
			(unlocked yes)
			(layer "F.Fab")
			(hide yes)
			(effects
				(font
					(size 1 1)
					(thickness 0.15)
				)
			)
		)
		(property "MPN" "CL10A105KA8NNNC"
			(at 0 0 0)
			(unlocked yes)
			(layer "F.Fab")
			(hide yes)
			(effects
				(font
					(size 1 1)
					(thickness 0.15)
				)
			)
		)
		(property "Val" "1u"
			(at 0 0 0)
			(unlocked yes)
			(layer "F.Fab")
			(hide yes)
			(effects
				(font
					(size 1 1)
					(thickness 0.15)
				)
			)
		)
		(property "License" "Apache-2.0"
			(at 0 0 0)
			(unlocked yes)
			(layer "F.Fab")
			(hide yes)
			(effects
				(font
					(size 1 1)
					(thickness 0.15)
				)
			)
		)
		(property "Author" "Antmicro"
			(at 0 0 0)
			(unlocked yes)
			(layer "F.Fab")
			(hide yes)
			(effects
				(font
					(size 1 1)
					(thickness 0.15)
				)
			)
		)
		(property "Voltage" "25V"
			(at 0 0 0)
			(unlocked yes)
			(layer "F.Fab")
			(hide yes)
			(effects
				(font
					(size 1 1)
					(thickness 0.15)
				)
			)
		)
		(property "Dielectric" ""
			(at 0 0 0)
			(unlocked yes)
			(layer "F.Fab")
			(hide yes)
			(effects
				(font
					(size 1 1)
					(thickness 0.15)
				)
			)
		)
		(sheetname "/Supply/")
		(sheetfile "supply.kicad_sch")
		(attr smd)
		(fp_line
			(start -0.15 -0.4)
			(end 0.15 -0.4)
			(stroke
				(width 0.15)
				(type solid)
			)
			(layer "F.SilkS")
		)
		(fp_line
			(start -0.15 0.4)
			(end 0.15 0.4)
			(stroke
				(width 0.15)
				(type solid)
			)
			(layer "F.SilkS")
		)
		(fp_rect
			(start -1.25 -0.65)
			(end 1.25 0.65)
			(stroke
				(width 0.05)
				(type solid)
			)
			(fill no)
			(layer "F.CrtYd")
		)
		(fp_rect
			(start -0.8 -0.4)
			(end 0.8 0.4)
			(stroke
				(width 0.15)
				(type solid)
			)
			(fill no)
			(layer "F.Fab")
		)
		(fp_text user "License: Apache-2.0"
			(at -1.682 5.895 0)
			(layer "F.Fab")
			(effects
				(font
					(size 0.7 0.7)
					(thickness 0.15)
				)
				(justify left bottom)
			)
		)
		(fp_text user "${REFERENCE}"
			(at -1.682 3.895 0)
			(layer "F.Fab")
			(effects
				(font
					(size 0.7 0.7)
					(thickness 0.15)
				)
				(justify left bottom)
			)
		)
		(fp_text user "Author: Antmicro"
			(at -1.682 4.894 0)
			(layer "F.Fab")
			(effects
				(font
					(size 0.7 0.7)
					(thickness 0.15)
				)
				(justify left bottom)
			)
		)
		(pad "1" smd roundrect
			(at -0.7 0)
			(size 0.8 1)
			(layers "F.Cu" "F.Mask" "F.Paste")
			(roundrect_rratio 0.2)
			(net 1 "GND")
			(pintype "passive")
		)
		(pad "2" smd roundrect
			(at 0.7 0)
			(size 0.8 1)
			(layers "F.Cu" "F.Mask" "F.Paste")
			(roundrect_rratio 0.2)
			(net 35 "VDC")
			(pintype "passive")
		)
	)
	(footprint "antmicro-footprints:L_0402_1005Metric"
		(layer "F.Cu")
		(at 121.025 147.61 180)
		(descr "Inductor SMD 0402")
		(tags "Inductor SMD 0402")
		(property "Reference" "L6"
			(at -5.385 -0.465 0)
			(layer "F.SilkS")
			(effects
				(font
					(size 0.7 0.7)
					(thickness 0.15)
				)
				(justify right bottom)
			)
		)
		(property "Value" "L_20n_0.35A_0402"
			(at 0 1.4 0)
			(layer "F.Fab")
			(effects
				(font
					(size 0.7 0.7)
					(thickness 0.15)
				)
				(justify right bottom)
			)
		)
		(property "Datasheet" "https://product.tdk.com/system/files/dam/doc/product/inductor/inductor/smd/catalog/inductor_automotive_high-frequency_mlg1005s_en.pdf?ref_disty=mouser"
			(at 0 0 180)
			(layer "F.Fab")
			(hide yes)
			(effects
				(font
					(size 1.27 1.27)
					(thickness 0.15)
				)
			)
		)
		(property "Val" "20n/0.35A"
			(at 0 0 180)
			(unlocked yes)
			(layer "F.Fab")
			(hide yes)
			(effects
				(font
					(size 1 1)
					(thickness 0.15)
				)
			)
		)
		(property "Manufacturer" "TDK"
			(at 0 0 180)
			(unlocked yes)
			(layer "F.Fab")
			(hide yes)
			(effects
				(font
					(size 1 1)
					(thickness 0.15)
				)
			)
		)
		(property "MPN" "MLG1005S20NJTD25"
			(at 0 0 180)
			(unlocked yes)
			(layer "F.Fab")
			(hide yes)
			(effects
				(font
					(size 1 1)
					(thickness 0.15)
				)
			)
		)
		(property "ISat" ""
			(at 0 0 180)
			(unlocked yes)
			(layer "F.Fab")
			(hide yes)
			(effects
				(font
					(size 1 1)
					(thickness 0.15)
				)
			)
		)
		(property "IMax" "0.35 A"
			(at 0 0 180)
			(unlocked yes)
			(layer "F.Fab")
			(hide yes)
			(effects
				(font
					(size 1 1)
					(thickness 0.15)
				)
			)
		)
		(property "Size" "1.0x0.5"
			(at 0 0 180)
			(unlocked yes)
			(layer "F.Fab")
			(hide yes)
			(effects
				(font
					(size 1 1)
					(thickness 0.15)
				)
			)
		)
		(property "Author" "Antmicro"
			(at 0 0 180)
			(unlocked yes)
			(layer "F.Fab")
			(hide yes)
			(effects
				(font
					(size 1 1)
					(thickness 0.15)
				)
			)
		)
		(property "License" "Apache-2.0"
			(at 0 0 180)
			(unlocked yes)
			(layer "F.Fab")
			(hide yes)
			(effects
				(font
					(size 1 1)
					(thickness 0.15)
				)
			)
		)
		(sheetname "/HDMI + SD Card/")
		(sheetfile "hdmi-sd-card.kicad_sch")
		(attr smd)
		(fp_rect
			(start -0.925 -0.47)
			(end 0.925 0.47)
			(stroke
				(width 0.05)
				(type default)
			)
			(fill no)
			(layer "F.CrtYd")
		)
		(fp_rect
			(start -0.499 -0.249)
			(end 0.499 0.249)
			(stroke
				(width 0.15)
				(type solid)
			)
			(fill no)
			(layer "F.Fab")
		)
		(fp_text user "Author: Antmicro"
			(at -0.932 4.17 180)
			(layer "F.Fab")
			(effects
				(font
					(size 0.7 0.7)
					(thickness 0.15)
				)
				(justify left bottom)
			)
		)
		(fp_text user "License: Apache-2.0"
			(at -0.932 5.17 180)
			(layer "F.Fab")
			(effects
				(font
					(size 0.7 0.7)
					(thickness 0.15)
				)
				(justify left bottom)
			)
		)
		(fp_text user "${REFERENCE}"
			(at -0.932 3.168 180)
			(layer "F.Fab")
			(effects
				(font
					(size 0.7 0.7)
					(thickness 0.15)
				)
				(justify left bottom)
			)
		)
		(pad "1" smd roundrect
			(at -0.48 0 180)
			(size 0.59 0.64)
			(layers "F.Cu" "F.Mask" "F.Paste")
			(roundrect_rratio 0.25)
			(net 344 "/FPGA MGT Interface/HDMI_IN.D2_P")
			(pintype "passive")
		)
		(pad "2" smd roundrect
			(at 0.48 0 180)
			(size 0.59 0.64)
			(layers "F.Cu" "F.Mask" "F.Paste")
			(roundrect_rratio 0.25)
			(net 676 "Net-(L6-Pad2)")
			(pintype "passive")
		)
	)
	(footprint "antmicro-footprints:C_0805_2012Metric"
		(layer "F.Cu")
		(at 262.9055 155.371 90)
		(descr "Capacitor SMD 0805")
		(tags "capacitor SMD 0805")
		(property "Reference" "C173"
			(at -4.699 0.4905 90)
			(layer "F.SilkS")
			(effects
				(font
					(size 0.7 0.7)
					(thickness 0.15)
				)
				(justify left bottom)
			)
		)
		(property "Value" "C_22u_25V_0805"
			(at -2.055717 1.963152 90)
			(layer "F.Fab")
			(effects
				(font
					(size 0.7 0.7)
					(thickness 0.15)
				)
				(justify left bottom)
			)
		)
		(property "Datasheet" "https://product.samsungsem.com/mlcc/CL21A226MAYNNN.do"
			(at 0 0 90)
			(layer "F.Fab")
			(hide yes)
			(effects
				(font
					(size 1.27 1.27)
					(thickness 0.15)
				)
			)
		)
		(property "Manufacturer" "Samsung Electro-Mechanics"
			(at 0 0 90)
			(unlocked yes)
			(layer "F.Fab")
			(hide yes)
			(effects
				(font
					(size 1 1)
					(thickness 0.15)
				)
			)
		)
		(property "MPN" "CL21A226MAYNNNE"
			(at 0 0 90)
			(unlocked yes)
			(layer "F.Fab")
			(hide yes)
			(effects
				(font
					(size 1 1)
					(thickness 0.15)
				)
			)
		)
		(property "Val" "22u"
			(at 0 0 90)
			(unlocked yes)
			(layer "F.Fab")
			(hide yes)
			(effects
				(font
					(size 1 1)
					(thickness 0.15)
				)
			)
		)
		(property "License" "Apache-2.0"
			(at 0 0 90)
			(unlocked yes)
			(layer "F.Fab")
			(hide yes)
			(effects
				(font
					(size 1 1)
					(thickness 0.15)
				)
			)
		)
		(property "Author" "Antmicro"
			(at 0 0 90)
			(unlocked yes)
			(layer "F.Fab")
			(hide yes)
			(effects
				(font
					(size 1 1)
					(thickness 0.15)
				)
			)
		)
		(property "Voltage" "25V"
			(at 0 0 90)
			(unlocked yes)
			(layer "F.Fab")
			(hide yes)
			(effects
				(font
					(size 1 1)
					(thickness 0.15)
				)
			)
		)
		(property "Dielectric" "X5R"
			(at 0 0 90)
			(unlocked yes)
			(layer "F.Fab")
			(hide yes)
			(effects
				(font
					(size 1 1)
					(thickness 0.15)
				)
			)
		)
		(property "Public" "False"
			(at 0 0 90)
			(unlocked yes)
			(layer "F.Fab")
			(hide yes)
			(effects
				(font
					(size 1 1)
					(thickness 0.15)
				)
			)
		)
		(sheetname "/Supply/DC-DC IO/")
		(sheetfile "dc-dc-io.kicad_sch")
		(attr smd)
		(fp_line
			(start -0.3 -0.7)
			(end 0.3 -0.7)
			(stroke
				(width 0.15)
				(type solid)
			)
			(layer "F.SilkS")
		)
		(fp_line
			(start -0.3 0.7)
			(end 0.3 0.7)
			(stroke
				(width 0.15)
				(type solid)
			)
			(layer "F.SilkS")
		)
		(fp_rect
			(start 1.95 -0.9)
			(end -1.95 0.9)
			(stroke
				(width 0.05)
				(type default)
			)
			(fill no)
			(layer "F.CrtYd")
		)
		(fp_rect
			(start -0.95 -0.675)
			(end 0.95 0.675)
			(stroke
				(width 0.15)
				(type solid)
			)
			(fill no)
			(layer "F.Fab")
		)
		(fp_text user "License: Apache-2.0"
			(at -1.9 4.947 90)
			(layer "F.Fab")
			(effects
				(font
					(size 0.7 0.7)
					(thickness 0.15)
				)
				(justify left bottom)
			)
		)
		(fp_text user "Author: Antmicro"
			(at -1.9 5.947 90)
			(layer "F.Fab")
			(effects
				(font
					(size 0.7 0.7)
					(thickness 0.15)
				)
				(justify left bottom)
			)
		)
		(fp_text user "${REFERENCE}"
			(at -1.9 3.947 90)
			(layer "F.Fab")
			(effects
				(font
					(size 0.7 0.7)
					(thickness 0.15)
				)
				(justify left bottom)
			)
		)
		(pad "1" smd roundrect
			(at -1.1 0 90)
			(size 1.2 1.3)
			(layers "F.Cu" "F.Mask" "F.Paste")
			(roundrect_rratio 0.25)
			(net 1 "GND")
			(pintype "passive")
		)
		(pad "2" smd roundrect
			(at 1.1 0 90)
			(size 1.2 1.3)
			(layers "F.Cu" "F.Mask" "F.Paste")
			(roundrect_rratio 0.25)
			(net 35 "VDC")
			(pintype "passive")
		)
	)
	(footprint "antmicro-footprints:SOT1161-2"
		(layer "F.Cu")
		(at 119.823 159.398 180)
		(descr "SOT1161-2")
		(tags "Integrated Circuit")
		(property "Reference" "U40"
			(at 0.273 -2.752 0)
			(layer "F.SilkS")
			(effects
				(font
					(size 0.7 0.7)
					(thickness 0.15)
				)
				(justify right bottom)
			)
		)
		(property "Value" "NVT4858_XQFN"
			(at 0 2.7 0)
			(layer "F.Fab")
			(effects
				(font
					(size 0.7 0.7)
					(thickness 0.15)
				)
				(justify right bottom)
			)
		)
		(property "Datasheet" "https://www.nxp.com/docs/en/data-sheet/NVT4858DS.pdf"
			(at 0 0 180)
			(layer "F.Fab")
			(hide yes)
			(effects
				(font
					(size 1.27 1.27)
					(thickness 0.15)
				)
			)
		)
		(property "Manufacturer" "NXP"
			(at 0 0 180)
			(unlocked yes)
			(layer "F.Fab")
			(hide yes)
			(effects
				(font
					(size 1 1)
					(thickness 0.15)
				)
			)
		)
		(property "MPN" "NVT4858HKZ"
			(at 0 0 180)
			(unlocked yes)
			(layer "F.Fab")
			(hide yes)
			(effects
				(font
					(size 1 1)
					(thickness 0.15)
				)
			)
		)
		(property "Author" "Antmicro"
			(at 0 0 180)
			(unlocked yes)
			(layer "F.Fab")
			(hide yes)
			(effects
				(font
					(size 1 1)
					(thickness 0.15)
				)
			)
		)
		(property "License" "Apache-2.0"
			(at 0 0 180)
			(unlocked yes)
			(layer "F.Fab")
			(hide yes)
			(effects
				(font
					(size 1 1)
					(thickness 0.15)
				)
			)
		)
		(sheetname "/HDMI + SD Card/")
		(sheetfile "hdmi-sd-card.kicad_sch")
		(attr smd)
		(fp_line
			(start 0.9 0.9)
			(end 0.9 1.3)
			(stroke
				(width 0.15)
				(type solid)
			)
			(layer "F.SilkS")
		)
		(fp_line
			(start 0.9 -0.901)
			(end 0.9 -1.301)
			(stroke
				(width 0.15)
				(type solid)
			)
			(layer "F.SilkS")
		)
		(fp_line
			(start -0.9 -0.9)
			(end -0.9 -1.3)
			(stroke
				(width 0.15)
				(type solid)
			)
			(layer "F.SilkS")
		)
		(fp_line
			(start -0.902 0.9)
			(end -0.902 1.3)
			(stroke
				(width 0.15)
				(type solid)
			)
			(layer "F.SilkS")
		)
		(fp_circle
			(center -1.6 -1.7)
			(end -1.55 -1.7)
			(stroke
				(width 0.15)
				(type solid)
			)
			(fill yes)
			(layer "F.SilkS")
		)
		(fp_rect
			(start -1.3 -1.7)
			(end 1.3 1.7)
			(stroke
				(width 0.05)
				(type solid)
			)
			(fill no)
			(layer "F.CrtYd")
		)
		(fp_line
			(start 0.9 1.3)
			(end -0.902 1.3)
			(stroke
				(width 0.15)
				(type solid)
			)
			(layer "F.Fab")
		)
		(fp_line
			(start 0.9 -1.301)
			(end 0.9 1.3)
			(stroke
				(width 0.15)
				(type solid)
			)
			(layer "F.Fab")
		)
		(fp_line
			(start -0.902 1.3)
			(end -0.902 -1.301)
			(stroke
				(width 0.15)
				(type solid)
			)
			(layer "F.Fab")
		)
		(fp_line
			(start -0.902 -1.301)
			(end 0.9 -1.301)
			(stroke
				(width 0.15)
				(type solid)
			)
			(layer "F.Fab")
		)
		(fp_text user "Author: Antmicro"
			(at -1.5 4.498 180)
			(layer "F.Fab")
			(effects
				(font
					(size 0.7 0.7)
					(thickness 0.15)
				)
				(justify left bottom)
			)
		)
		(fp_text user "License: Apache-2.0"
			(at -1.5 5.7 180)
			(layer "F.Fab")
			(effects
				(font
					(size 0.7 0.7)
					(thickness 0.15)
				)
				(justify left bottom)
			)
		)
		(pad "1" smd roundrect
			(at -0.6 -0.6 270)
			(size 0.22 0.9)
			(layers "F.Cu" "F.Mask" "F.Paste")
			(roundrect_rratio 0.25)
			(net 640 "/FPGA banks HP/SD.DAT2")
			(pinfunction "DAT2_{A}")
			(pintype "bidirectional")
		)
		(pad "2" smd roundrect
			(at -0.625 -0.202 270)
			(size 0.22 0.9)
			(layers "F.Cu" "F.Mask" "F.Paste")
			(roundrect_rratio 0.25)
			(net 641 "/FPGA banks HP/SD.DAT3")
			(pinfunction "DAT3_{A}")
			(pintype "bidirectional")
		)
		(pad "3" smd roundrect
			(at -0.625 0.2 270)
			(size 0.22 0.9)
			(layers "F.Cu" "F.Mask" "F.Paste")
			(roundrect_rratio 0.25)
			(net 638 "/FPGA banks HP/SD.DAT0")
			(pinfunction "DAT0_{A}")
			(pintype "bidirectional")
		)
		(pad "4" smd roundrect
			(at -0.625 0.598 270)
			(size 0.22 0.9)
			(layers "F.Cu" "F.Mask" "F.Paste")
			(roundrect_rratio 0.25)
			(net 639 "/FPGA banks HP/SD.DAT1")
			(pinfunction "DAT1_{A}")
			(pintype "bidirectional")
		)
		(pad "5" smd roundrect
			(at -0.6 1.175 180)
			(size 0.22 0.55)
			(layers "F.Cu" "F.Mask" "F.Paste")
			(roundrect_rratio 0.25)
			(net 636 "/FPGA banks HP/SD.CLK")
			(pinfunction "CLK_{A}")
			(pintype "input")
		)
		(pad "6" smd roundrect
			(at -0.202 1.175 180)
			(size 0.22 0.55)
			(layers "F.Cu" "F.Mask" "F.Paste")
			(roundrect_rratio 0.25)
			(net 671 "unconnected-(U40-CLK_{FB}-Pad6)")
			(pinfunction "CLK_{FB}")
			(pintype "output+no_connect")
		)
		(pad "7" smd roundrect
			(at 0.2 1.175 180)
			(size 0.22 0.55)
			(layers "F.Cu" "F.Mask" "F.Paste")
			(roundrect_rratio 0.25)
			(net 1 "GND")
			(pinfunction "GND")
			(pintype "power_in")
		)
		(pad "8" smd roundrect
			(at 0.598 1.175 180)
			(size 0.22 0.55)
			(layers "F.Cu" "F.Mask" "F.Paste")
			(roundrect_rratio 0.25)
			(net 609 "/HDMI + SD Card/SD_CLK")
			(pinfunction "CLK_{B}")
			(pintype "output")
		)
		(pad "9" smd roundrect
			(at 0.623 0.598 270)
			(size 0.22 0.9)
			(layers "F.Cu" "F.Mask" "F.Paste")
			(roundrect_rratio 0.25)
			(net 612 "/HDMI + SD Card/SD_DAT1")
			(pinfunction "DAT1_{B}")
			(pintype "bidirectional")
		)
		(pad "10" smd roundrect
			(at 0.623 0.2 270)
			(size 0.22 0.9)
			(layers "F.Cu" "F.Mask" "F.Paste")
			(roundrect_rratio 0.25)
			(net 611 "/HDMI + SD Card/SD_DAT0")
			(pinfunction "DAT0_{B}")
			(pintype "bidirectional")
		)
		(pad "11" smd roundrect
			(at 0.623 -0.202 270)
			(size 0.22 0.9)
			(layers "F.Cu" "F.Mask" "F.Paste")
			(roundrect_rratio 0.25)
			(net 607 "/HDMI + SD Card/SD_DAT3")
			(pinfunction "DAT3_{B}")
			(pintype "bidirectional")
		)
		(pad "12" smd roundrect
			(at 0.623 -0.6 270)
			(size 0.22 0.9)
			(layers "F.Cu" "F.Mask" "F.Paste")
			(roundrect_rratio 0.25)
			(net 606 "/HDMI + SD Card/SD_DAT2")
			(pinfunction "DAT2_{B}")
			(pintype "bidirectional")
		)
		(pad "13" smd roundrect
			(at 0.598 -1.176 180)
			(size 0.22 0.55)
			(layers "F.Cu" "F.Mask" "F.Paste")
			(roundrect_rratio 0.25)
			(net 608 "/HDMI + SD Card/SD_CMD")
			(pinfunction "CMD_{B}")
			(pintype "bidirectional")
		)
		(pad "14" smd roundrect
			(at 0.2 -1.176 180)
			(size 0.22 0.55)
			(layers "F.Cu" "F.Mask" "F.Paste")
			(roundrect_rratio 0.25)
			(net 647 "/HDMI + SD Card/VCCB")
			(pinfunction "VCC_{B}")
			(pintype "power_in")
		)
		(pad "15" smd roundrect
			(at -0.202 -1.176 180)
			(size 0.22 0.55)
			(layers "F.Cu" "F.Mask" "F.Paste")
			(roundrect_rratio 0.25)
			(net 797 "+1V8")
			(pinfunction "VCC_{A}")
			(pintype "power_in")
		)
		(pad "16" smd roundrect
			(at -0.6 -1.176 180)
			(size 0.22 0.55)
			(layers "F.Cu" "F.Mask" "F.Paste")
			(roundrect_rratio 0.25)
			(net 637 "/FPGA banks HP/SD.CMD")
			(pinfunction "CMD_{A}")
			(pintype "bidirectional")
		)
	)
	(footprint "antmicro-footprints:C_0805_2012Metric"
		(layer "F.Cu")
		(at 262.9 172.9095 90)
		(descr "Capacitor SMD 0805")
		(tags "capacitor SMD 0805")
		(property "Reference" "C182"
			(at 1.9095 0.6 90)
			(layer "F.SilkS")
			(effects
				(font
					(size 0.7 0.7)
					(thickness 0.15)
				)
				(justify left bottom)
			)
		)
		(property "Value" "C_22u_25V_0805"
			(at -2.055717 1.963152 90)
			(layer "F.Fab")
			(effects
				(font
					(size 0.7 0.7)
					(thickness 0.15)
				)
				(justify left bottom)
			)
		)
		(property "Datasheet" "https://product.samsungsem.com/mlcc/CL21A226MAYNNN.do"
			(at 0 0 90)
			(layer "F.Fab")
			(hide yes)
			(effects
				(font
					(size 1.27 1.27)
					(thickness 0.15)
				)
			)
		)
		(property "MPN" "CL21A226MAYNNNE"
			(at 0 0 90)
			(unlocked yes)
			(layer "F.Fab")
			(hide yes)
			(effects
				(font
					(size 1 1)
					(thickness 0.15)
				)
			)
		)
		(property "Manufacturer" "Samsung Electro-Mechanics"
			(at 0 0 90)
			(unlocked yes)
			(layer "F.Fab")
			(hide yes)
			(effects
				(font
					(size 1 1)
					(thickness 0.15)
				)
			)
		)
		(property "License" "Apache-2.0"
			(at 0 0 90)
			(unlocked yes)
			(layer "F.Fab")
			(hide yes)
			(effects
				(font
					(size 1 1)
					(thickness 0.15)
				)
			)
		)
		(property "Author" "Antmicro"
			(at 0 0 90)
			(unlocked yes)
			(layer "F.Fab")
			(hide yes)
			(effects
				(font
					(size 1 1)
					(thickness 0.15)
				)
			)
		)
		(property "Val" "22u"
			(at 0 0 90)
			(unlocked yes)
			(layer "F.Fab")
			(hide yes)
			(effects
				(font
					(size 1 1)
					(thickness 0.15)
				)
			)
		)
		(property "Voltage" "25V"
			(at 0 0 90)
			(unlocked yes)
			(layer "F.Fab")
			(hide yes)
			(effects
				(font
					(size 1 1)
					(thickness 0.15)
				)
			)
		)
		(property "Dielectric" "X5R"
			(at 0 0 90)
			(unlocked yes)
			(layer "F.Fab")
			(hide yes)
			(effects
				(font
					(size 1 1)
					(thickness 0.15)
				)
			)
		)
		(property "Public" "False"
			(at 0 0 90)
			(unlocked yes)
			(layer "F.Fab")
			(hide yes)
			(effects
				(font
					(size 1 1)
					(thickness 0.15)
				)
			)
		)
		(sheetname "/Supply/DC-DC AUX, MGT/")
		(sheetfile "dc-dc-aux-mgt.kicad_sch")
		(attr smd)
		(fp_line
			(start -0.3 -0.7)
			(end 0.3 -0.7)
			(stroke
				(width 0.15)
				(type solid)
			)
			(layer "F.SilkS")
		)
		(fp_line
			(start -0.3 0.7)
			(end 0.3 0.7)
			(stroke
				(width 0.15)
				(type solid)
			)
			(layer "F.SilkS")
		)
		(fp_rect
			(start 1.95 -0.9)
			(end -1.95 0.9)
			(stroke
				(width 0.05)
				(type default)
			)
			(fill no)
			(layer "F.CrtYd")
		)
		(fp_rect
			(start -0.95 -0.675)
			(end 0.95 0.675)
			(stroke
				(width 0.15)
				(type solid)
			)
			(fill no)
			(layer "F.Fab")
		)
		(fp_text user "Author: Antmicro"
			(at -1.9 5.947 90)
			(layer "F.Fab")
			(effects
				(font
					(size 0.7 0.7)
					(thickness 0.15)
				)
				(justify left bottom)
			)
		)
		(fp_text user "License: Apache-2.0"
			(at -1.9 4.947 90)
			(layer "F.Fab")
			(effects
				(font
					(size 0.7 0.7)
					(thickness 0.15)
				)
				(justify left bottom)
			)
		)
		(fp_text user "${REFERENCE}"
			(at -1.9 3.947 90)
			(layer "F.Fab")
			(effects
				(font
					(size 0.7 0.7)
					(thickness 0.15)
				)
				(justify left bottom)
			)
		)
		(pad "1" smd roundrect
			(at -1.1 0 90)
			(size 1.2 1.3)
			(layers "F.Cu" "F.Mask" "F.Paste")
			(roundrect_rratio 0.25)
			(net 1 "GND")
			(pintype "passive")
		)
		(pad "2" smd roundrect
			(at 1.1 0 90)
			(size 1.2 1.3)
			(layers "F.Cu" "F.Mask" "F.Paste")
			(roundrect_rratio 0.25)
			(net 35 "VDC")
			(pintype "passive")
		)
	)
	(footprint "antmicro-footprints:C_0402_1005Metric"
		(layer "F.Cu")
		(at 109.349499 148.564 -90)
		(descr "Capacitor SMD 0402")
		(tags "capacitor SMD 0402")
		(property "Reference" "C133"
			(at 1.011 -0.500501 90)
			(layer "F.SilkS")
			(effects
				(font
					(size 0.7 0.7)
					(thickness 0.15)
				)
				(justify right bottom)
			)
		)
		(property "Value" "C_100n_0402"
			(at -1.022927 2.155213 90)
			(layer "F.Fab")
			(effects
				(font
					(size 0.7 0.7)
					(thickness 0.15)
				)
				(justify right bottom)
			)
		)
		(property "Datasheet" "https://www.murata.com/products/productdetail?partno=GRM155R61H104KE14%23"
			(at 0 0 270)
			(layer "F.Fab")
			(hide yes)
			(effects
				(font
					(size 1.27 1.27)
					(thickness 0.15)
				)
			)
		)
		(property "Manufacturer" "Murata"
			(at 0 0 270)
			(unlocked yes)
			(layer "F.Fab")
			(hide yes)
			(effects
				(font
					(size 1 1)
					(thickness 0.15)
				)
			)
		)
		(property "MPN" "GRM155R61H104KE14D"
			(at 0 0 270)
			(unlocked yes)
			(layer "F.Fab")
			(hide yes)
			(effects
				(font
					(size 1 1)
					(thickness 0.15)
				)
			)
		)
		(property "Val" "100n"
			(at 0 0 270)
			(unlocked yes)
			(layer "F.Fab")
			(hide yes)
			(effects
				(font
					(size 1 1)
					(thickness 0.15)
				)
			)
		)
		(property "License" "Apache-2.0"
			(at 0 0 270)
			(unlocked yes)
			(layer "F.Fab")
			(hide yes)
			(effects
				(font
					(size 1 1)
					(thickness 0.15)
				)
			)
		)
		(property "Author" "Antmicro"
			(at 0 0 270)
			(unlocked yes)
			(layer "F.Fab")
			(hide yes)
			(effects
				(font
					(size 1 1)
					(thickness 0.15)
				)
			)
		)
		(property "Voltage" "50V"
			(at 0 0 270)
			(unlocked yes)
			(layer "F.Fab")
			(hide yes)
			(effects
				(font
					(size 1 1)
					(thickness 0.15)
				)
			)
		)
		(property "Dielectric" "X5R"
			(at 0 0 270)
			(unlocked yes)
			(layer "F.Fab")
			(hide yes)
			(effects
				(font
					(size 1 1)
					(thickness 0.15)
				)
			)
		)
		(sheetname "/Debug FTDI + VNA/")
		(sheetfile "debug-ftdi.kicad_sch")
		(attr smd)
		(fp_rect
			(start -0.925 -0.47)
			(end 0.925 0.47)
			(stroke
				(width 0.05)
				(type default)
			)
			(fill no)
			(layer "F.CrtYd")
		)
		(fp_line
			(start -0.494 0.248)
			(end -0.494 -0.25)
			(stroke
				(width 0.15)
				(type solid)
			)
			(layer "F.Fab")
		)
		(fp_line
			(start 0.504 0.248)
			(end -0.494 0.248)
			(stroke
				(width 0.15)
				(type solid)
			)
			(layer "F.Fab")
		)
		(fp_line
			(start -0.494 -0.25)
			(end 0.504 -0.25)
			(stroke
				(width 0.15)
				(type solid)
			)
			(layer "F.Fab")
		)
		(fp_line
			(start 0.504 -0.25)
			(end 0.504 0.248)
			(stroke
				(width 0.15)
				(type solid)
			)
			(layer "F.Fab")
		)
		(fp_text user "Author: Antmicro"
			(at -0.939 3.399 270)
			(layer "F.Fab")
			(effects
				(font
					(size 0.7 0.7)
					(thickness 0.15)
				)
				(justify left bottom)
			)
		)
		(fp_text user "${REFERENCE}"
			(at -0.939 4.599 270)
			(layer "F.Fab")
			(effects
				(font
					(size 0.7 0.7)
					(thickness 0.15)
				)
				(justify left bottom)
			)
		)
		(fp_text user "License: Apache-2.0"
			(at -0.939 5.799 270)
			(layer "F.Fab")
			(effects
				(font
					(size 0.7 0.7)
					(thickness 0.15)
				)
				(justify left bottom)
			)
		)
		(pad "1" smd roundrect
			(at -0.48 0 270)
			(size 0.59 0.64)
			(layers "F.Cu" "F.Mask" "F.Paste")
			(roundrect_rratio 0.25)
			(net 321 "Net-(C133-Pad1)")
			(pintype "passive")
		)
		(pad "2" smd roundrect
			(at 0.48 0 270)
			(size 0.59 0.64)
			(layers "F.Cu" "F.Mask" "F.Paste")
			(roundrect_rratio 0.25)
			(net 1 "GND")
			(pintype "passive")
		)
	)
	(footprint "antmicro-footprints:LED_0603_1608Metric_G"
		(layer "F.Cu")
		(at 135.823499 185.549 90)
		(descr "LED SMD 0603 Green")
		(tags "LED SMD 0603 Green")
		(property "Reference" "D10"
			(at -0.001 -0.901 90)
			(layer "F.SilkS")
			(hide yes)
			(effects
				(font
					(size 0.7 0.7)
					(thickness 0.15)
				)
				(justify left bottom)
			)
		)
		(property "Value" "LED_G_0603_KP-1608CGCK"
			(at -0.001 1.599 90)
			(layer "F.Fab")
			(effects
				(font
					(size 0.7 0.7)
					(thickness 0.15)
				)
				(justify left bottom)
			)
		)
		(property "Datasheet" "http://www.kingbright.com/attachments/file/psearch//000/00/00/KP-1608CGCK(Ver.23B).pdf"
			(at 0 0 90)
			(layer "F.Fab")
			(hide yes)
			(effects
				(font
					(size 1.27 1.27)
					(thickness 0.15)
				)
			)
		)
		(property "MPN" "KP-1608CGCK"
			(at 0 0 90)
			(unlocked yes)
			(layer "F.Fab")
			(hide yes)
			(effects
				(font
					(size 1 1)
					(thickness 0.15)
				)
			)
		)
		(property "Manufacturer" "Kingbright"
			(at 0 0 90)
			(unlocked yes)
			(layer "F.Fab")
			(hide yes)
			(effects
				(font
					(size 1 1)
					(thickness 0.15)
				)
			)
		)
		(property "Color" "Green"
			(at 0 0 90)
			(unlocked yes)
			(layer "F.Fab")
			(hide yes)
			(effects
				(font
					(size 1 1)
					(thickness 0.15)
				)
			)
		)
		(property "Author" "Antmicro"
			(at 0 0 90)
			(unlocked yes)
			(layer "F.Fab")
			(hide yes)
			(effects
				(font
					(size 1 1)
					(thickness 0.15)
				)
			)
		)
		(property "License" "Apache-2.0"
			(at 0 0 90)
			(unlocked yes)
			(layer "F.Fab")
			(hide yes)
			(effects
				(font
					(size 1 1)
					(thickness 0.15)
				)
			)
		)
		(sheetname "/Debug FTDI + VNA/")
		(sheetfile "debug-ftdi.kicad_sch")
		(attr smd)
		(fp_line
			(start 0.22 -0.35)
			(end -0.22 -0.35)
			(stroke
				(width 0.15)
				(type solid)
			)
			(layer "F.SilkS")
		)
		(fp_line
			(start -1.18 -0.319)
			(end -1.18 0.321)
			(stroke
				(width 0.15)
				(type solid)
			)
			(layer "F.SilkS")
		)
		(fp_line
			(start 0.105328 0.001008)
			(end 0.24 0.001)
			(stroke
				(width 0.1)
				(type solid)
			)
			(layer "F.SilkS")
		)
		(fp_line
			(start -0.094672 0.001008)
			(end 0.105328 -0.198992)
			(stroke
				(width 0.1)
				(type solid)
			)
			(layer "F.SilkS")
		)
		(fp_line
			(start -0.094672 0.001008)
			(end -0.24 0.001008)
			(stroke
				(width 0.1)
				(type solid)
			)
			(layer "F.SilkS")
		)
		(fp_line
			(start 0.105328 0.201008)
			(end 0.105328 -0.198992)
			(stroke
				(width 0.1)
				(type solid)
			)
			(layer "F.SilkS")
		)
		(fp_line
			(start 0.105328 0.201008)
			(end -0.094672 0.001008)
			(stroke
				(width 0.1)
				(type solid)
			)
			(layer "F.SilkS")
		)
		(fp_line
			(start -0.094672 0.201008)
			(end -0.094672 -0.198992)
			(stroke
				(width 0.1)
				(type solid)
			)
			(layer "F.SilkS")
		)
		(fp_line
			(start 0.22 0.35)
			(end -0.22 0.35)
			(stroke
				(width 0.15)
				(type solid)
			)
			(layer "F.SilkS")
		)
		(fp_rect
			(start 1.25 0.65)
			(end -1.25 -0.65)
			(stroke
				(width 0.05)
				(type solid)
			)
			(fill no)
			(layer "F.CrtYd")
		)
		(fp_line
			(start 0.201 -0.202)
			(end -0.101 0)
			(stroke
				(width 0.15)
				(type solid)
			)
			(layer "F.Fab")
		)
		(fp_line
			(start -0.199 -0.202)
			(end -0.199 0.1)
			(stroke
				(width 0.15)
				(type solid)
			)
			(layer "F.Fab")
		)
		(fp_line
			(start 0.599 0)
			(end 0.201 0)
			(stroke
				(width 0.15)
				(type solid)
			)
			(layer "F.Fab")
		)
		(fp_line
			(start 0.201 0)
			(end 0.201 -0.202)
			(stroke
				(width 0.15)
				(type solid)
			)
			(layer "F.Fab")
		)
		(fp_line
			(start -0.101 0)
			(end 0.201 0.2)
			(stroke
				(width 0.15)
				(type solid)
			)
			(layer "F.Fab")
		)
		(fp_line
			(start -0.199 0)
			(end -0.597 0)
			(stroke
				(width 0.15)
				(type solid)
			)
			(layer "F.Fab")
		)
		(fp_line
			(start 0.201 0.2)
			(end 0.201 0)
			(stroke
				(width 0.15)
				(type solid)
			)
			(layer "F.Fab")
		)
		(fp_line
			(start -0.199 0.2)
			(end -0.199 0.1)
			(stroke
				(width 0.15)
				(type solid)
			)
			(layer "F.Fab")
		)
		(fp_rect
			(start 0.848 0.4)
			(end -0.85 -0.402)
			(stroke
				(width 0.15)
				(type solid)
			)
			(fill no)
			(layer "F.Fab")
		)
		(fp_text user "${REFERENCE}"
			(at -1.4224 5.999 90)
			(layer "F.Fab")
			(effects
				(font
					(size 0.7 0.7)
					(thickness 0.15)
				)
				(justify left bottom)
			)
		)
		(fp_text user "Author: Antmicro"
			(at -1.4224 4.799 90)
			(layer "F.Fab")
			(effects
				(font
					(size 0.7 0.7)
					(thickness 0.15)
				)
				(justify left bottom)
			)
		)
		(fp_text user "License: Apache-2.0"
			(at -1.4224 3.599 90)
			(layer "F.Fab")
			(effects
				(font
					(size 0.7 0.7)
					(thickness 0.15)
				)
				(justify left bottom)
			)
		)
		(pad "1" smd roundrect
			(at -0.7 0 270)
			(size 0.8 1)
			(layers "F.Cu" "F.Mask" "F.Paste")
			(roundrect_rratio 0.2)
			(net 1 "GND")
			(pinfunction "C")
			(pintype "passive")
		)
		(pad "2" smd roundrect
			(at 0.7 0 270)
			(size 0.8 1)
			(layers "F.Cu" "F.Mask" "F.Paste")
			(roundrect_rratio 0.2)
			(net 39 "Net-(D10-A)")
			(pinfunction "A")
			(pintype "passive")
		)
	)
	(footprint "antmicro-footprints:R_0402_1005Metric"
		(layer "F.Cu")
		(at 127.681 166.1125 90)
		(descr "Resistor SMD 0402")
		(tags "resistor SMD 0402")
		(property "Reference" "R225"
			(at 0.9125 3.969 90)
			(layer "F.SilkS")
			(effects
				(font
					(size 0.7 0.7)
					(thickness 0.15)
				)
				(justify left bottom)
			)
		)
		(property "Value" "R_64k9_0402"
			(at -1.011843 1.772047 90)
			(layer "F.Fab")
			(effects
				(font
					(size 0.7 0.7)
					(thickness 0.15)
				)
				(justify left bottom)
			)
		)
		(property "Datasheet" "https://www.bourns.com/docs/product-datasheets/cr.pdf"
			(at 0 0 90)
			(layer "F.Fab")
			(hide yes)
			(effects
				(font
					(size 1.27 1.27)
					(thickness 0.15)
				)
			)
		)
		(property "MPN" "CR0402-FX-6492GLF"
			(at 0 0 90)
			(unlocked yes)
			(layer "F.Fab")
			(hide yes)
			(effects
				(font
					(size 1 1)
					(thickness 0.15)
				)
			)
		)
		(property "Manufacturer" "Bourns"
			(at 0 0 90)
			(unlocked yes)
			(layer "F.Fab")
			(hide yes)
			(effects
				(font
					(size 1 1)
					(thickness 0.15)
				)
			)
		)
		(property "License" "Apache-2.0"
			(at 0 0 90)
			(unlocked yes)
			(layer "F.Fab")
			(hide yes)
			(effects
				(font
					(size 1 1)
					(thickness 0.15)
				)
			)
		)
		(property "Author" "Antmicro"
			(at 0 0 90)
			(unlocked yes)
			(layer "F.Fab")
			(hide yes)
			(effects
				(font
					(size 1 1)
					(thickness 0.15)
				)
			)
		)
		(property "Val" "64k9"
			(at 0 0 90)
			(unlocked yes)
			(layer "F.Fab")
			(hide yes)
			(effects
				(font
					(size 1 1)
					(thickness 0.15)
				)
			)
		)
		(property "Tolerance" "1%"
			(at 0 0 90)
			(unlocked yes)
			(layer "F.Fab")
			(hide yes)
			(effects
				(font
					(size 1 1)
					(thickness 0.15)
				)
			)
		)
		(sheetname "/HDMI + SD Card/")
		(sheetfile "hdmi-sd-card.kicad_sch")
		(attr smd exclude_from_bom dnp)
		(fp_rect
			(start -0.925 -0.47)
			(end 0.925 0.47)
			(stroke
				(width 0.05)
				(type default)
			)
			(fill no)
			(layer "F.CrtYd")
		)
		(fp_rect
			(start -0.5 -0.25)
			(end 0.5 0.25)
			(stroke
				(width 0.15)
				(type solid)
			)
			(fill no)
			(layer "F.Fab")
		)
		(fp_text user "${REFERENCE}"
			(at -0.95 3.168 90)
			(layer "F.Fab")
			(effects
				(font
					(size 0.7 0.7)
					(thickness 0.15)
				)
				(justify left bottom)
			)
		)
		(fp_text user "License: Apache-2.0"
			(at -0.95 5.169 90)
			(layer "F.Fab")
			(effects
				(font
					(size 0.7 0.7)
					(thickness 0.15)
				)
				(justify left bottom)
			)
		)
		(fp_text user "Author: Antmicro"
			(at -0.95 4.169 90)
			(layer "F.Fab")
			(effects
				(font
					(size 0.7 0.7)
					(thickness 0.15)
				)
				(justify left bottom)
			)
		)
		(pad "1" smd roundrect
			(at -0.48 0 90)
			(size 0.59 0.64)
			(layers "F.Cu" "F.Mask" "F.Paste")
			(roundrect_rratio 0.25)
			(net 710 "/HDMI + SD Card/I2C_EN{slash}PIN")
			(pintype "passive")
		)
		(pad "2" smd roundrect
			(at 0.48 0 90)
			(size 0.59 0.64)
			(layers "F.Cu" "F.Mask" "F.Paste")
			(roundrect_rratio 0.25)
			(net 151 "+3V3")
			(pintype "passive")
		)
	)
	(footprint "antmicro-footprints:SOD-523"
		(layer "F.Cu")
		(at 116.981 174.668 90)
		(property "Reference" "D14"
			(at -0.2495 1.615 90)
			(layer "F.SilkS")
			(effects
				(font
					(size 0.7 0.7)
					(thickness 0.15)
				)
				(justify left bottom)
			)
		)
		(property "Value" "BAT54-02V-G3-08"
			(at 0 1.499 90)
			(layer "F.Fab")
			(effects
				(font
					(size 0.7 0.7)
					(thickness 0.15)
				)
				(justify left bottom)
			)
		)
		(property "Datasheet" "https://www.vishay.com/docs/85633/bat5402v.pdf"
			(at 0 0 90)
			(layer "F.Fab")
			(hide yes)
			(effects
				(font
					(size 1.27 1.27)
					(thickness 0.15)
				)
			)
		)
		(property "MPN" "BAT54-02V-G3-08"
			(at 0 0 90)
			(unlocked yes)
			(layer "F.Fab")
			(hide yes)
			(effects
				(font
					(size 1 1)
					(thickness 0.15)
				)
			)
		)
		(property "Manufacturer" "Vishay"
			(at 0 0 90)
			(unlocked yes)
			(layer "F.Fab")
			(hide yes)
			(effects
				(font
					(size 1 1)
					(thickness 0.15)
				)
			)
		)
		(property "Author" "Antmicro"
			(at 0 0 90)
			(unlocked yes)
			(layer "F.Fab")
			(hide yes)
			(effects
				(font
					(size 1 1)
					(thickness 0.15)
				)
			)
		)
		(property "License" "Apache-2.0"
			(at 0 0 90)
			(unlocked yes)
			(layer "F.Fab")
			(hide yes)
			(effects
				(font
					(size 1 1)
					(thickness 0.15)
				)
			)
		)
		(sheetname "/HDMI + SD Card/")
		(sheetfile "hdmi-sd-card.kicad_sch")
		(attr smd)
		(fp_line
			(start -0.35 -0.5)
			(end -0.35 0.5)
			(stroke
				(width 0.15)
				(type solid)
			)
			(layer "F.SilkS")
		)
		(fp_rect
			(start -1 -0.6)
			(end 1 0.6)
			(stroke
				(width 0.05)
				(type solid)
			)
			(fill no)
			(layer "F.CrtYd")
		)
		(fp_line
			(start 0.65 -0.425)
			(end 0.65 0.423)
			(stroke
				(width 0.15)
				(type solid)
			)
			(layer "F.Fab")
		)
		(fp_line
			(start -0.652 -0.425)
			(end 0.65 -0.425)
			(stroke
				(width 0.15)
				(type solid)
			)
			(layer "F.Fab")
		)
		(fp_line
			(start -0.35 -0.4)
			(end -0.35 0.4)
			(stroke
				(width 0.15)
				(type solid)
			)
			(layer "F.Fab")
		)
		(fp_line
			(start -0.652 0.423)
			(end -0.652 -0.425)
			(stroke
				(width 0.15)
				(type solid)
			)
			(layer "F.Fab")
		)
		(fp_line
			(start -0.652 0.423)
			(end 0.65 0.423)
			(stroke
				(width 0.15)
				(type solid)
			)
			(layer "F.Fab")
		)
		(fp_text user "License: Apache-2.0"
			(at -1.276 5.9 90)
			(layer "F.Fab")
			(effects
				(font
					(size 0.7 0.7)
					(thickness 0.15)
				)
				(justify left bottom)
			)
		)
		(fp_text user "Author: Antmicro"
			(at -1.276 4.7 90)
			(layer "F.Fab")
			(effects
				(font
					(size 0.7 0.7)
					(thickness 0.15)
				)
				(justify left bottom)
			)
		)
		(fp_text user "${REFERENCE}"
			(at -1.276 3.499 90)
			(layer "F.Fab")
			(effects
				(font
					(size 0.7 0.7)
					(thickness 0.15)
				)
				(justify left bottom)
			)
		)
		(pad "1" smd roundrect
			(at -0.701 0 90)
			(size 0.5 0.6)
			(layers "F.Cu" "F.Mask" "F.Paste")
			(roundrect_rratio 0.25)
			(net 8 "/HDMI + SD Card/HDMI_CONN_5V")
			(pinfunction "C")
			(pintype "passive")
		)
		(pad "2" smd roundrect
			(at 0.699 0 90)
			(size 0.5 0.6)
			(layers "F.Cu" "F.Mask" "F.Paste")
			(roundrect_rratio 0.25)
			(net 33 "/HDMI + SD Card/HDMI_5V")
			(pinfunction "A")
			(pintype "passive")
		)
	)
	(footprint "antmicro-footprints:TP_SMD_1mm"
		(layer "F.Cu")
		(at 243.23 134.757 90)
		(property "Reference" "TP7"
			(at 0 -0.731898 90)
			(layer "F.SilkS")
			(hide yes)
			(effects
				(font
					(size 0.7 0.7)
					(thickness 0.15)
				)
				(justify left bottom)
			)
		)
		(property "Value" "TP_1mm_SMD"
			(at 0 1.4 90)
			(layer "F.Fab")
			(effects
				(font
					(size 0.7 0.7)
					(thickness 0.15)
				)
				(justify left bottom)
			)
		)
		(property "MPN" ""
			(at 0 0 90)
			(unlocked yes)
			(layer "F.Fab")
			(hide yes)
			(effects
				(font
					(size 1 1)
					(thickness 0.15)
				)
			)
		)
		(property "Manufacturer" ""
			(at 0 0 90)
			(unlocked yes)
			(layer "F.Fab")
			(hide yes)
			(effects
				(font
					(size 1 1)
					(thickness 0.15)
				)
			)
		)
		(property "Author" "Antmicro"
			(at 0 0 90)
			(unlocked yes)
			(layer "F.Fab")
			(hide yes)
			(effects
				(font
					(size 1 1)
					(thickness 0.15)
				)
			)
		)
		(property "License" "Apache-2.0"
			(at 0 0 90)
			(unlocked yes)
			(layer "F.Fab")
			(hide yes)
			(effects
				(font
					(size 1 1)
					(thickness 0.15)
				)
			)
		)
		(sheetname "/I^{2}C + I3C/")
		(sheetfile "i2c.kicad_sch")
		(attr exclude_from_pos_files)
		(fp_circle
			(center 0 0)
			(end 0.6 0)
			(stroke
				(width 0.05)
				(type default)
			)
			(fill no)
			(layer "F.CrtYd")
		)
		(fp_text user "${REFERENCE}"
			(at -0.5 2.8 90)
			(layer "F.Fab")
			(effects
				(font
					(size 0.7 0.7)
					(thickness 0.15)
				)
				(justify left bottom)
			)
		)
		(fp_text user "Author: Antmicro"
			(at -0.5 4 90)
			(layer "F.Fab")
			(effects
				(font
					(size 0.7 0.7)
					(thickness 0.15)
				)
				(justify left bottom)
			)
		)
		(fp_text user "License: Apache-2.0"
			(at -0.5 5.2 90)
			(layer "F.Fab")
			(effects
				(font
					(size 0.7 0.7)
					(thickness 0.15)
				)
				(justify left bottom)
			)
		)
		(pad "1" smd circle
			(at 0 0 90)
			(size 1 1)
			(layers "F.Cu" "F.Mask")
			(net 796 "Net-(U45-EN)")
			(pinfunction "1")
			(pintype "passive")
		)
	)
	(footprint "antmicro-footprints:R_0402_1005Metric"
		(layer "F.Cu")
		(at 254.1055 160.171 180)
		(descr "Resistor SMD 0402")
		(tags "resistor SMD 0402")
		(property "Reference" "R155"
			(at -0.5945 -1.429 0)
			(layer "F.SilkS")
			(effects
				(font
					(size 0.7 0.7)
					(thickness 0.15)
				)
				(justify right bottom)
			)
		)
		(property "Value" "R_0R_0402"
			(at -1.011843 1.772047 0)
			(layer "F.Fab")
			(effects
				(font
					(size 0.7 0.7)
					(thickness 0.15)
				)
				(justify right bottom)
			)
		)
		(property "Datasheet" "https://industrial.panasonic.com/cdbs/www-data/pdf/RDA0000/AOA0000C301.pdf"
			(at 0 0 180)
			(layer "F.Fab")
			(hide yes)
			(effects
				(font
					(size 1.27 1.27)
					(thickness 0.15)
				)
			)
		)
		(property "Manufacturer" "Panasonic"
			(at 0 0 180)
			(unlocked yes)
			(layer "F.Fab")
			(hide yes)
			(effects
				(font
					(size 1 1)
					(thickness 0.15)
				)
			)
		)
		(property "MPN" "ERJ2GE0R00X"
			(at 0 0 180)
			(unlocked yes)
			(layer "F.Fab")
			(hide yes)
			(effects
				(font
					(size 1 1)
					(thickness 0.15)
				)
			)
		)
		(property "Val" "0R"
			(at 0 0 180)
			(unlocked yes)
			(layer "F.Fab")
			(hide yes)
			(effects
				(font
					(size 1 1)
					(thickness 0.15)
				)
			)
		)
		(property "License" "Apache-2.0"
			(at 0 0 180)
			(unlocked yes)
			(layer "F.Fab")
			(hide yes)
			(effects
				(font
					(size 1 1)
					(thickness 0.15)
				)
			)
		)
		(property "Author" "Antmicro"
			(at 0 0 180)
			(unlocked yes)
			(layer "F.Fab")
			(hide yes)
			(effects
				(font
					(size 1 1)
					(thickness 0.15)
				)
			)
		)
		(property "Tolerance" "~"
			(at 0 0 180)
			(unlocked yes)
			(layer "F.Fab")
			(hide yes)
			(effects
				(font
					(size 1 1)
					(thickness 0.15)
				)
			)
		)
		(property "Current" "1A"
			(at 0 0 180)
			(unlocked yes)
			(layer "F.Fab")
			(hide yes)
			(effects
				(font
					(size 1 1)
					(thickness 0.15)
				)
			)
		)
		(sheetname "/Supply/DC-DC IO/")
		(sheetfile "dc-dc-io.kicad_sch")
		(attr smd)
		(fp_rect
			(start -0.925 -0.47)
			(end 0.925 0.47)
			(stroke
				(width 0.05)
				(type default)
			)
			(fill no)
			(layer "F.CrtYd")
		)
		(fp_rect
			(start -0.5 -0.25)
			(end 0.5 0.25)
			(stroke
				(width 0.15)
				(type solid)
			)
			(fill no)
			(layer "F.Fab")
		)
		(fp_text user "Author: Antmicro"
			(at -0.95 4.169 180)
			(layer "F.Fab")
			(effects
				(font
					(size 0.7 0.7)
					(thickness 0.15)
				)
				(justify left bottom)
			)
		)
		(fp_text user "${REFERENCE}"
			(at -0.95 3.168 180)
			(layer "F.Fab")
			(effects
				(font
					(size 0.7 0.7)
					(thickness 0.15)
				)
				(justify left bottom)
			)
		)
		(fp_text user "License: Apache-2.0"
			(at -0.95 5.169 180)
			(layer "F.Fab")
			(effects
				(font
					(size 0.7 0.7)
					(thickness 0.15)
				)
				(justify left bottom)
			)
		)
		(pad "1" smd roundrect
			(at -0.48 0 180)
			(size 0.59 0.64)
			(layers "F.Cu" "F.Mask" "F.Paste")
			(roundrect_rratio 0.25)
			(net 714 "/Supply/DC-DC IO/FB5")
			(pintype "passive")
		)
		(pad "2" smd roundrect
			(at 0.48 0 180)
			(size 0.59 0.64)
			(layers "F.Cu" "F.Mask" "F.Paste")
			(roundrect_rratio 0.25)
			(net 45 "/Supply/DC-DC IO/3V3_local")
			(pintype "passive")
		)
	)
	(footprint "antmicro-footprints:R_0402_1005Metric"
		(layer "F.Cu")
		(at 140.824499 178.449 90)
		(descr "Resistor SMD 0402")
		(tags "resistor SMD 0402")
		(property "Reference" "R79"
			(at -1.122484 1.400501 90)
			(layer "F.SilkS")
			(effects
				(font
					(size 0.7 0.7)
					(thickness 0.15)
				)
				(justify left bottom)
			)
		)
		(property "Value" "R_10k_0402"
			(at -1.011843 1.772047 90)
			(layer "F.Fab")
			(effects
				(font
					(size 0.7 0.7)
					(thickness 0.15)
				)
				(justify left bottom)
			)
		)
		(property "Datasheet" "https://www.bourns.com/docs/product-datasheets/cr.pdf"
			(at 0 0 90)
			(layer "F.Fab")
			(hide yes)
			(effects
				(font
					(size 1.27 1.27)
					(thickness 0.15)
				)
			)
		)
		(property "Manufacturer" "Bourns"
			(at 0 0 90)
			(unlocked yes)
			(layer "F.Fab")
			(hide yes)
			(effects
				(font
					(size 1 1)
					(thickness 0.15)
				)
			)
		)
		(property "MPN" "CR0402-FX-1002GLF"
			(at 0 0 90)
			(unlocked yes)
			(layer "F.Fab")
			(hide yes)
			(effects
				(font
					(size 1 1)
					(thickness 0.15)
				)
			)
		)
		(property "Val" "10k"
			(at 0 0 90)
			(unlocked yes)
			(layer "F.Fab")
			(hide yes)
			(effects
				(font
					(size 1 1)
					(thickness 0.15)
				)
			)
		)
		(property "License" "Apache-2.0"
			(at 0 0 90)
			(unlocked yes)
			(layer "F.Fab")
			(hide yes)
			(effects
				(font
					(size 1 1)
					(thickness 0.15)
				)
			)
		)
		(property "Author" "Antmicro"
			(at 0 0 90)
			(unlocked yes)
			(layer "F.Fab")
			(hide yes)
			(effects
				(font
					(size 1 1)
					(thickness 0.15)
				)
			)
		)
		(property "Tolerance" "1%"
			(at 0 0 90)
			(unlocked yes)
			(layer "F.Fab")
			(hide yes)
			(effects
				(font
					(size 1 1)
					(thickness 0.15)
				)
			)
		)
		(sheetname "/Debug FTDI + VNA/")
		(sheetfile "debug-ftdi.kicad_sch")
		(attr smd)
		(fp_rect
			(start -0.925 -0.47)
			(end 0.925 0.47)
			(stroke
				(width 0.05)
				(type default)
			)
			(fill no)
			(layer "F.CrtYd")
		)
		(fp_rect
			(start -0.5 -0.25)
			(end 0.5 0.25)
			(stroke
				(width 0.15)
				(type solid)
			)
			(fill no)
			(layer "F.Fab")
		)
		(fp_text user "Author: Antmicro"
			(at -0.95 4.169 90)
			(layer "F.Fab")
			(effects
				(font
					(size 0.7 0.7)
					(thickness 0.15)
				)
				(justify left bottom)
			)
		)
		(fp_text user "License: Apache-2.0"
			(at -0.95 5.169 90)
			(layer "F.Fab")
			(effects
				(font
					(size 0.7 0.7)
					(thickness 0.15)
				)
				(justify left bottom)
			)
		)
		(fp_text user "${REFERENCE}"
			(at -0.95 3.168 90)
			(layer "F.Fab")
			(effects
				(font
					(size 0.7 0.7)
					(thickness 0.15)
				)
				(justify left bottom)
			)
		)
		(pad "1" smd roundrect
			(at -0.48 0 90)
			(size 0.59 0.64)
			(layers "F.Cu" "F.Mask" "F.Paste")
			(roundrect_rratio 0.25)
			(net 6 "/Debug FTDI + VNA/FTDI_3V3")
			(pintype "passive")
		)
		(pad "2" smd roundrect
			(at 0.48 0 90)
			(size 0.59 0.64)
			(layers "F.Cu" "F.Mask" "F.Paste")
			(roundrect_rratio 0.25)
			(net 372 "/Debug FTDI + VNA/FTDI_PWREN")
			(pintype "passive")
		)
	)
	(footprint "antmicro-footprints:C_0603_1608Metric"
		(layer "F.Cu")
		(at 232.65 168.755 180)
		(descr "Capacitor SMD 0603")
		(tags "capacitor 0603")
		(property "Reference" "C262"
			(at -4.025 -0.395001 0)
			(layer "F.SilkS")
			(effects
				(font
					(size 0.7 0.7)
					(thickness 0.15)
				)
				(justify right bottom)
			)
		)
		(property "Value" "C_22u_0603"
			(at -1.42757 1.770288 0)
			(layer "F.Fab")
			(effects
				(font
					(size 0.7 0.7)
					(thickness 0.15)
				)
				(justify right bottom)
			)
		)
		(property "Datasheet" "https://www.murata.com/products/productdetail?partno=GRM188R60J226MEA0%23"
			(at 0 0 180)
			(layer "F.Fab")
			(hide yes)
			(effects
				(font
					(size 1.27 1.27)
					(thickness 0.15)
				)
			)
		)
		(property "Manufacturer" "Murata"
			(at 0 0 180)
			(unlocked yes)
			(layer "F.Fab")
			(hide yes)
			(effects
				(font
					(size 1 1)
					(thickness 0.15)
				)
			)
		)
		(property "MPN" "GRM188R60J226MEA0D"
			(at 0 0 180)
			(unlocked yes)
			(layer "F.Fab")
			(hide yes)
			(effects
				(font
					(size 1 1)
					(thickness 0.15)
				)
			)
		)
		(property "Val" "22u"
			(at 0 0 180)
			(unlocked yes)
			(layer "F.Fab")
			(hide yes)
			(effects
				(font
					(size 1 1)
					(thickness 0.15)
				)
			)
		)
		(property "License" "Apache-2.0"
			(at 0 0 180)
			(unlocked yes)
			(layer "F.Fab")
			(hide yes)
			(effects
				(font
					(size 1 1)
					(thickness 0.15)
				)
			)
		)
		(property "Author" "Antmicro"
			(at 0 0 180)
			(unlocked yes)
			(layer "F.Fab")
			(hide yes)
			(effects
				(font
					(size 1 1)
					(thickness 0.15)
				)
			)
		)
		(property "Voltage" ""
			(at 0 0 180)
			(unlocked yes)
			(layer "F.Fab")
			(hide yes)
			(effects
				(font
					(size 1 1)
					(thickness 0.15)
				)
			)
		)
		(property "Dielectric" ""
			(at 0 0 180)
			(unlocked yes)
			(layer "F.Fab")
			(hide yes)
			(effects
				(font
					(size 1 1)
					(thickness 0.15)
				)
			)
		)
		(sheetname "/Supply/DC-DC VCCINT/")
		(sheetfile "dc-dc-vccint.kicad_sch")
		(attr smd)
		(fp_line
			(start -0.15 0.4)
			(end 0.15 0.4)
			(stroke
				(width 0.15)
				(type solid)
			)
			(layer "F.SilkS")
		)
		(fp_line
			(start -0.15 -0.4)
			(end 0.15 -0.4)
			(stroke
				(width 0.15)
				(type solid)
			)
			(layer "F.SilkS")
		)
		(fp_rect
			(start -1.25 -0.65)
			(end 1.25 0.65)
			(stroke
				(width 0.05)
				(type solid)
			)
			(fill no)
			(layer "F.CrtYd")
		)
		(fp_rect
			(start -0.8 -0.4)
			(end 0.8 0.4)
			(stroke
				(width 0.15)
				(type solid)
			)
			(fill no)
			(layer "F.Fab")
		)
		(fp_text user "${REFERENCE}"
			(at -1.682 3.895 180)
			(layer "F.Fab")
			(effects
				(font
					(size 0.7 0.7)
					(thickness 0.15)
				)
				(justify left bottom)
			)
		)
		(fp_text user "License: Apache-2.0"
			(at -1.682 5.895 180)
			(layer "F.Fab")
			(effects
				(font
					(size 0.7 0.7)
					(thickness 0.15)
				)
				(justify left bottom)
			)
		)
		(fp_text user "Author: Antmicro"
			(at -1.682 4.894 180)
			(layer "F.Fab")
			(effects
				(font
					(size 0.7 0.7)
					(thickness 0.15)
				)
				(justify left bottom)
			)
		)
		(pad "1" smd roundrect
			(at -0.7 0 180)
			(size 0.8 1)
			(layers "F.Cu" "F.Mask" "F.Paste")
			(roundrect_rratio 0.2)
			(net 1 "GND")
			(pintype "passive")
		)
		(pad "2" smd roundrect
			(at 0.7 0 180)
			(size 0.8 1)
			(layers "F.Cu" "F.Mask" "F.Paste")
			(roundrect_rratio 0.2)
			(net 224 "/Supply/DC-DC VCCINT/0V85_REG1")
			(pintype "passive")
		)
	)
	(footprint "antmicro-footprints:C_0603_1608Metric"
		(layer "F.Cu")
		(at 248.87 171.372001 90)
		(descr "Capacitor SMD 0603")
		(tags "capacitor 0603")
		(property "Reference" "C186"
			(at 1.272001 0.48 90)
			(layer "F.SilkS")
			(effects
				(font
					(size 0.7 0.7)
					(thickness 0.15)
				)
				(justify left bottom)
			)
		)
		(property "Value" "C_22u_0603"
			(at -1.42757 1.770288 90)
			(layer "F.Fab")
			(effects
				(font
					(size 0.7 0.7)
					(thickness 0.15)
				)
				(justify left bottom)
			)
		)
		(property "Datasheet" "https://www.murata.com/products/productdetail?partno=GRM188R60J226MEA0%23"
			(at 0 0 90)
			(layer "F.Fab")
			(hide yes)
			(effects
				(font
					(size 1.27 1.27)
					(thickness 0.15)
				)
			)
		)
		(property "Manufacturer" "Murata"
			(at 0 0 90)
			(unlocked yes)
			(layer "F.Fab")
			(hide yes)
			(effects
				(font
					(size 1 1)
					(thickness 0.15)
				)
			)
		)
		(property "MPN" "GRM188R60J226MEA0D"
			(at 0 0 90)
			(unlocked yes)
			(layer "F.Fab")
			(hide yes)
			(effects
				(font
					(size 1 1)
					(thickness 0.15)
				)
			)
		)
		(property "Val" "22u"
			(at 0 0 90)
			(unlocked yes)
			(layer "F.Fab")
			(hide yes)
			(effects
				(font
					(size 1 1)
					(thickness 0.15)
				)
			)
		)
		(property "License" "Apache-2.0"
			(at 0 0 90)
			(unlocked yes)
			(layer "F.Fab")
			(hide yes)
			(effects
				(font
					(size 1 1)
					(thickness 0.15)
				)
			)
		)
		(property "Author" "Antmicro"
			(at 0 0 90)
			(unlocked yes)
			(layer "F.Fab")
			(hide yes)
			(effects
				(font
					(size 1 1)
					(thickness 0.15)
				)
			)
		)
		(property "Voltage" ""
			(at 0 0 90)
			(unlocked yes)
			(layer "F.Fab")
			(hide yes)
			(effects
				(font
					(size 1 1)
					(thickness 0.15)
				)
			)
		)
		(property "Dielectric" ""
			(at 0 0 90)
			(unlocked yes)
			(layer "F.Fab")
			(hide yes)
			(effects
				(font
					(size 1 1)
					(thickness 0.15)
				)
			)
		)
		(sheetname "/Supply/DC-DC AUX, MGT/")
		(sheetfile "dc-dc-aux-mgt.kicad_sch")
		(attr smd)
		(fp_line
			(start -0.15 -0.4)
			(end 0.15 -0.4)
			(stroke
				(width 0.15)
				(type solid)
			)
			(layer "F.SilkS")
		)
		(fp_line
			(start -0.15 0.4)
			(end 0.15 0.4)
			(stroke
				(width 0.15)
				(type solid)
			)
			(layer "F.SilkS")
		)
		(fp_rect
			(start -1.25 -0.65)
			(end 1.25 0.65)
			(stroke
				(width 0.05)
				(type solid)
			)
			(fill no)
			(layer "F.CrtYd")
		)
		(fp_rect
			(start -0.8 -0.4)
			(end 0.8 0.4)
			(stroke
				(width 0.15)
				(type solid)
			)
			(fill no)
			(layer "F.Fab")
		)
		(fp_text user "License: Apache-2.0"
			(at -1.682 5.895 90)
			(layer "F.Fab")
			(effects
				(font
					(size 0.7 0.7)
					(thickness 0.15)
				)
				(justify left bottom)
			)
		)
		(fp_text user "Author: Antmicro"
			(at -1.682 4.894 90)
			(layer "F.Fab")
			(effects
				(font
					(size 0.7 0.7)
					(thickness 0.15)
				)
				(justify left bottom)
			)
		)
		(fp_text user "${REFERENCE}"
			(at -1.682 3.895 90)
			(layer "F.Fab")
			(effects
				(font
					(size 0.7 0.7)
					(thickness 0.15)
				)
				(justify left bottom)
			)
		)
		(pad "1" smd roundrect
			(at -0.7 0 90)
			(size 0.8 1)
			(layers "F.Cu" "F.Mask" "F.Paste")
			(roundrect_rratio 0.2)
			(net 1 "GND")
			(pintype "passive")
		)
		(pad "2" smd roundrect
			(at 0.7 0 90)
			(size 0.8 1)
			(layers "F.Cu" "F.Mask" "F.Paste")
			(roundrect_rratio 0.2)
			(net 48 "/Supply/DC-DC AUX, MGT/MGTAVTT_local")
			(pintype "passive")
		)
	)
	(footprint "antmicro-footprints:C_0402_1005Metric"
		(layer "F.Cu")
		(at 232 179.175 180)
		(descr "Capacitor SMD 0402")
		(tags "capacitor SMD 0402")
		(property "Reference" "C213"
			(at 0.94 -0.465 0)
			(layer "F.SilkS")
			(effects
				(font
					(size 0.7 0.7)
					(thickness 0.15)
				)
				(justify right bottom)
			)
		)
		(property "Value" "C_1u_25V_0402"
			(at -1.022927 2.155213 0)
			(layer "F.Fab")
			(effects
				(font
					(size 0.7 0.7)
					(thickness 0.15)
				)
				(justify right bottom)
			)
		)
		(property "Datasheet" "https://www.murata.com/products/productdetail?partno=GRM155R61E105KE11%23"
			(at 0 0 180)
			(layer "F.Fab")
			(hide yes)
			(effects
				(font
					(size 1.27 1.27)
					(thickness 0.15)
				)
			)
		)
		(property "MPN" "GRM155R61E105KE11J"
			(at 0 0 180)
			(unlocked yes)
			(layer "F.Fab")
			(hide yes)
			(effects
				(font
					(size 1 1)
					(thickness 0.15)
				)
			)
		)
		(property "Manufacturer" "Murata"
			(at 0 0 180)
			(unlocked yes)
			(layer "F.Fab")
			(hide yes)
			(effects
				(font
					(size 1 1)
					(thickness 0.15)
				)
			)
		)
		(property "License" "Apache-2.0"
			(at 0 0 180)
			(unlocked yes)
			(layer "F.Fab")
			(hide yes)
			(effects
				(font
					(size 1 1)
					(thickness 0.15)
				)
			)
		)
		(property "Author" "Antmicro"
			(at 0 0 180)
			(unlocked yes)
			(layer "F.Fab")
			(hide yes)
			(effects
				(font
					(size 1 1)
					(thickness 0.15)
				)
			)
		)
		(property "Val" "1u"
			(at 0 0 180)
			(unlocked yes)
			(layer "F.Fab")
			(hide yes)
			(effects
				(font
					(size 1 1)
					(thickness 0.15)
				)
			)
		)
		(property "Voltage" "25V"
			(at 0 0 180)
			(unlocked yes)
			(layer "F.Fab")
			(hide yes)
			(effects
				(font
					(size 1 1)
					(thickness 0.15)
				)
			)
		)
		(property "Dielectric" "X5R"
			(at 0 0 180)
			(unlocked yes)
			(layer "F.Fab")
			(hide yes)
			(effects
				(font
					(size 1 1)
					(thickness 0.15)
				)
			)
		)
		(sheetname "/Supply/DC-DC VCCINT/")
		(sheetfile "dc-dc-vccint.kicad_sch")
		(attr smd)
		(fp_rect
			(start -0.925 -0.47)
			(end 0.925 0.47)
			(stroke
				(width 0.05)
				(type default)
			)
			(fill no)
			(layer "F.CrtYd")
		)
		(fp_line
			(start 0.504 0.248)
			(end -0.494 0.248)
			(stroke
				(width 0.15)
				(type solid)
			)
			(layer "F.Fab")
		)
		(fp_line
			(start 0.504 -0.25)
			(end 0.504 0.248)
			(stroke
				(width 0.15)
				(type solid)
			)
			(layer "F.Fab")
		)
		(fp_line
			(start -0.494 0.248)
			(end -0.494 -0.25)
			(stroke
				(width 0.15)
				(type solid)
			)
			(layer "F.Fab")
		)
		(fp_line
			(start -0.494 -0.25)
			(end 0.504 -0.25)
			(stroke
				(width 0.15)
				(type solid)
			)
			(layer "F.Fab")
		)
		(fp_text user "Author: Antmicro"
			(at -0.939 3.399 180)
			(layer "F.Fab")
			(effects
				(font
					(size 0.7 0.7)
					(thickness 0.15)
				)
				(justify left bottom)
			)
		)
		(fp_text user "${REFERENCE}"
			(at -0.939 4.599 180)
			(layer "F.Fab")
			(effects
				(font
					(size 0.7 0.7)
					(thickness 0.15)
				)
				(justify left bottom)
			)
		)
		(fp_text user "License: Apache-2.0"
			(at -0.939 5.799 180)
			(layer "F.Fab")
			(effects
				(font
					(size 0.7 0.7)
					(thickness 0.15)
				)
				(justify left bottom)
			)
		)
		(pad "1" smd roundrect
			(at -0.48 0 180)
			(size 0.59 0.64)
			(layers "F.Cu" "F.Mask" "F.Paste")
			(roundrect_rratio 0.25)
			(net 1 "GND")
			(pintype "passive")
		)
		(pad "2" smd roundrect
			(at 0.48 0 180)
			(size 0.59 0.64)
			(layers "F.Cu" "F.Mask" "F.Paste")
			(roundrect_rratio 0.25)
			(net 35 "VDC")
			(pintype "passive")
		)
	)
	(footprint "antmicro-footprints:C_0402_1005Metric"
		(layer "F.Cu")
		(at 235.57 132.32 90)
		(descr "Capacitor SMD 0402")
		(tags "capacitor SMD 0402")
		(property "Reference" "C166"
			(at -4.15 0.17 90)
			(layer "F.SilkS")
			(effects
				(font
					(size 0.7 0.7)
					(thickness 0.15)
				)
				(justify left bottom)
			)
		)
		(property "Value" "C_100n_0402"
			(at -1.022927 2.155213 90)
			(layer "F.Fab")
			(effects
				(font
					(size 0.7 0.7)
					(thickness 0.15)
				)
				(justify left bottom)
			)
		)
		(property "Datasheet" "https://www.murata.com/products/productdetail?partno=GRM155R61H104KE14%23"
			(at 0 0 90)
			(layer "F.Fab")
			(hide yes)
			(effects
				(font
					(size 1.27 1.27)
					(thickness 0.15)
				)
			)
		)
		(property "Manufacturer" "Murata"
			(at 0 0 90)
			(unlocked yes)
			(layer "F.Fab")
			(hide yes)
			(effects
				(font
					(size 1 1)
					(thickness 0.15)
				)
			)
		)
		(property "MPN" "GRM155R61H104KE14D"
			(at 0 0 90)
			(unlocked yes)
			(layer "F.Fab")
			(hide yes)
			(effects
				(font
					(size 1 1)
					(thickness 0.15)
				)
			)
		)
		(property "Val" "100n"
			(at 0 0 90)
			(unlocked yes)
			(layer "F.Fab")
			(hide yes)
			(effects
				(font
					(size 1 1)
					(thickness 0.15)
				)
			)
		)
		(property "License" "Apache-2.0"
			(at 0 0 90)
			(unlocked yes)
			(layer "F.Fab")
			(hide yes)
			(effects
				(font
					(size 1 1)
					(thickness 0.15)
				)
			)
		)
		(property "Author" "Antmicro"
			(at 0 0 90)
			(unlocked yes)
			(layer "F.Fab")
			(hide yes)
			(effects
				(font
					(size 1 1)
					(thickness 0.15)
				)
			)
		)
		(property "Voltage" "50V"
			(at 0 0 90)
			(unlocked yes)
			(layer "F.Fab")
			(hide yes)
			(effects
				(font
					(size 1 1)
					(thickness 0.15)
				)
			)
		)
		(property "Dielectric" "X5R"
			(at 0 0 90)
			(unlocked yes)
			(layer "F.Fab")
			(hide yes)
			(effects
				(font
					(size 1 1)
					(thickness 0.15)
				)
			)
		)
		(sheetname "/I^{2}C + I3C/")
		(sheetfile "i2c.kicad_sch")
		(attr smd)
		(fp_rect
			(start -0.925 -0.47)
			(end 0.925 0.47)
			(stroke
				(width 0.05)
				(type default)
			)
			(fill no)
			(layer "F.CrtYd")
		)
		(fp_line
			(start 0.504 -0.25)
			(end 0.504 0.248)
			(stroke
				(width 0.15)
				(type solid)
			)
			(layer "F.Fab")
		)
		(fp_line
			(start -0.494 -0.25)
			(end 0.504 -0.25)
			(stroke
				(width 0.15)
				(type solid)
			)
			(layer "F.Fab")
		)
		(fp_line
			(start 0.504 0.248)
			(end -0.494 0.248)
			(stroke
				(width 0.15)
				(type solid)
			)
			(layer "F.Fab")
		)
		(fp_line
			(start -0.494 0.248)
			(end -0.494 -0.25)
			(stroke
				(width 0.15)
				(type solid)
			)
			(layer "F.Fab")
		)
		(fp_text user "Author: Antmicro"
			(at -0.939 3.399 90)
			(layer "F.Fab")
			(effects
				(font
					(size 0.7 0.7)
					(thickness 0.15)
				)
				(justify left bottom)
			)
		)
		(fp_text user "${REFERENCE}"
			(at -0.939 4.599 90)
			(layer "F.Fab")
			(effects
				(font
					(size 0.7 0.7)
					(thickness 0.15)
				)
				(justify left bottom)
			)
		)
		(fp_text user "License: Apache-2.0"
			(at -0.939 5.799 90)
			(layer "F.Fab")
			(effects
				(font
					(size 0.7 0.7)
					(thickness 0.15)
				)
				(justify left bottom)
			)
		)
		(pad "1" smd roundrect
			(at -0.48 0 90)
			(size 0.59 0.64)
			(layers "F.Cu" "F.Mask" "F.Paste")
			(roundrect_rratio 0.25)
			(net 201 "VDDSPD")
			(pintype "passive")
		)
		(pad "2" smd roundrect
			(at 0.48 0 90)
			(size 0.59 0.64)
			(layers "F.Cu" "F.Mask" "F.Paste")
			(roundrect_rratio 0.25)
			(net 1 "GND")
			(pintype "passive")
		)
	)
	(footprint "antmicro-footprints:C_0603_1608Metric"
		(layer "F.Cu")
		(at 250.293 156.521 -90)
		(descr "Capacitor SMD 0603")
		(tags "capacitor 0603")
		(property "Reference" "C190"
			(at 1.329 -0.557 90)
			(layer "F.SilkS")
			(effects
				(font
					(size 0.7 0.7)
					(thickness 0.15)
				)
				(justify right bottom)
			)
		)
		(property "Value" "C_22u_0603"
			(at -1.42757 1.770288 90)
			(layer "F.Fab")
			(effects
				(font
					(size 0.7 0.7)
					(thickness 0.15)
				)
				(justify right bottom)
			)
		)
		(property "Datasheet" "https://www.murata.com/products/productdetail?partno=GRM188R60J226MEA0%23"
			(at 0 0 270)
			(layer "F.Fab")
			(hide yes)
			(effects
				(font
					(size 1.27 1.27)
					(thickness 0.15)
				)
			)
		)
		(property "Manufacturer" "Murata"
			(at 0 0 270)
			(unlocked yes)
			(layer "F.Fab")
			(hide yes)
			(effects
				(font
					(size 1 1)
					(thickness 0.15)
				)
			)
		)
		(property "MPN" "GRM188R60J226MEA0D"
			(at 0 0 270)
			(unlocked yes)
			(layer "F.Fab")
			(hide yes)
			(effects
				(font
					(size 1 1)
					(thickness 0.15)
				)
			)
		)
		(property "Val" "22u"
			(at 0 0 270)
			(unlocked yes)
			(layer "F.Fab")
			(hide yes)
			(effects
				(font
					(size 1 1)
					(thickness 0.15)
				)
			)
		)
		(property "License" "Apache-2.0"
			(at 0 0 270)
			(unlocked yes)
			(layer "F.Fab")
			(hide yes)
			(effects
				(font
					(size 1 1)
					(thickness 0.15)
				)
			)
		)
		(property "Author" "Antmicro"
			(at 0 0 270)
			(unlocked yes)
			(layer "F.Fab")
			(hide yes)
			(effects
				(font
					(size 1 1)
					(thickness 0.15)
				)
			)
		)
		(property "Voltage" ""
			(at 0 0 270)
			(unlocked yes)
			(layer "F.Fab")
			(hide yes)
			(effects
				(font
					(size 1 1)
					(thickness 0.15)
				)
			)
		)
		(property "Dielectric" ""
			(at 0 0 270)
			(unlocked yes)
			(layer "F.Fab")
			(hide yes)
			(effects
				(font
					(size 1 1)
					(thickness 0.15)
				)
			)
		)
		(sheetname "/Supply/DC-DC IO/")
		(sheetfile "dc-dc-io.kicad_sch")
		(attr smd)
		(fp_line
			(start -0.15 0.4)
			(end 0.15 0.4)
			(stroke
				(width 0.15)
				(type solid)
			)
			(layer "F.SilkS")
		)
		(fp_line
			(start -0.15 -0.4)
			(end 0.15 -0.4)
			(stroke
				(width 0.15)
				(type solid)
			)
			(layer "F.SilkS")
		)
		(fp_rect
			(start -1.25 -0.65)
			(end 1.25 0.65)
			(stroke
				(width 0.05)
				(type solid)
			)
			(fill no)
			(layer "F.CrtYd")
		)
		(fp_rect
			(start -0.8 -0.4)
			(end 0.8 0.4)
			(stroke
				(width 0.15)
				(type solid)
			)
			(fill no)
			(layer "F.Fab")
		)
		(fp_text user "License: Apache-2.0"
			(at -1.682 5.895 270)
			(layer "F.Fab")
			(effects
				(font
					(size 0.7 0.7)
					(thickness 0.15)
				)
				(justify left bottom)
			)
		)
		(fp_text user "Author: Antmicro"
			(at -1.682 4.894 270)
			(layer "F.Fab")
			(effects
				(font
					(size 0.7 0.7)
					(thickness 0.15)
				)
				(justify left bottom)
			)
		)
		(fp_text user "${REFERENCE}"
			(at -1.682 3.895 270)
			(layer "F.Fab")
			(effects
				(font
					(size 0.7 0.7)
					(thickness 0.15)
				)
				(justify left bottom)
			)
		)
		(pad "1" smd roundrect
			(at -0.7 0 270)
			(size 0.8 1)
			(layers "F.Cu" "F.Mask" "F.Paste")
			(roundrect_rratio 0.2)
			(net 1 "GND")
			(pintype "passive")
		)
		(pad "2" smd roundrect
			(at 0.7 0 270)
			(size 0.8 1)
			(layers "F.Cu" "F.Mask" "F.Paste")
			(roundrect_rratio 0.2)
			(net 45 "/Supply/DC-DC IO/3V3_local")
			(pintype "passive")
		)
	)
	(footprint "antmicro-footprints:R_0402_1005Metric"
		(layer "F.Cu")
		(at 260.55 169.3945 90)
		(descr "Resistor SMD 0402")
		(tags "resistor SMD 0402")
		(property "Reference" "R163"
			(at 2.1945 0.35 90)
			(layer "F.SilkS")
			(effects
				(font
					(size 0.7 0.7)
					(thickness 0.15)
				)
				(justify left bottom)
			)
		)
		(property "Value" "R_0R_0402"
			(at -1.011843 1.772047 90)
			(layer "F.Fab")
			(effects
				(font
					(size 0.7 0.7)
					(thickness 0.15)
				)
				(justify left bottom)
			)
		)
		(property "Datasheet" "https://industrial.panasonic.com/cdbs/www-data/pdf/RDA0000/AOA0000C301.pdf"
			(at 0 0 90)
			(layer "F.Fab")
			(hide yes)
			(effects
				(font
					(size 1.27 1.27)
					(thickness 0.15)
				)
			)
		)
		(property "Manufacturer" "Panasonic"
			(at 0 0 90)
			(unlocked yes)
			(layer "F.Fab")
			(hide yes)
			(effects
				(font
					(size 1 1)
					(thickness 0.15)
				)
			)
		)
		(property "MPN" "ERJ2GE0R00X"
			(at 0 0 90)
			(unlocked yes)
			(layer "F.Fab")
			(hide yes)
			(effects
				(font
					(size 1 1)
					(thickness 0.15)
				)
			)
		)
		(property "Val" "0R"
			(at 0 0 90)
			(unlocked yes)
			(layer "F.Fab")
			(hide yes)
			(effects
				(font
					(size 1 1)
					(thickness 0.15)
				)
			)
		)
		(property "License" "Apache-2.0"
			(at 0 0 90)
			(unlocked yes)
			(layer "F.Fab")
			(hide yes)
			(effects
				(font
					(size 1 1)
					(thickness 0.15)
				)
			)
		)
		(property "Author" "Antmicro"
			(at 0 0 90)
			(unlocked yes)
			(layer "F.Fab")
			(hide yes)
			(effects
				(font
					(size 1 1)
					(thickness 0.15)
				)
			)
		)
		(property "Tolerance" "~"
			(at 0 0 90)
			(unlocked yes)
			(layer "F.Fab")
			(hide yes)
			(effects
				(font
					(size 1 1)
					(thickness 0.15)
				)
			)
		)
		(property "Current" "1A"
			(at 0 0 90)
			(unlocked yes)
			(layer "F.Fab")
			(hide yes)
			(effects
				(font
					(size 1 1)
					(thickness 0.15)
				)
			)
		)
		(sheetname "/Supply/DC-DC AUX, MGT/")
		(sheetfile "dc-dc-aux-mgt.kicad_sch")
		(attr smd)
		(fp_rect
			(start -0.925 -0.47)
			(end 0.925 0.47)
			(stroke
				(width 0.05)
				(type default)
			)
			(fill no)
			(layer "F.CrtYd")
		)
		(fp_rect
			(start -0.5 -0.25)
			(end 0.5 0.25)
			(stroke
				(width 0.15)
				(type solid)
			)
			(fill no)
			(layer "F.Fab")
		)
		(fp_text user "License: Apache-2.0"
			(at -0.95 5.169 90)
			(layer "F.Fab")
			(effects
				(font
					(size 0.7 0.7)
					(thickness 0.15)
				)
				(justify left bottom)
			)
		)
		(fp_text user "${REFERENCE}"
			(at -0.95 3.168 90)
			(layer "F.Fab")
			(effects
				(font
					(size 0.7 0.7)
					(thickness 0.15)
				)
				(justify left bottom)
			)
		)
		(fp_text user "Author: Antmicro"
			(at -0.95 4.169 90)
			(layer "F.Fab")
			(effects
				(font
					(size 0.7 0.7)
					(thickness 0.15)
				)
				(justify left bottom)
			)
		)
		(pad "1" smd roundrect
			(at -0.48 0 90)
			(size 0.59 0.64)
			(layers "F.Cu" "F.Mask" "F.Paste")
			(roundrect_rratio 0.25)
			(net 716 "/Supply/DC-DC AUX, MGT/FB3")
			(pintype "passive")
		)
		(pad "2" smd roundrect
			(at 0.48 0 90)
			(size 0.59 0.64)
			(layers "F.Cu" "F.Mask" "F.Paste")
			(roundrect_rratio 0.25)
			(net 47 "/Supply/DC-DC AUX, MGT/MGTAVCC_local")
			(pintype "passive")
		)
	)
	(footprint "antmicro-footprints:R_0402_1005Metric"
		(layer "F.Cu")
		(at 123.681 166.1125 90)
		(descr "Resistor SMD 0402")
		(tags "resistor SMD 0402")
		(property "Reference" "R229"
			(at 0.9125 3.969 90)
			(layer "F.SilkS")
			(effects
				(font
					(size 0.7 0.7)
					(thickness 0.15)
				)
				(justify left bottom)
			)
		)
		(property "Value" "R_64k9_0402"
			(at -1.011843 1.772047 90)
			(layer "F.Fab")
			(effects
				(font
					(size 0.7 0.7)
					(thickness 0.15)
				)
				(justify left bottom)
			)
		)
		(property "Datasheet" "https://www.bourns.com/docs/product-datasheets/cr.pdf"
			(at 0 0 90)
			(layer "F.Fab")
			(hide yes)
			(effects
				(font
					(size 1.27 1.27)
					(thickness 0.15)
				)
			)
		)
		(property "MPN" "CR0402-FX-6492GLF"
			(at 0 0 90)
			(unlocked yes)
			(layer "F.Fab")
			(hide yes)
			(effects
				(font
					(size 1 1)
					(thickness 0.15)
				)
			)
		)
		(property "Manufacturer" "Bourns"
			(at 0 0 90)
			(unlocked yes)
			(layer "F.Fab")
			(hide yes)
			(effects
				(font
					(size 1 1)
					(thickness 0.15)
				)
			)
		)
		(property "License" "Apache-2.0"
			(at 0 0 90)
			(unlocked yes)
			(layer "F.Fab")
			(hide yes)
			(effects
				(font
					(size 1 1)
					(thickness 0.15)
				)
			)
		)
		(property "Author" "Antmicro"
			(at 0 0 90)
			(unlocked yes)
			(layer "F.Fab")
			(hide yes)
			(effects
				(font
					(size 1 1)
					(thickness 0.15)
				)
			)
		)
		(property "Val" "64k9"
			(at 0 0 90)
			(unlocked yes)
			(layer "F.Fab")
			(hide yes)
			(effects
				(font
					(size 1 1)
					(thickness 0.15)
				)
			)
		)
		(property "Tolerance" "1%"
			(at 0 0 90)
			(unlocked yes)
			(layer "F.Fab")
			(hide yes)
			(effects
				(font
					(size 1 1)
					(thickness 0.15)
				)
			)
		)
		(sheetname "/HDMI + SD Card/")
		(sheetfile "hdmi-sd-card.kicad_sch")
		(attr smd exclude_from_bom dnp)
		(fp_rect
			(start -0.925 -0.47)
			(end 0.925 0.47)
			(stroke
				(width 0.05)
				(type default)
			)
			(fill no)
			(layer "F.CrtYd")
		)
		(fp_rect
			(start -0.5 -0.25)
			(end 0.5 0.25)
			(stroke
				(width 0.15)
				(type solid)
			)
			(fill no)
			(layer "F.Fab")
		)
		(fp_text user "${REFERENCE}"
			(at -0.95 3.168 90)
			(layer "F.Fab")
			(effects
				(font
					(size 0.7 0.7)
					(thickness 0.15)
				)
				(justify left bottom)
			)
		)
		(fp_text user "Author: Antmicro"
			(at -0.95 4.169 90)
			(layer "F.Fab")
			(effects
				(font
					(size 0.7 0.7)
					(thickness 0.15)
				)
				(justify left bottom)
			)
		)
		(fp_text user "License: Apache-2.0"
			(at -0.95 5.169 90)
			(layer "F.Fab")
			(effects
				(font
					(size 0.7 0.7)
					(thickness 0.15)
				)
				(justify left bottom)
			)
		)
		(pad "1" smd roundrect
			(at -0.48 0 90)
			(size 0.59 0.64)
			(layers "F.Cu" "F.Mask" "F.Paste")
			(roundrect_rratio 0.25)
			(net 739 "/HDMI + SD Card/TX_TERM_CTL")
			(pintype "passive")
		)
		(pad "2" smd roundrect
			(at 0.48 0 90)
			(size 0.59 0.64)
			(layers "F.Cu" "F.Mask" "F.Paste")
			(roundrect_rratio 0.25)
			(net 151 "+3V3")
			(pintype "passive")
		)
	)
	(footprint "antmicro-footprints:NetTie-2_SMD_Pad0.127mm"
		(layer "F.Cu")
		(at 256.72 165.62 180)
		(descr "Net tie, 2 pin, 0.127mm  SMD pads")
		(tags "net tie")
		(property "Reference" "NT11"
			(at -0.128 -1.345 0)
			(layer "F.SilkS")
			(hide yes)
			(effects
				(font
					(size 0.7 0.7)
					(thickness 0.15)
				)
				(justify right bottom)
			)
		)
		(property "Value" "Net-Tie_P0.127mm"
			(at 0 1.199 0)
			(layer "F.Fab")
			(effects
				(font
					(size 0.7 0.7)
					(thickness 0.15)
				)
				(justify right bottom)
			)
		)
		(property "MPN" ""
			(at 0 0 180)
			(unlocked yes)
			(layer "F.Fab")
			(hide yes)
			(effects
				(font
					(size 1 1)
					(thickness 0.15)
				)
			)
		)
		(property "Manufacturer" ""
			(at 0 0 180)
			(unlocked yes)
			(layer "F.Fab")
			(hide yes)
			(effects
				(font
					(size 1 1)
					(thickness 0.15)
				)
			)
		)
		(property "Author" "Antmicro"
			(at 0 0 180)
			(unlocked yes)
			(layer "F.Fab")
			(hide yes)
			(effects
				(font
					(size 1 1)
					(thickness 0.15)
				)
			)
		)
		(property "License" "Apache-2.0"
			(at 0 0 180)
			(unlocked yes)
			(layer "F.Fab")
			(hide yes)
			(effects
				(font
					(size 1 1)
					(thickness 0.15)
				)
			)
		)
		(property ki_fp_filters "Net*Tie*")
		(sheetname "/Supply/DC-DC AUX, MGT/")
		(sheetfile "dc-dc-aux-mgt.kicad_sch")
		(attr through_hole exclude_from_pos_files exclude_from_bom)
		(net_tie_pad_groups "1, 2")
		(fp_poly
			(pts
				(xy -0.0635 -0.0635) (xy 0.0625 -0.0635) (xy 0.0625 0.0635) (xy -0.0635 0.0635)
			)
			(stroke
				(width 0)
				(type solid)
			)
			(fill yes)
			(layer "F.Cu")
		)
		(fp_poly
			(pts
				(xy 0.2 -0.16) (xy 0.29 -0.07) (xy 0.29 0.07) (xy 0.2 0.16) (xy -0.2 0.16) (xy -0.29 0.07) (xy -0.29 -0.06)
				(xy -0.19 -0.16)
			)
			(stroke
				(width 0.05)
				(type solid)
			)
			(fill no)
			(layer "F.CrtYd")
		)
		(fp_text user "License: Apache-2.0"
			(at -0.128 5.6 180)
			(layer "F.Fab")
			(effects
				(font
					(size 0.7 0.7)
					(thickness 0.15)
				)
				(justify left bottom)
			)
		)
		(fp_text user "${REFERENCE}"
			(at -0.128 3.2 180)
			(layer "F.Fab")
			(effects
				(font
					(size 0.7 0.7)
					(thickness 0.15)
				)
				(justify left bottom)
			)
		)
		(fp_text user "Author: Antmicro"
			(at -0.128 4.4 180)
			(layer "F.Fab")
			(effects
				(font
					(size 0.7 0.7)
					(thickness 0.15)
				)
				(justify left bottom)
			)
		)
		(pad "1" smd roundrect
			(at -0.127 0)
			(size 0.127 0.127)
			(layers "F.Cu")
			(roundrect_rratio 0.5)
			(chamfer_ratio 0)
			(chamfer top_left bottom_left)
			(net 691 "/Supply/DC-DC AUX, MGT/MGTAVCC_SEN_-")
			(pinfunction "1")
			(pintype "passive")
		)
		(pad "2" smd roundrect
			(at 0.126 0 180)
			(size 0.127 0.127)
			(layers "F.Cu")
			(roundrect_rratio 0.5)
			(chamfer_ratio 0)
			(chamfer top_left bottom_left)
			(net 820 "+0V9_MGTAVCC")
			(pinfunction "2")
			(pintype "passive")
		)
	)
	(footprint "antmicro-footprints:TP_1206_SMD_RCW-0C"
		(layer "F.Cu")
		(at 262.414 161.85 90)
		(property "Reference" "TP21"
			(at -2.29 -1.4 90)
			(layer "F.SilkS")
			(hide yes)
			(effects
				(font
					(size 0.7 0.7)
					(thickness 0.15)
				)
				(justify left bottom)
			)
		)
		(property "Value" "TP_1206_SMD_RCW-0C"
			(at -4.68 2.25 90)
			(layer "F.Fab")
			(effects
				(font
					(size 0.7 0.7)
					(thickness 0.15)
				)
				(justify left bottom)
			)
		)
		(property "Datasheet" "https://www.te.com/commerce/DocumentDelivery/DDEController?Action=srchrtrv&DocNm=1773266&DocType=DS&DocLang=English"
			(at 0 0 90)
			(layer "F.Fab")
			(hide yes)
			(effects
				(font
					(size 1.27 1.27)
					(thickness 0.15)
				)
			)
		)
		(property "MPN" "RCW-0C"
			(at 0 0 90)
			(unlocked yes)
			(layer "F.Fab")
			(hide yes)
			(effects
				(font
					(size 1 1)
					(thickness 0.15)
				)
			)
		)
		(property "Manufacturer" "TE Connectivity"
			(at 0 0 90)
			(unlocked yes)
			(layer "F.Fab")
			(hide yes)
			(effects
				(font
					(size 1 1)
					(thickness 0.15)
				)
			)
		)
		(property "Author" "Antmicro"
			(at 0 0 90)
			(unlocked yes)
			(layer "F.Fab")
			(hide yes)
			(effects
				(font
					(size 1 1)
					(thickness 0.15)
				)
			)
		)
		(property "License" "Apache-2.0"
			(at 0 0 90)
			(unlocked yes)
			(layer "F.Fab")
			(hide yes)
			(effects
				(font
					(size 1 1)
					(thickness 0.15)
				)
			)
		)
		(sheetname "/Supply/")
		(sheetfile "supply.kicad_sch")
		(attr smd)
		(fp_line
			(start 1.78 -0.981)
			(end 1.281 -0.981)
			(stroke
				(width 0.15)
				(type solid)
			)
			(layer "F.SilkS")
		)
		(fp_line
			(start 1.78 -0.981)
			(end 1.78 -0.479)
			(stroke
				(width 0.15)
				(type solid)
			)
			(layer "F.SilkS")
		)
		(fp_line
			(start -1.779 -0.981)
			(end -1.279 -0.981)
			(stroke
				(width 0.15)
				(type solid)
			)
			(layer "F.SilkS")
		)
		(fp_line
			(start -1.779 -0.981)
			(end -1.779 -0.479)
			(stroke
				(width 0.15)
				(type solid)
			)
			(layer "F.SilkS")
		)
		(fp_line
			(start -1.779 0.482)
			(end -1.779 0.98)
			(stroke
				(width 0.15)
				(type solid)
			)
			(layer "F.SilkS")
		)
		(fp_line
			(start -1.779 0.98)
			(end -1.279 0.98)
			(stroke
				(width 0.15)
				(type solid)
			)
			(layer "F.SilkS")
		)
		(fp_line
			(start 1.78 0.982)
			(end 1.78 0.482)
			(stroke
				(width 0.15)
				(type solid)
			)
			(layer "F.SilkS")
		)
		(fp_line
			(start 1.78 0.982)
			(end 1.281 0.982)
			(stroke
				(width 0.15)
				(type solid)
			)
			(layer "F.SilkS")
		)
		(fp_rect
			(start -2.101 -1.314)
			(end 2.1 1.312)
			(stroke
				(width 0.05)
				(type solid)
			)
			(fill no)
			(layer "F.CrtYd")
		)
		(fp_rect
			(start -1.601 -0.814)
			(end 1.6 0.812)
			(stroke
				(width 0.15)
				(type solid)
			)
			(fill no)
			(layer "F.Fab")
		)
		(fp_text user "License: Apache-2.0"
			(at -4.68 5.45 90)
			(layer "F.Fab")
			(effects
				(font
					(size 0.7 0.7)
					(thickness 0.15)
				)
				(justify left bottom)
			)
		)
		(fp_text user "Author: Antmicro"
			(at -4.68 4.25 90)
			(layer "F.Fab")
			(effects
				(font
					(size 0.7 0.7)
					(thickness 0.15)
				)
				(justify left bottom)
			)
		)
		(fp_text user "${REFERENCE}"
			(at -4.68 6.65 90)
			(layer "F.Fab")
			(effects
				(font
					(size 0.7 0.7)
					(thickness 0.15)
				)
				(justify left bottom)
			)
		)
		(pad "1" smd rect
			(at 0 0 90)
			(size 3.4 1.8)
			(layers "F.Cu" "F.Mask" "F.Paste")
			(net 1 "GND")
			(pinfunction "1")
			(pintype "passive")
		)
	)
	(footprint "antmicro-footprints:SOD-523"
		(layer "F.Cu")
		(at 147.7745 172.934 180)
		(property "Reference" "D15"
			(at -1.1455 -1.816 0)
			(layer "F.SilkS")
			(effects
				(font
					(size 0.7 0.7)
					(thickness 0.15)
				)
				(justify right bottom)
			)
		)
		(property "Value" "BAT54-02V-G3-08"
			(at 0 1.499 0)
			(layer "F.Fab")
			(effects
				(font
					(size 0.7 0.7)
					(thickness 0.15)
				)
				(justify right bottom)
			)
		)
		(property "Datasheet" "https://www.vishay.com/docs/85633/bat5402v.pdf"
			(at 0 0 180)
			(layer "F.Fab")
			(hide yes)
			(effects
				(font
					(size 1.27 1.27)
					(thickness 0.15)
				)
			)
		)
		(property "MPN" "BAT54-02V-G3-08"
			(at 0 0 180)
			(unlocked yes)
			(layer "F.Fab")
			(hide yes)
			(effects
				(font
					(size 1 1)
					(thickness 0.15)
				)
			)
		)
		(property "Manufacturer" "Vishay"
			(at 0 0 180)
			(unlocked yes)
			(layer "F.Fab")
			(hide yes)
			(effects
				(font
					(size 1 1)
					(thickness 0.15)
				)
			)
		)
		(property "Author" "Antmicro"
			(at 0 0 180)
			(unlocked yes)
			(layer "F.Fab")
			(hide yes)
			(effects
				(font
					(size 1 1)
					(thickness 0.15)
				)
			)
		)
		(property "License" "Apache-2.0"
			(at 0 0 180)
			(unlocked yes)
			(layer "F.Fab")
			(hide yes)
			(effects
				(font
					(size 1 1)
					(thickness 0.15)
				)
			)
		)
		(sheetname "/Debug FTDI + VNA/")
		(sheetfile "debug-ftdi.kicad_sch")
		(attr smd)
		(fp_line
			(start -0.35 -0.5)
			(end -0.35 0.5)
			(stroke
				(width 0.15)
				(type solid)
			)
			(layer "F.SilkS")
		)
		(fp_rect
			(start -1 -0.6)
			(end 1 0.6)
			(stroke
				(width 0.05)
				(type solid)
			)
			(fill no)
			(layer "F.CrtYd")
		)
		(fp_line
			(start 0.65 -0.425)
			(end 0.65 0.423)
			(stroke
				(width 0.15)
				(type solid)
			)
			(layer "F.Fab")
		)
		(fp_line
			(start -0.35 -0.4)
			(end -0.35 0.4)
			(stroke
				(width 0.15)
				(type solid)
			)
			(layer "F.Fab")
		)
		(fp_line
			(start -0.652 0.423)
			(end 0.65 0.423)
			(stroke
				(width 0.15)
				(type solid)
			)
			(layer "F.Fab")
		)
		(fp_line
			(start -0.652 0.423)
			(end -0.652 -0.425)
			(stroke
				(width 0.15)
				(type solid)
			)
			(layer "F.Fab")
		)
		(fp_line
			(start -0.652 -0.425)
			(end 0.65 -0.425)
			(stroke
				(width 0.15)
				(type solid)
			)
			(layer "F.Fab")
		)
		(fp_text user "${REFERENCE}"
			(at -1.276 3.499 180)
			(layer "F.Fab")
			(effects
				(font
					(size 0.7 0.7)
					(thickness 0.15)
				)
				(justify left bottom)
			)
		)
		(fp_text user "License: Apache-2.0"
			(at -1.276 5.9 180)
			(layer "F.Fab")
			(effects
				(font
					(size 0.7 0.7)
					(thickness 0.15)
				)
				(justify left bottom)
			)
		)
		(fp_text user "Author: Antmicro"
			(at -1.276 4.7 180)
			(layer "F.Fab")
			(effects
				(font
					(size 0.7 0.7)
					(thickness 0.15)
				)
				(justify left bottom)
			)
		)
		(pad "1" smd roundrect
			(at -0.701 0 180)
			(size 0.5 0.6)
			(layers "F.Cu" "F.Mask" "F.Paste")
			(roundrect_rratio 0.25)
			(net 44 "/Debug FTDI + VNA/FTDI_SDA_OUT")
			(pinfunction "C")
			(pintype "passive")
		)
		(pad "2" smd roundrect
			(at 0.699 0 180)
			(size 0.5 0.6)
			(layers "F.Cu" "F.Mask" "F.Paste")
			(roundrect_rratio 0.25)
			(net 139 "/Debug FTDI + VNA/FTDI_SDA_IN")
			(pinfunction "A")
			(pintype "passive")
		)
	)
	(footprint "antmicro-footprints:L_WE-HCM-7050"
		(layer "F.Cu")
		(at 218.91 174.72 90)
		(property "Reference" "L1"
			(at -2.9 -3.9 90)
			(layer "F.SilkS")
			(effects
				(font
					(size 0.7 0.7)
					(thickness 0.15)
				)
				(justify left bottom)
			)
		)
		(property "Value" "L_150n_30A_WE-HCM-7050"
			(at -2.9 5.2 90)
			(layer "F.Fab")
			(effects
				(font
					(size 0.7 0.7)
					(thickness 0.15)
				)
				(justify left bottom)
			)
		)
		(property "Datasheet" "https://www.we-online.com/components/products/datasheet/744302015.pdf"
			(at 0 0 90)
			(layer "F.Fab")
			(hide yes)
			(effects
				(font
					(size 1.27 1.27)
					(thickness 0.15)
				)
			)
		)
		(property "Val" "150n/30A"
			(at 0 0 90)
			(unlocked yes)
			(layer "F.Fab")
			(hide yes)
			(effects
				(font
					(size 1 1)
					(thickness 0.15)
				)
			)
		)
		(property "Manufacturer" "Würth Elektronik"
			(at 0 0 90)
			(unlocked yes)
			(layer "F.Fab")
			(hide yes)
			(effects
				(font
					(size 1 1)
					(thickness 0.15)
				)
			)
		)
		(property "MPN" "744302015"
			(at 0 0 90)
			(unlocked yes)
			(layer "F.Fab")
			(hide yes)
			(effects
				(font
					(size 1 1)
					(thickness 0.15)
				)
			)
		)
		(property "ISat" "35 A"
			(at 0 0 90)
			(unlocked yes)
			(layer "F.Fab")
			(hide yes)
			(effects
				(font
					(size 1 1)
					(thickness 0.15)
				)
			)
		)
		(property "IMax" "30 A"
			(at 0 0 90)
			(unlocked yes)
			(layer "F.Fab")
			(hide yes)
			(effects
				(font
					(size 1 1)
					(thickness 0.15)
				)
			)
		)
		(property "Size" "7.15x7"
			(at 0 0 90)
			(unlocked yes)
			(layer "F.Fab")
			(hide yes)
			(effects
				(font
					(size 1 1)
					(thickness 0.15)
				)
			)
		)
		(property "Author" "Antmicro"
			(at 0 0 90)
			(unlocked yes)
			(layer "F.Fab")
			(hide yes)
			(effects
				(font
					(size 1 1)
					(thickness 0.15)
				)
			)
		)
		(property "License" "Apache-2.0"
			(at 0 0 90)
			(unlocked yes)
			(layer "F.Fab")
			(hide yes)
			(effects
				(font
					(size 1 1)
					(thickness 0.15)
				)
			)
		)
		(sheetname "/Supply/DC-DC VCCINT/")
		(sheetfile "dc-dc-vccint.kicad_sch")
		(attr smd)
		(fp_line
			(start 3.6 -3.6)
			(end -3.6 -3.6)
			(stroke
				(width 0.15)
				(type solid)
			)
			(layer "F.SilkS")
		)
		(fp_line
			(start -3.6 -3.6)
			(end -3.6 -1.8)
			(stroke
				(width 0.15)
				(type solid)
			)
			(layer "F.SilkS")
		)
		(fp_line
			(start 3.6 -1.8)
			(end 3.6 -3.6)
			(stroke
				(width 0.15)
				(type solid)
			)
			(layer "F.SilkS")
		)
		(fp_line
			(start 3.6 1.8)
			(end 3.6 3.6)
			(stroke
				(width 0.15)
				(type solid)
			)
			(layer "F.SilkS")
		)
		(fp_line
			(start -3.6 1.8)
			(end -3.6 3.6)
			(stroke
				(width 0.15)
				(type solid)
			)
			(layer "F.SilkS")
		)
		(fp_line
			(start 3.6 3.6)
			(end -3.6 3.6)
			(stroke
				(width 0.15)
				(type solid)
			)
			(layer "F.SilkS")
		)
		(fp_rect
			(start -3.9 -3.75)
			(end 3.9 3.75)
			(stroke
				(width 0.05)
				(type solid)
			)
			(fill no)
			(layer "F.CrtYd")
		)
		(fp_rect
			(start -3.5 -3.5)
			(end 3.5 3.5)
			(stroke
				(width 0.15)
				(type solid)
			)
			(fill no)
			(layer "F.Fab")
		)
		(fp_text user "${REFERENCE}"
			(at -4.25 7.2 90)
			(layer "F.Fab")
			(effects
				(font
					(size 0.7 0.7)
					(thickness 0.15)
				)
				(justify left bottom)
			)
		)
		(fp_text user "License: Apache-2.0"
			(at -4.25 8.4 90)
			(layer "F.Fab")
			(effects
				(font
					(size 0.7 0.7)
					(thickness 0.15)
				)
				(justify left bottom)
			)
		)
		(fp_text user "Author: Antmicro"
			(at -4.25 9.6 90)
			(layer "F.Fab")
			(effects
				(font
					(size 0.7 0.7)
					(thickness 0.15)
				)
				(justify left bottom)
			)
		)
		(pad "1" smd roundrect
			(at -2.65 0 90)
			(size 2 3.05)
			(layers "F.Cu" "F.Mask" "F.Paste")
			(roundrect_rratio 0.1)
			(net 165 "Net-(C215-Pad2)")
			(pintype "passive")
		)
		(pad "2" smd roundrect
			(at 2.65 0 270)
			(size 2 3.05)
			(layers "F.Cu" "F.Mask" "F.Paste")
			(roundrect_rratio 0.1)
			(net 223 "/Supply/DC-DC VCCINT/0V85_REG0")
			(pintype "passive")
		)
	)
	(footprint "antmicro-footprints:R_0402_1005Metric"
		(layer "F.Cu")
		(at 119.15 152.61 180)
		(descr "Resistor SMD 0402")
		(tags "resistor SMD 0402")
		(property "Reference" "R33"
			(at -5.11 -0.415 180)
			(layer "F.SilkS")
			(effects
				(font
					(size 0.7 0.7)
					(thickness 0.15)
				)
				(justify right bottom)
			)
		)
		(property "Value" "R_49k9_0402"
			(at -1.011843 1.772047 0)
			(layer "F.Fab")
			(effects
				(font
					(size 0.7 0.7)
					(thickness 0.15)
				)
				(justify right bottom)
			)
		)
		(property "Datasheet" "https://www.bourns.com/docs/product-datasheets/cr.pdf"
			(at 0 0 180)
			(layer "F.Fab")
			(hide yes)
			(effects
				(font
					(size 1.27 1.27)
					(thickness 0.15)
				)
			)
		)
		(property "MPN" "CR0402-FX-4992GLF"
			(at 0 0 180)
			(unlocked yes)
			(layer "F.Fab")
			(hide yes)
			(effects
				(font
					(size 1 1)
					(thickness 0.15)
				)
			)
		)
		(property "Manufacturer" "Bourns"
			(at 0 0 180)
			(unlocked yes)
			(layer "F.Fab")
			(hide yes)
			(effects
				(font
					(size 1 1)
					(thickness 0.15)
				)
			)
		)
		(property "License" "Apache-2.0"
			(at 0 0 180)
			(unlocked yes)
			(layer "F.Fab")
			(hide yes)
			(effects
				(font
					(size 1 1)
					(thickness 0.15)
				)
			)
		)
		(property "Author" "Antmicro"
			(at 0 0 180)
			(unlocked yes)
			(layer "F.Fab")
			(hide yes)
			(effects
				(font
					(size 1 1)
					(thickness 0.15)
				)
			)
		)
		(property "Val" "49k9"
			(at 0 0 180)
			(unlocked yes)
			(layer "F.Fab")
			(hide yes)
			(effects
				(font
					(size 1 1)
					(thickness 0.15)
				)
			)
		)
		(property "Tolerance" "1%"
			(at 0 0 180)
			(unlocked yes)
			(layer "F.Fab")
			(hide yes)
			(effects
				(font
					(size 1 1)
					(thickness 0.15)
				)
			)
		)
		(sheetname "/HDMI + SD Card/")
		(sheetfile "hdmi-sd-card.kicad_sch")
		(attr smd)
		(fp_rect
			(start -0.925 -0.47)
			(end 0.925 0.47)
			(stroke
				(width 0.05)
				(type default)
			)
			(fill no)
			(layer "F.CrtYd")
		)
		(fp_rect
			(start -0.5 -0.25)
			(end 0.5 0.25)
			(stroke
				(width 0.15)
				(type solid)
			)
			(fill no)
			(layer "F.Fab")
		)
		(fp_text user "Author: Antmicro"
			(at -0.95 4.169 180)
			(layer "F.Fab")
			(effects
				(font
					(size 0.7 0.7)
					(thickness 0.15)
				)
				(justify left bottom)
			)
		)
		(fp_text user "License: Apache-2.0"
			(at -0.95 5.169 180)
			(layer "F.Fab")
			(effects
				(font
					(size 0.7 0.7)
					(thickness 0.15)
				)
				(justify left bottom)
			)
		)
		(fp_text user "${REFERENCE}"
			(at -0.95 3.168 180)
			(layer "F.Fab")
			(effects
				(font
					(size 0.7 0.7)
					(thickness 0.15)
				)
				(justify left bottom)
			)
		)
		(pad "1" smd roundrect
			(at -0.48 0 180)
			(size 0.59 0.64)
			(layers "F.Cu" "F.Mask" "F.Paste")
			(roundrect_rratio 0.25)
			(net 679 "Net-(L9-Pad2)")
			(pintype "passive")
		)
		(pad "2" smd roundrect
			(at 0.48 0 180)
			(size 0.59 0.64)
			(layers "F.Cu" "F.Mask" "F.Paste")
			(roundrect_rratio 0.25)
			(net 322 "Net-(C300-Pad2)")
			(pintype "passive")
		)
	)
	(footprint "antmicro-footprints:C_0603_1608Metric"
		(layer "F.Cu")
		(at 226.635 168.755)
		(descr "Capacitor SMD 0603")
		(tags "capacitor 0603")
		(property "Reference" "C271"
			(at -1.36 -2.155 0)
			(layer "F.SilkS")
			(effects
				(font
					(size 0.7 0.7)
					(thickness 0.15)
				)
				(justify left bottom)
			)
		)
		(property "Value" "C_22u_0603"
			(at -1.42757 1.770288 0)
			(layer "F.Fab")
			(effects
				(font
					(size 0.7 0.7)
					(thickness 0.15)
				)
				(justify left bottom)
			)
		)
		(property "Datasheet" "https://www.murata.com/products/productdetail?partno=GRM188R60J226MEA0%23"
			(at 0 0 0)
			(layer "F.Fab")
			(hide yes)
			(effects
				(font
					(size 1.27 1.27)
					(thickness 0.15)
				)
			)
		)
		(property "Manufacturer" "Murata"
			(at 0 0 0)
			(unlocked yes)
			(layer "F.Fab")
			(hide yes)
			(effects
				(font
					(size 1 1)
					(thickness 0.15)
				)
			)
		)
		(property "MPN" "GRM188R60J226MEA0D"
			(at 0 0 0)
			(unlocked yes)
			(layer "F.Fab")
			(hide yes)
			(effects
				(font
					(size 1 1)
					(thickness 0.15)
				)
			)
		)
		(property "Val" "22u"
			(at 0 0 0)
			(unlocked yes)
			(layer "F.Fab")
			(hide yes)
			(effects
				(font
					(size 1 1)
					(thickness 0.15)
				)
			)
		)
		(property "License" "Apache-2.0"
			(at 0 0 0)
			(unlocked yes)
			(layer "F.Fab")
			(hide yes)
			(effects
				(font
					(size 1 1)
					(thickness 0.15)
				)
			)
		)
		(property "Author" "Antmicro"
			(at 0 0 0)
			(unlocked yes)
			(layer "F.Fab")
			(hide yes)
			(effects
				(font
					(size 1 1)
					(thickness 0.15)
				)
			)
		)
		(property "Voltage" ""
			(at 0 0 0)
			(unlocked yes)
			(layer "F.Fab")
			(hide yes)
			(effects
				(font
					(size 1 1)
					(thickness 0.15)
				)
			)
		)
		(property "Dielectric" ""
			(at 0 0 0)
			(unlocked yes)
			(layer "F.Fab")
			(hide yes)
			(effects
				(font
					(size 1 1)
					(thickness 0.15)
				)
			)
		)
		(sheetname "/Supply/DC-DC VCCINT/")
		(sheetfile "dc-dc-vccint.kicad_sch")
		(attr smd)
		(fp_line
			(start -0.15 -0.4)
			(end 0.15 -0.4)
			(stroke
				(width 0.15)
				(type solid)
			)
			(layer "F.SilkS")
		)
		(fp_line
			(start -0.15 0.4)
			(end 0.15 0.4)
			(stroke
				(width 0.15)
				(type solid)
			)
			(layer "F.SilkS")
		)
		(fp_rect
			(start -1.25 -0.65)
			(end 1.25 0.65)
			(stroke
				(width 0.05)
				(type solid)
			)
			(fill no)
			(layer "F.CrtYd")
		)
		(fp_rect
			(start -0.8 -0.4)
			(end 0.8 0.4)
			(stroke
				(width 0.15)
				(type solid)
			)
			(fill no)
			(layer "F.Fab")
		)
		(fp_text user "Author: Antmicro"
			(at -1.682 4.894 0)
			(layer "F.Fab")
			(effects
				(font
					(size 0.7 0.7)
					(thickness 0.15)
				)
				(justify left bottom)
			)
		)
		(fp_text user "${REFERENCE}"
			(at -1.682 3.895 0)
			(layer "F.Fab")
			(effects
				(font
					(size 0.7 0.7)
					(thickness 0.15)
				)
				(justify left bottom)
			)
		)
		(fp_text user "License: Apache-2.0"
			(at -1.682 5.895 0)
			(layer "F.Fab")
			(effects
				(font
					(size 0.7 0.7)
					(thickness 0.15)
				)
				(justify left bottom)
			)
		)
		(pad "1" smd roundrect
			(at -0.7 0)
			(size 0.8 1)
			(layers "F.Cu" "F.Mask" "F.Paste")
			(roundrect_rratio 0.2)
			(net 1 "GND")
			(pintype "passive")
		)
		(pad "2" smd roundrect
			(at 0.7 0)
			(size 0.8 1)
			(layers "F.Cu" "F.Mask" "F.Paste")
			(roundrect_rratio 0.2)
			(net 224 "/Supply/DC-DC VCCINT/0V85_REG1")
			(pintype "passive")
		)
	)
	(footprint "antmicro-footprints:SC70-3"
		(layer "F.Cu")
		(at 234.35 166.2 90)
		(property "Reference" "Q15"
			(at -0.35 -1.1 180)
			(layer "F.SilkS")
			(effects
				(font
					(size 0.7 0.7)
					(thickness 0.15)
				)
				(justify left bottom)
			)
		)
		(property "Value" "BSS138PW"
			(at -74.770501 -11.8455 90)
			(layer "F.Fab")
			(effects
				(font
					(size 0.7 0.7)
					(thickness 0.15)
				)
				(justify left bottom)
			)
		)
		(property "Datasheet" "https://assets.nexperia.com/documents/data-sheet/BSS138PW.pdf"
			(at 0 0 90)
			(layer "F.Fab")
			(hide yes)
			(effects
				(font
					(size 1.27 1.27)
					(thickness 0.15)
				)
			)
		)
		(property "MPN" "BSS138PW"
			(at 0 0 90)
			(unlocked yes)
			(layer "F.Fab")
			(hide yes)
			(effects
				(font
					(size 1 1)
					(thickness 0.15)
				)
			)
		)
		(property "Manufacturer" "Nexperia"
			(at 0 0 90)
			(unlocked yes)
			(layer "F.Fab")
			(hide yes)
			(effects
				(font
					(size 1 1)
					(thickness 0.15)
				)
			)
		)
		(property "Author" "Antmicro"
			(at 0 0 90)
			(unlocked yes)
			(layer "F.Fab")
			(hide yes)
			(effects
				(font
					(size 1 1)
					(thickness 0.15)
				)
			)
		)
		(property "License" "Apache-2.0"
			(at 0 0 90)
			(unlocked yes)
			(layer "F.Fab")
			(hide yes)
			(effects
				(font
					(size 1 1)
					(thickness 0.15)
				)
			)
		)
		(sheetname "/Supply/")
		(sheetfile "supply.kicad_sch")
		(attr smd)
		(fp_line
			(start -0.3 -1)
			(end 0.627 -0.999)
			(stroke
				(width 0.15)
				(type solid)
			)
			(layer "F.SilkS")
		)
		(fp_line
			(start 0.627 -0.6)
			(end 0.627 -0.999)
			(stroke
				(width 0.15)
				(type solid)
			)
			(layer "F.SilkS")
		)
		(fp_line
			(start 0.627 0.6)
			(end 0.627 1.001)
			(stroke
				(width 0.15)
				(type solid)
			)
			(layer "F.SilkS")
		)
		(fp_line
			(start -0.3 1)
			(end 0.627 1.001)
			(stroke
				(width 0.15)
				(type solid)
			)
			(layer "F.SilkS")
		)
		(fp_line
			(start 0.9 -1.3)
			(end 0.9 -0.4)
			(stroke
				(width 0.05)
				(type solid)
			)
			(layer "F.CrtYd")
		)
		(fp_line
			(start -0.9 -1.3)
			(end 0.9 -1.3)
			(stroke
				(width 0.05)
				(type solid)
			)
			(layer "F.CrtYd")
		)
		(fp_line
			(start -0.9 -1.3)
			(end -0.9 -1)
			(stroke
				(width 0.05)
				(type solid)
			)
			(layer "F.CrtYd")
		)
		(fp_line
			(start -0.9 -1)
			(end -1.4 -1)
			(stroke
				(width 0.05)
				(type solid)
			)
			(layer "F.CrtYd")
		)
		(fp_line
			(start 1.4 -0.4)
			(end 1.4 0.4)
			(stroke
				(width 0.05)
				(type solid)
			)
			(layer "F.CrtYd")
		)
		(fp_line
			(start 0.9 -0.4)
			(end 1.4 -0.4)
			(stroke
				(width 0.05)
				(type solid)
			)
			(layer "F.CrtYd")
		)
		(fp_line
			(start 1.4 0.4)
			(end 0.9 0.4)
			(stroke
				(width 0.05)
				(type solid)
			)
			(layer "F.CrtYd")
		)
		(fp_line
			(start 0.9 0.4)
			(end 0.9 1.3)
			(stroke
				(width 0.05)
				(type solid)
			)
			(layer "F.CrtYd")
		)
		(fp_line
			(start -0.9 1)
			(end -1.4 1)
			(stroke
				(width 0.05)
				(type solid)
			)
			(layer "F.CrtYd")
		)
		(fp_line
			(start -1.4 1)
			(end -1.4 -1)
			(stroke
				(width 0.05)
				(type solid)
			)
			(layer "F.CrtYd")
		)
		(fp_line
			(start 0.9 1.3)
			(end -0.9 1.3)
			(stroke
				(width 0.05)
				(type solid)
			)
			(layer "F.CrtYd")
		)
		(fp_line
			(start -0.9 1.3)
			(end -0.9 1)
			(stroke
				(width 0.05)
				(type solid)
			)
			(layer "F.CrtYd")
		)
		(fp_rect
			(start -0.623 -0.999)
			(end 0.627 1.001)
			(stroke
				(width 0.15)
				(type solid)
			)
			(fill no)
			(layer "F.Fab")
		)
		(fp_text user "${REFERENCE}"
			(at -1.45 4.783 90)
			(layer "F.Fab")
			(effects
				(font
					(size 0.7 0.7)
					(thickness 0.15)
				)
				(justify left bottom)
			)
		)
		(fp_text user "License: Apache-2.0"
			(at -1.45 6.782 90)
			(layer "F.Fab")
			(effects
				(font
					(size 0.7 0.7)
					(thickness 0.15)
				)
				(justify left bottom)
			)
		)
		(fp_text user "Author: Antmicro"
			(at -1.45 5.782 90)
			(layer "F.Fab")
			(effects
				(font
					(size 0.7 0.7)
					(thickness 0.15)
				)
				(justify left bottom)
			)
		)
		(pad "1" smd rect
			(at -1.051 -0.65 180)
			(size 0.6 0.6)
			(layers "F.Cu" "F.Mask" "F.Paste")
			(net 206 "FAN_PWM")
			(pinfunction "G")
			(pintype "passive")
		)
		(pad "2" smd rect
			(at -1.051 0.65 180)
			(size 0.6 0.6)
			(layers "F.Cu" "F.Mask" "F.Paste")
			(net 1 "GND")
			(pinfunction "S")
			(pintype "passive")
		)
		(pad "3" smd rect
			(at 1.05 0 180)
			(size 0.6 0.6)
			(layers "F.Cu" "F.Mask" "F.Paste")
			(net 250 "Net-(Q15-D)")
			(pinfunction "D")
			(pintype "passive")
		)
	)
	(footprint "antmicro-footprints:PCB-Edge_PCIexpress_x8"
		(layer "F.Cu")
		(at 145.65 199.25)
		(descr "PCIexpress x8")
		(tags "PCIexpress")
		(property "Reference" "J10"
			(at -0.025 -3.175 0)
			(layer "F.SilkS")
			(hide yes)
			(effects
				(font
					(size 0.7 0.7)
					(thickness 0.15)
				)
				(justify left bottom)
			)
		)
		(property "Value" "PCB-Edge_PCIexpress_x8"
			(at -0.8 7.3 0)
			(layer "F.Fab")
			(effects
				(font
					(size 0.7 0.7)
					(thickness 0.15)
				)
				(justify left bottom)
			)
		)
		(property "Author" "Antmicro"
			(at 0 0 0)
			(unlocked yes)
			(layer "F.Fab")
			(hide yes)
			(effects
				(font
					(size 1 1)
					(thickness 0.15)
				)
			)
		)
		(property "License" "Apache-2.0"
			(at 0 0 0)
			(unlocked yes)
			(layer "F.Fab")
			(hide yes)
			(effects
				(font
					(size 1 1)
					(thickness 0.15)
				)
			)
		)
		(sheetname "/PCIe connector/")
		(sheetfile "pcie-connector.kicad_sch")
		(attr exclude_from_pos_files exclude_from_bom)
		(fp_poly
			(pts
				(xy -0.5 -2.05) (xy 50.7 -2.05) (xy 50.6 3.4) (xy -0.6 3.4)
			)
			(stroke
				(width 0.2)
				(type solid)
			)
			(fill yes)
			(layer "F.Mask")
		)
		(fp_poly
			(pts
				(xy -0.6 -2.05) (xy 50.6 -2.05) (xy 50.6 3.4) (xy -0.6 3.4)
			)
			(stroke
				(width 0.2)
				(type solid)
			)
			(fill yes)
			(layer "B.Mask")
		)
		(fp_circle
			(center 0 -2.675)
			(end 0.05 -2.675)
			(stroke
				(width 0.15)
				(type solid)
			)
			(fill yes)
			(layer "F.SilkS")
		)
		(fp_line
			(start -0.65 -4.95)
			(end -0.65 2.95)
			(stroke
				(width 0.1)
				(type solid)
			)
			(layer "Edge.Cuts")
		)
		(fp_line
			(start -0.65 2.95)
			(end -0.15 3.45)
			(stroke
				(width 0.1)
				(type solid)
			)
			(layer "Edge.Cuts")
		)
		(fp_line
			(start -0.15 3.45)
			(end 10.05 3.45)
			(stroke
				(width 0.1)
				(type solid)
			)
			(layer "Edge.Cuts")
		)
		(fp_line
			(start 10.55 -4)
			(end 10.55 2.95)
			(stroke
				(width 0.1)
				(type solid)
			)
			(layer "Edge.Cuts")
		)
		(fp_line
			(start 10.55 2.95)
			(end 10.05 3.45)
			(stroke
				(width 0.1)
				(type solid)
			)
			(layer "Edge.Cuts")
		)
		(fp_line
			(start 12.45 -4)
			(end 12.45 2.95)
			(stroke
				(width 0.1)
				(type solid)
			)
			(layer "Edge.Cuts")
		)
		(fp_line
			(start 12.45 2.95)
			(end 12.95 3.45)
			(stroke
				(width 0.1)
				(type solid)
			)
			(layer "Edge.Cuts")
		)
		(fp_line
			(start 12.95 3.45)
			(end 50.15 3.45)
			(stroke
				(width 0.1)
				(type solid)
			)
			(layer "Edge.Cuts")
		)
		(fp_line
			(start 50.65 -4.95)
			(end 50.65 2.95)
			(stroke
				(width 0.1)
				(type solid)
			)
			(layer "Edge.Cuts")
		)
		(fp_line
			(start 50.65 2.95)
			(end 50.15 3.45)
			(stroke
				(width 0.1)
				(type solid)
			)
			(layer "Edge.Cuts")
		)
		(fp_arc
			(start 10.55 -4)
			(mid 11.5 -4.95)
			(end 12.45 -4)
			(stroke
				(width 0.1)
				(type solid)
			)
			(layer "Edge.Cuts")
		)
		(fp_text user "${REFERENCE}"
			(at -0.75 8.65 0)
			(layer "F.Fab")
			(effects
				(font
					(size 0.7 0.7)
					(thickness 0.15)
				)
				(justify left bottom)
			)
		)
		(fp_text user "Author: Antmicro"
			(at -0.75 9.85 0)
			(layer "F.Fab")
			(effects
				(font
					(size 0.7 0.7)
					(thickness 0.15)
				)
				(justify left bottom)
			)
		)
		(fp_text user "License: Apache-2.0"
			(at -0.75 11.05 0)
			(layer "F.Fab")
			(effects
				(font
					(size 0.7 0.7)
					(thickness 0.15)
				)
				(justify left bottom)
			)
		)
		(pad "A1" connect rect
			(at 0 -0.55)
			(size 0.7 3.2)
			(layers "B.Cu" "B.Mask")
			(net 174 "/PCIe connector/PRSNT#1")
			(pinfunction "~{PRSNT1}")
			(pintype "passive")
		)
		(pad "A2" connect rect
			(at 1 0)
			(size 0.7 4.3)
			(layers "B.Cu" "B.Mask")
			(net 10 "+12V")
			(pinfunction "12V")
			(pintype "power_in")
		)
		(pad "A3" connect rect
			(at 2 0)
			(size 0.7 4.3)
			(layers "B.Cu" "B.Mask")
			(net 10 "+12V")
			(pinfunction "12V")
			(pintype "passive")
		)
		(pad "A4" connect rect
			(at 3 0)
			(size 0.7 4.3)
			(layers "B.Cu" "B.Mask")
			(net 1 "GND")
			(pinfunction "GND")
			(pintype "passive")
		)
		(pad "A5" connect rect
			(at 4 0)
			(size 0.7 4.3)
			(layers "B.Cu" "B.Mask")
			(net 260 "unconnected-(J10-TCK-PadA5)")
			(pinfunction "TCK")
			(pintype "input+no_connect")
		)
		(pad "A6" connect rect
			(at 5 0)
			(size 0.7 4.3)
			(layers "B.Cu" "B.Mask")
			(net 261 "unconnected-(J10-TDI-PadA6)")
			(pinfunction "TDI")
			(pintype "input+no_connect")
		)
		(pad "A7" connect rect
			(at 6 0)
			(size 0.7 4.3)
			(layers "B.Cu" "B.Mask")
			(net 262 "unconnected-(J10-TDO-PadA7)")
			(pinfunction "TDO")
			(pintype "output+no_connect")
		)
		(pad "A8" connect rect
			(at 7 0)
			(size 0.7 4.3)
			(layers "B.Cu" "B.Mask")
			(net 263 "unconnected-(J10-TMS-PadA8)")
			(pinfunction "TMS")
			(pintype "input+no_connect")
		)
		(pad "A9" connect rect
			(at 8 0)
			(size 0.7 4.3)
			(layers "B.Cu" "B.Mask")
			(net 815 "unconnected-(J10-3V3-PadA10)_1")
			(pinfunction "3V3")
			(pintype "passive+no_connect")
		)
		(pad "A10" connect rect
			(at 9 0)
			(size 0.7 4.3)
			(layers "B.Cu" "B.Mask")
			(net 816 "unconnected-(J10-3V3-PadA10)_2")
			(pinfunction "3V3")
			(pintype "power_in+no_connect")
		)
		(pad "A11" connect rect
			(at 10 0)
			(size 0.7 4.3)
			(layers "B.Cu" "B.Mask")
			(net 98 "PCIE.PWRGD")
			(pinfunction "~{PERST}")
			(pintype "open_collector")
		)
		(pad "A12" connect rect
			(at 13 0)
			(size 0.7 4.3)
			(layers "B.Cu" "B.Mask")
			(net 1 "GND")
			(pinfunction "GND")
			(pintype "power_in")
		)
		(pad "A13" connect rect
			(at 14 0)
			(size 0.7 4.3)
			(layers "B.Cu" "B.Mask")
			(net 11 "/FPGA MGT Interface/PCIE.CLK_P")
			(pinfunction "REFCLK_p")
			(pintype "input")
		)
		(pad "A14" connect rect
			(at 15 0)
			(size 0.7 4.3)
			(layers "B.Cu" "B.Mask")
			(net 13 "/FPGA MGT Interface/PCIE.CLK_N")
			(pinfunction "REFCLK_n")
			(pintype "input")
		)
		(pad "A15" connect rect
			(at 16 0)
			(size 0.7 4.3)
			(layers "B.Cu" "B.Mask")
			(net 1 "GND")
			(pinfunction "GND")
			(pintype "passive")
		)
		(pad "A16" connect rect
			(at 17 0)
			(size 0.7 4.3)
			(layers "B.Cu" "B.Mask")
			(net 21 "/FPGA MGT Interface/PCIE.TXD0_P")
			(pinfunction "HSI0_p")
			(pintype "output")
		)
		(pad "A17" connect rect
			(at 18 0)
			(size 0.7 4.3)
			(layers "B.Cu" "B.Mask")
			(net 27 "/FPGA MGT Interface/PCIE.TXD0_N")
			(pinfunction "HSI0_n")
			(pintype "output")
		)
		(pad "A18" connect rect
			(at 19 0)
			(size 0.7 4.3)
			(layers "B.Cu" "B.Mask")
			(net 1 "GND")
			(pinfunction "GND")
			(pintype "passive")
		)
		(pad "A19" connect rect
			(at 20 0)
			(size 0.7 4.3)
			(layers "B.Cu" "B.Mask")
			(net 265 "unconnected-(J10-NC-PadA19)")
			(pinfunction "NC")
			(pintype "no_connect")
		)
		(pad "A20" connect rect
			(at 21 0)
			(size 0.7 4.3)
			(layers "B.Cu" "B.Mask")
			(net 1 "GND")
			(pinfunction "GND")
			(pintype "passive")
		)
		(pad "A21" connect rect
			(at 22 0)
			(size 0.7 4.3)
			(layers "B.Cu" "B.Mask")
			(net 19 "/FPGA MGT Interface/PCIE.TXD1_P")
			(pinfunction "HSI1_p")
			(pintype "output")
		)
		(pad "A22" connect rect
			(at 23 0)
			(size 0.7 4.3)
			(layers "B.Cu" "B.Mask")
			(net 30 "/FPGA MGT Interface/PCIE.TXD1_N")
			(pinfunction "HSI1_n")
			(pintype "output")
		)
		(pad "A23" connect rect
			(at 24 0)
			(size 0.7 4.3)
			(layers "B.Cu" "B.Mask")
			(net 1 "GND")
			(pinfunction "GND")
			(pintype "passive")
		)
		(pad "A24" connect rect
			(at 25 0)
			(size 0.7 4.3)
			(layers "B.Cu" "B.Mask")
			(net 1 "GND")
			(pinfunction "GND")
			(pintype "passive")
		)
		(pad "A25" connect rect
			(at 26 0)
			(size 0.7 4.3)
			(layers "B.Cu" "B.Mask")
			(net 17 "/FPGA MGT Interface/PCIE.TXD2_P")
			(pinfunction "HSI2_p")
			(pintype "output")
		)
		(pad "A26" connect rect
			(at 27 0)
			(size 0.7 4.3)
			(layers "B.Cu" "B.Mask")
			(net 25 "/FPGA MGT Interface/PCIE.TXD2_N")
			(pinfunction "HSI2_n")
			(pintype "output")
		)
		(pad "A27" connect rect
			(at 28 0)
			(size 0.7 4.3)
			(layers "B.Cu" "B.Mask")
			(net 1 "GND")
			(pinfunction "GND")
			(pintype "passive")
		)
		(pad "A28" connect rect
			(at 29 0)
			(size 0.7 4.3)
			(layers "B.Cu" "B.Mask")
			(net 1 "GND")
			(pinfunction "GND")
			(pintype "passive")
		)
		(pad "A29" connect rect
			(at 30 0)
			(size 0.7 4.3)
			(layers "B.Cu" "B.Mask")
			(net 15 "/FPGA MGT Interface/PCIE.TXD3_P")
			(pinfunction "HSI3_p")
			(pintype "output")
		)
		(pad "A30" connect rect
			(at 31 0)
			(size 0.7 4.3)
			(layers "B.Cu" "B.Mask")
			(net 23 "/FPGA MGT Interface/PCIE.TXD3_N")
			(pinfunction "HSI3_n")
			(pintype "output")
		)
		(pad "A31" connect rect
			(at 32 0)
			(size 0.7 4.3)
			(layers "B.Cu" "B.Mask")
			(net 1 "GND")
			(pinfunction "GND")
			(pintype "passive")
		)
		(pad "A32" connect rect
			(at 33 0)
			(size 0.7 4.3)
			(layers "B.Cu" "B.Mask")
			(net 574 "unconnected-(J10-NC-PadA32)")
			(pinfunction "NC")
			(pintype "no_connect")
		)
		(pad "A33" connect rect
			(at 34 0)
			(size 0.7 4.3)
			(layers "B.Cu" "B.Mask")
			(net 575 "unconnected-(J10-NC-PadA33)")
			(pinfunction "NC")
			(pintype "no_connect")
		)
		(pad "A34" connect rect
			(at 35 0)
			(size 0.7 4.3)
			(layers "B.Cu" "B.Mask")
			(net 1 "GND")
			(pinfunction "GND")
			(pintype "passive")
		)
		(pad "A35" connect rect
			(at 36 0)
			(size 0.7 4.3)
			(layers "B.Cu" "B.Mask")
			(net 258 "/FPGA MGT Interface/PCIE.TXD4_P")
			(pinfunction "HSI4_p")
			(pintype "output")
		)
		(pad "A36" connect rect
			(at 37 0)
			(size 0.7 4.3)
			(layers "B.Cu" "B.Mask")
			(net 259 "/FPGA MGT Interface/PCIE.TXD4_N")
			(pinfunction "HSI4_n")
			(pintype "output")
		)
		(pad "A37" connect rect
			(at 38 0)
			(size 0.7 4.3)
			(layers "B.Cu" "B.Mask")
			(net 1 "GND")
			(pinfunction "GND")
			(pintype "passive")
		)
		(pad "A38" connect rect
			(at 39 0)
			(size 0.7 4.3)
			(layers "B.Cu" "B.Mask")
			(net 1 "GND")
			(pinfunction "GND")
			(pintype "passive")
		)
		(pad "A39" connect rect
			(at 40 0)
			(size 0.7 4.3)
			(layers "B.Cu" "B.Mask")
			(net 257 "/FPGA MGT Interface/PCIE.TXD5_P")
			(pinfunction "HSI5_p")
			(pintype "output")
		)
		(pad "A40" connect rect
			(at 41 0)
			(size 0.7 4.3)
			(layers "B.Cu" "B.Mask")
			(net 252 "/FPGA MGT Interface/PCIE.TXD5_N")
			(pinfunction "HSI5_n")
			(pintype "output")
		)
		(pad "A41" connect rect
			(at 42 0)
			(size 0.7 4.3)
			(layers "B.Cu" "B.Mask")
			(net 1 "GND")
			(pinfunction "GND")
			(pintype "passive")
		)
		(pad "A42" connect rect
			(at 43 0)
			(size 0.7 4.3)
			(layers "B.Cu" "B.Mask")
			(net 1 "GND")
			(pinfunction "GND")
			(pintype "passive")
		)
		(pad "A43" connect rect
			(at 44 0)
			(size 0.7 4.3)
			(layers "B.Cu" "B.Mask")
			(net 255 "/FPGA MGT Interface/PCIE.TXD6_P")
			(pinfunction "HSI6_p")
			(pintype "output")
		)
		(pad "A44" connect rect
			(at 45 0)
			(size 0.7 4.3)
			(layers "B.Cu" "B.Mask")
			(net 256 "/FPGA MGT Interface/PCIE.TXD6_N")
			(pinfunction "HSI6_n")
			(pintype "output")
		)
		(pad "A45" connect rect
			(at 46 0)
			(size 0.7 4.3)
			(layers "B.Cu" "B.Mask")
			(net 1 "GND")
			(pinfunction "GND")
			(pintype "passive")
		)
		(pad "A46" connect rect
			(at 47 0)
			(size 0.7 4.3)
			(layers "B.Cu" "B.Mask")
			(net 1 "GND")
			(pinfunction "GND")
			(pintype "passive")
		)
		(pad "A47" connect rect
			(at 48 0)
			(size 0.7 4.3)
			(layers "B.Cu" "B.Mask")
			(net 253 "/FPGA MGT Interface/PCIE.TXD7_P")
			(pinfunction "HSI7_p")
			(pintype "output")
		)
		(pad "A48" connect rect
			(at 49 0)
			(size 0.7 4.3)
			(layers "B.Cu" "B.Mask")
			(net 254 "/FPGA MGT Interface/PCIE.TXD7_N")
			(pinfunction "HSI7_n")
			(pintype "output")
		)
		(pad "A49" connect rect
			(at 50 0)
			(size 0.7 4.3)
			(layers "B.Cu" "B.Mask")
			(net 1 "GND")
			(pinfunction "GND")
			(pintype "passive")
		)
		(pad "B1" connect rect
			(at 0 0)
			(size 0.7 4.3)
			(layers "F.Cu" "F.Mask")
			(net 10 "+12V")
			(pinfunction "12V")
			(pintype "passive")
		)
		(pad "B2" connect rect
			(at 1 0)
			(size 0.7 4.3)
			(layers "F.Cu" "F.Mask")
			(net 10 "+12V")
			(pinfunction "12V")
			(pintype "passive")
		)
		(pad "B3" connect rect
			(at 2 0)
			(size 0.7 4.3)
			(layers "F.Cu" "F.Mask")
			(net 10 "+12V")
			(pinfunction "12V")
			(pintype "passive")
		)
		(pad "B4" connect rect
			(at 3 0)
			(size 0.7 4.3)
			(layers "F.Cu" "F.Mask")
			(net 1 "GND")
			(pinfunction "GND")
			(pintype "passive")
		)
		(pad "B5" connect rect
			(at 4 0)
			(size 0.7 4.3)
			(layers "F.Cu" "F.Mask")
			(net 576 "unconnected-(J10-SMCLK-PadB5)")
			(pinfunction "SMCLK")
			(pintype "open_collector+no_connect")
		)
		(pad "B6" connect rect
			(at 5 0)
			(size 0.7 4.3)
			(layers "F.Cu" "F.Mask")
			(net 577 "unconnected-(J10-SMDAT-PadB6)")
			(pinfunction "SMDAT")
			(pintype "open_collector+no_connect")
		)
		(pad "B7" connect rect
			(at 6 0)
			(size 0.7 4.3)
			(layers "F.Cu" "F.Mask")
			(net 1 "GND")
			(pinfunction "GND")
			(pintype "passive")
		)
		(pad "B8" connect rect
			(at 7 0)
			(size 0.7 4.3)
			(layers "F.Cu" "F.Mask")
			(net 264 "unconnected-(J10-3V3-PadA10)")
			(pinfunction "3V3")
			(pintype "passive+no_connect")
		)
		(pad "B9" connect rect
			(at 8 0)
			(size 0.7 4.3)
			(layers "F.Cu" "F.Mask")
			(net 578 "unconnected-(J10-~{TRST}-PadB9)")
			(pinfunction "~{TRST}")
			(pintype "input+no_connect")
		)
		(pad "B10" connect rect
			(at 9 0)
			(size 0.7 4.3)
			(layers "F.Cu" "F.Mask")
			(net 579 "unconnected-(J10-3V3AUX-PadB10)")
			(pinfunction "3V3AUX")
			(pintype "power_in+no_connect")
		)
		(pad "B11" connect rect
			(at 10 0)
			(size 0.7 4.3)
			(layers "F.Cu" "F.Mask")
			(net 580 "unconnected-(J10-~{WAKE}-PadB11)")
			(pinfunction "~{WAKE}")
			(pintype "open_collector+no_connect")
		)
		(pad "B12" connect rect
			(at 13 0)
			(size 0.7 4.3)
			(layers "F.Cu" "F.Mask")
			(net 581 "unconnected-(J10-~{CLKREQ}-PadB12)")
			(pinfunction "~{CLKREQ}")
			(pintype "open_collector+no_connect")
		)
		(pad "B13" connect rect
			(at 14 0)
			(size 0.7 4.3)
			(layers "F.Cu" "F.Mask")
			(net 1 "GND")
			(pinfunction "GND")
			(pintype "passive")
		)
		(pad "B14" connect rect
			(at 15 0)
			(size 0.7 4.3)
			(layers "F.Cu" "F.Mask")
			(net 332 "/FPGA MGT Interface/PCIE.RXD0_P")
			(pinfunction "HSO0_p")
			(pintype "input")
		)
		(pad "B15" connect rect
			(at 16 0)
			(size 0.7 4.3)
			(layers "F.Cu" "F.Mask")
			(net 333 "/FPGA MGT Interface/PCIE.RXD0_N")
			(pinfunction "HSO0_n")
			(pintype "input")
		)
		(pad "B16" connect rect
			(at 17 0)
			(size 0.7 4.3)
			(layers "F.Cu" "F.Mask")
			(net 1 "GND")
			(pinfunction "GND")
			(pintype "passive")
		)
		(pad "B17" connect rect
			(at 18 0)
			(size 0.7 4.3)
			(layers "F.Cu" "F.Mask")
			(net 175 "/PCIe connector/x1")
			(pinfunction "~{PRSNT2_x1}")
			(pintype "passive")
		)
		(pad "B18" connect rect
			(at 19 0)
			(size 0.7 4.3)
			(layers "F.Cu" "F.Mask")
			(net 1 "GND")
			(pinfunction "GND")
			(pintype "passive")
		)
		(pad "B19" connect rect
			(at 20 0)
			(size 0.7 4.3)
			(layers "F.Cu" "F.Mask")
			(net 334 "/FPGA MGT Interface/PCIE.RXD1_P")
			(pinfunction "HSO1_p")
			(pintype "input")
		)
		(pad "B20" connect rect
			(at 21 0)
			(size 0.7 4.3)
			(layers "F.Cu" "F.Mask")
			(net 335 "/FPGA MGT Interface/PCIE.RXD1_N")
			(pinfunction "HSO1_n")
			(pintype "input")
		)
		(pad "B21" connect rect
			(at 22 0)
			(size 0.7 4.3)
			(layers "F.Cu" "F.Mask")
			(net 1 "GND")
			(pinfunction "GND")
			(pintype "passive")
		)
		(pad "B22" connect rect
			(at 23 0)
			(size 0.7 4.3)
			(layers "F.Cu" "F.Mask")
			(net 1 "GND")
			(pinfunction "GND")
			(pintype "passive")
		)
		(pad "B23" connect rect
			(at 24 0)
			(size 0.7 4.3)
			(layers "F.Cu" "F.Mask")
			(net 336 "/FPGA MGT Interface/PCIE.RXD2_P")
			(pinfunction "HSO2_p")
			(pintype "input")
		)
		(pad "B24" connect rect
			(at 25 0)
			(size 0.7 4.3)
			(layers "F.Cu" "F.Mask")
			(net 337 "/FPGA MGT Interface/PCIE.RXD2_N")
			(pinfunction "HSO2_n")
			(pintype "input")
		)
		(pad "B25" connect rect
			(at 26 0)
			(size 0.7 4.3)
			(layers "F.Cu" "F.Mask")
			(net 1 "GND")
			(pinfunction "GND")
			(pintype "passive")
		)
		(pad "B26" connect rect
			(at 27 0)
			(size 0.7 4.3)
			(layers "F.Cu" "F.Mask")
			(net 1 "GND")
			(pinfunction "GND")
			(pintype "passive")
		)
		(pad "B27" connect rect
			(at 28 0)
			(size 0.7 4.3)
			(layers "F.Cu" "F.Mask")
			(net 338 "/FPGA MGT Interface/PCIE.RXD3_P")
			(pinfunction "HSO3_p")
			(pintype "input")
		)
		(pad "B28" connect rect
			(at 29 0)
			(size 0.7 4.3)
			(layers "F.Cu" "F.Mask")
			(net 339 "/FPGA MGT Interface/PCIE.RXD3_N")
			(pinfunction "HSO3_n")
			(pintype "input")
		)
		(pad "B29" connect rect
			(at 30 0)
			(size 0.7 4.3)
			(layers "F.Cu" "F.Mask")
			(net 1 "GND")
			(pinfunction "GND")
			(pintype "passive")
		)
		(pad "B30" connect rect
			(at 31 0)
			(size 0.7 4.3)
			(layers "F.Cu" "F.Mask")
			(net 582 "unconnected-(J10-~{PWRBRK}-PadB30)")
			(pinfunction "~{PWRBRK}")
			(pintype "open_collector+no_connect")
		)
		(pad "B31" connect rect
			(at 32 0)
			(size 0.7 4.3)
			(layers "F.Cu" "F.Mask")
			(net 176 "/PCIe connector/x4")
			(pinfunction "~{PRSNT2_x4}")
			(pintype "passive")
		)
		(pad "B32" connect rect
			(at 33 0)
			(size 0.7 4.3)
			(layers "F.Cu" "F.Mask")
			(net 1 "GND")
			(pinfunction "GND")
			(pintype "passive")
		)
		(pad "B33" connect rect
			(at 34 0)
			(size 0.7 4.3)
			(layers "F.Cu" "F.Mask")
			(net 583 "/FPGA MGT Interface/PCIE.RXD4_P")
			(pinfunction "HSO4_p")
			(pintype "input")
		)
		(pad "B34" connect rect
			(at 35 0)
			(size 0.7 4.3)
			(layers "F.Cu" "F.Mask")
			(net 584 "/FPGA MGT Interface/PCIE.RXD4_N")
			(pinfunction "HSO4_n")
			(pintype "input")
		)
		(pad "B35" connect rect
			(at 36 0)
			(size 0.7 4.3)
			(layers "F.Cu" "F.Mask")
			(net 1 "GND")
			(pinfunction "GND")
			(pintype "passive")
		)
		(pad "B36" connect rect
			(at 37 0)
			(size 0.7 4.3)
			(layers "F.Cu" "F.Mask")
			(net 1 "GND")
			(pinfunction "GND")
			(pintype "passive")
		)
		(pad "B37" connect rect
			(at 38 0)
			(size 0.7 4.3)
			(layers "F.Cu" "F.Mask")
			(net 585 "/FPGA MGT Interface/PCIE.RXD5_P")
			(pinfunction "HSO5_p")
			(pintype "input")
		)
		(pad "B38" connect rect
			(at 39 0)
			(size 0.7 4.3)
			(layers "F.Cu" "F.Mask")
			(net 586 "/FPGA MGT Interface/PCIE.RXD5_N")
			(pinfunction "HSO5_n")
			(pintype "input")
		)
		(pad "B39" connect rect
			(at 40 0)
			(size 0.7 4.3)
			(layers "F.Cu" "F.Mask")
			(net 1 "GND")
			(pinfunction "GND")
			(pintype "passive")
		)
		(pad "B40" connect rect
			(at 41 0)
			(size 0.7 4.3)
			(layers "F.Cu" "F.Mask")
			(net 1 "GND")
			(pinfunction "GND")
			(pintype "passive")
		)
		(pad "B41" connect rect
			(at 42 0)
			(size 0.7 4.3)
			(layers "F.Cu" "F.Mask")
			(net 587 "/FPGA MGT Interface/PCIE.RXD6_P")
			(pinfunction "HSO6_p")
			(pintype "input")
		)
		(pad "B42" connect rect
			(at 43 0)
			(size 0.7 4.3)
			(layers "F.Cu" "F.Mask")
			(net 588 "/FPGA MGT Interface/PCIE.RXD6_N")
			(pinfunction "HSO6_n")
			(pintype "input")
		)
		(pad "B43" connect rect
			(at 44 0)
			(size 0.7 4.3)
			(layers "F.Cu" "F.Mask")
			(net 1 "GND")
			(pinfunction "GND")
			(pintype "passive")
		)
		(pad "B44" connect rect
			(at 45 0)
			(size 0.7 4.3)
			(layers "F.Cu" "F.Mask")
			(net 1 "GND")
			(pinfunction "GND")
			(pintype "passive")
		)
		(pad "B45" connect rect
			(at 46 0)
			(size 0.7 4.3)
			(layers "F.Cu" "F.Mask")
			(net 589 "/FPGA MGT Interface/PCIE.RXD7_P")
			(pinfunction "HSO7_p")
			(pintype "input")
		)
		(pad "B46" connect rect
			(at 47 0)
			(size 0.7 4.3)
			(layers "F.Cu" "F.Mask")
			(net 590 "/FPGA MGT Interface/PCIE.RXD7_N")
			(pinfunction "HSO7_n")
			(pintype "input")
		)
		(pad "B47" connect rect
			(at 48 0)
			(size 0.7 4.3)
			(layers "F.Cu" "F.Mask")
			(net 1 "GND")
			(pinfunction "GND")
			(pintype "passive")
		)
		(pad "B48" connect rect
			(at 49 -0.55)
			(size 0.7 3.2)
			(layers "F.Cu" "F.Mask")
			(net 591 "/PCIe connector/x8")
			(pinfunction "~{PRSNT2_x8}")
			(pintype "passive")
		)
		(pad "B49" connect rect
			(at 50 0)
			(size 0.7 4.3)
			(layers "F.Cu" "F.Mask")
			(net 1 "GND")
			(pinfunction "GND")
			(pintype "passive")
		)
	)
	(footprint "antmicro-footprints:MP_Pad6mm_Drill3mm"
		(layer "F.Cu")
		(at 107.5 193.4)
		(property "Reference" "MP2"
			(at 0 -3.2 0)
			(layer "F.SilkS")
			(hide yes)
			(effects
				(font
					(size 0.7 0.7)
					(thickness 0.15)
				)
				(justify left bottom)
			)
		)
		(property "Value" "MP_Pad6mm_Drill3mm"
			(at 0 3.9 0)
			(layer "F.Fab")
			(effects
				(font
					(size 0.7 0.7)
					(thickness 0.15)
				)
				(justify left bottom)
			)
		)
		(attr board_only exclude_from_pos_files exclude_from_bom)
		(fp_circle
			(center 0 0)
			(end 3.25 0)
			(stroke
				(width 0.05)
				(type default)
			)
			(fill no)
			(layer "F.CrtYd")
		)
		(fp_text user "Author: Antmicro"
			(at -0.178 7.225 0)
			(layer "F.Fab")
			(effects
				(font
					(size 0.7 0.7)
					(thickness 0.15)
				)
				(justify left bottom)
			)
		)
		(fp_text user "${REFERENCE}"
			(at -0.178 6.025 0)
			(layer "F.Fab")
			(effects
				(font
					(size 0.7 0.7)
					(thickness 0.15)
				)
				(justify left bottom)
			)
		)
		(fp_text user "License: Apache-2.0"
			(at -0.178 8.425 0)
			(layer "F.Fab")
			(effects
				(font
					(size 0.7 0.7)
					(thickness 0.15)
				)
				(justify left bottom)
			)
		)
		(pad "1" thru_hole circle
			(at 0 0)
			(size 6 6)
			(drill 3)
			(layers "*.Cu" "*.Mask")
			(remove_unused_layers no)
			(net 1 "GND")
		)
	)
	(footprint "antmicro-footprints:Fiducial_1mm_Mask2mm"
		(layer "F.Cu")
		(at 259.8 182.15 180)
		(descr "Circular Fiducial, 1mm bare copper, 3mm soldermask opening")
		(tags "fiducial")
		(property "Reference" "FID1005"
			(at 0 -1.4 0)
			(layer "F.SilkS")
			(hide yes)
			(effects
				(font
					(size 0.7 0.7)
					(thickness 0.15)
				)
				(justify right bottom)
			)
		)
		(property "Value" "Fiducial_1mm_Mask2mm"
			(at 0 2.2 0)
			(layer "F.Fab")
			(effects
				(font
					(size 0.7 0.7)
					(thickness 0.15)
				)
				(justify right bottom)
			)
		)
		(sheetfile "data-center-rdimm-ddr5-tester.kicad_sch")
		(attr board_only exclude_from_pos_files exclude_from_bom)
		(fp_circle
			(center 0 0)
			(end 1.24 0)
			(stroke
				(width 0.05)
				(type solid)
			)
			(fill no)
			(layer "F.CrtYd")
		)
		(fp_circle
			(center 0 0)
			(end 0.999 0)
			(stroke
				(width 0.15)
				(type solid)
			)
			(fill no)
			(layer "F.Fab")
		)
		(fp_text user "Author: Antmicro"
			(at -1.25 5.803 180)
			(layer "F.Fab")
			(effects
				(font
					(size 0.7 0.7)
					(thickness 0.15)
				)
				(justify left bottom)
			)
		)
		(fp_text user "License: Apache-2.0"
			(at -1.25 7.003 180)
			(layer "F.Fab")
			(effects
				(font
					(size 0.7 0.7)
					(thickness 0.15)
				)
				(justify left bottom)
			)
		)
		(fp_text user "${REFERENCE}"
			(at -1.25 4.603 180)
			(layer "F.Fab")
			(effects
				(font
					(size 0.7 0.7)
					(thickness 0.15)
				)
				(justify left bottom)
			)
		)
		(pad "" smd circle
			(at 0 0 180)
			(size 1 1)
			(layers "F.Cu" "F.Mask")
			(solder_mask_margin 0.5)
			(clearance 0.5)
		)
	)
	(footprint "antmicro-footprints:QFN-56-1EP_8x8mm_P0.5mm"
		(layer "F.Cu")
		(at 141.684 162.835)
		(descr "QFN 56 Pin")
		(tags "QFN")
		(property "Reference" "U6"
			(at 2.940499 5.314 0)
			(layer "F.SilkS")
			(effects
				(font
					(size 0.7 0.7)
					(thickness 0.15)
				)
				(justify left bottom)
			)
		)
		(property "Value" "FT4232H_VQFN"
			(at 0 5.32 0)
			(layer "F.Fab")
			(effects
				(font
					(size 0.7 0.7)
					(thickness 0.15)
				)
				(justify left bottom)
			)
		)
		(property "Datasheet" "https://www.ftdichip.com/Support/Documents/DataSheets/ICs/DS_FT4232H.pdf"
			(at 0 0 0)
			(layer "F.Fab")
			(hide yes)
			(effects
				(font
					(size 1.27 1.27)
					(thickness 0.15)
				)
			)
		)
		(property "Manufacturer" "FTDI Chip"
			(at 0 0 0)
			(unlocked yes)
			(layer "F.Fab")
			(hide yes)
			(effects
				(font
					(size 1 1)
					(thickness 0.15)
				)
			)
		)
		(property "MPN" "FT4232H-56Q-REEL"
			(at 0 0 0)
			(unlocked yes)
			(layer "F.Fab")
			(hide yes)
			(effects
				(font
					(size 1 1)
					(thickness 0.15)
				)
			)
		)
		(property "Author" "Antmicro"
			(at 0 0 0)
			(unlocked yes)
			(layer "F.Fab")
			(hide yes)
			(effects
				(font
					(size 1 1)
					(thickness 0.15)
				)
			)
		)
		(property "License" "Apache-2.0"
			(at 0 0 0)
			(unlocked yes)
			(layer "F.Fab")
			(hide yes)
			(effects
				(font
					(size 1 1)
					(thickness 0.15)
				)
			)
		)
		(sheetname "/Debug FTDI + VNA/")
		(sheetfile "debug-ftdi.kicad_sch")
		(attr smd)
		(fp_line
			(start -4.111 -3.635)
			(end -4.111 -4.111)
			(stroke
				(width 0.15)
				(type solid)
			)
			(layer "F.SilkS")
		)
		(fp_line
			(start -4.111 4.11)
			(end -4.111 3.634)
			(stroke
				(width 0.15)
				(type solid)
			)
			(layer "F.SilkS")
		)
		(fp_line
			(start -3.635 -4.111)
			(end -4.111 -4.111)
			(stroke
				(width 0.15)
				(type solid)
			)
			(layer "F.SilkS")
		)
		(fp_line
			(start -3.635 4.11)
			(end -4.111 4.11)
			(stroke
				(width 0.15)
				(type solid)
			)
			(layer "F.SilkS")
		)
		(fp_line
			(start 3.634 -4.111)
			(end 4.11 -4.111)
			(stroke
				(width 0.15)
				(type solid)
			)
			(layer "F.SilkS")
		)
		(fp_line
			(start 3.634 4.11)
			(end 4.11 4.11)
			(stroke
				(width 0.15)
				(type solid)
			)
			(layer "F.SilkS")
		)
		(fp_line
			(start 4.11 -4.111)
			(end 4.11 -3.635)
			(stroke
				(width 0.15)
				(type solid)
			)
			(layer "F.SilkS")
		)
		(fp_line
			(start 4.11 4.11)
			(end 4.11 3.634)
			(stroke
				(width 0.15)
				(type solid)
			)
			(layer "F.SilkS")
		)
		(fp_circle
			(center -4.35 -3.6)
			(end -4.3 -3.6)
			(stroke
				(width 0.15)
				(type solid)
			)
			(fill yes)
			(layer "F.SilkS")
		)
		(fp_rect
			(start 4.4 4.4)
			(end -4.4 -4.4)
			(stroke
				(width 0.05)
				(type solid)
			)
			(fill no)
			(layer "F.CrtYd")
		)
		(fp_line
			(start -4 -3)
			(end -3 -4)
			(stroke
				(width 0.15)
				(type solid)
			)
			(layer "F.Fab")
		)
		(fp_rect
			(start 4 4)
			(end -4 -4)
			(stroke
				(width 0.15)
				(type solid)
			)
			(fill no)
			(layer "F.Fab")
		)
		(fp_text user "Author: Antmicro"
			(at -4.4 8.519 0)
			(layer "F.Fab")
			(effects
				(font
					(size 0.7 0.7)
					(thickness 0.15)
				)
				(justify left bottom)
			)
		)
		(fp_text user "${REFERENCE}"
			(at -4.4 7.32 0)
			(layer "F.Fab")
			(effects
				(font
					(size 0.7 0.7)
					(thickness 0.15)
				)
				(justify left bottom)
			)
		)
		(fp_text user "License: Apache-2.0"
			(at -4.4 9.719 0)
			(layer "F.Fab")
			(effects
				(font
					(size 0.7 0.7)
					(thickness 0.15)
				)
				(justify left bottom)
			)
		)
		(pad "" smd roundrect
			(at -2.101 -2.101)
			(size 1.13 1.13)
			(layers "F.Paste")
			(roundrect_rratio 0.221239)
		)
		(pad "" smd roundrect
			(at -2.101 -0.7)
			(size 1.13 1.13)
			(layers "F.Paste")
			(roundrect_rratio 0.221239)
		)
		(pad "" smd roundrect
			(at -2.101 0.699)
			(size 1.13 1.13)
			(layers "F.Paste")
			(roundrect_rratio 0.221239)
		)
		(pad "" smd roundrect
			(at -2.101 2.1)
			(size 1.13 1.13)
			(layers "F.Paste")
			(roundrect_rratio 0.221239)
		)
		(pad "" smd roundrect
			(at -0.7 -2.101)
			(size 1.13 1.13)
			(layers "F.Paste")
			(roundrect_rratio 0.221239)
		)
		(pad "" smd roundrect
			(at -0.7 -0.7)
			(size 1.13 1.13)
			(layers "F.Paste")
			(roundrect_rratio 0.221239)
		)
		(pad "" smd roundrect
			(at -0.7 0.699)
			(size 1.13 1.13)
			(layers "F.Paste")
			(roundrect_rratio 0.221239)
		)
		(pad "" smd roundrect
			(at -0.7 2.1)
			(size 1.13 1.13)
			(layers "F.Paste")
			(roundrect_rratio 0.221239)
		)
		(pad "" smd roundrect
			(at 0.699 -2.101)
			(size 1.13 1.13)
			(layers "F.Paste")
			(roundrect_rratio 0.221239)
		)
		(pad "" smd roundrect
			(at 0.699 -0.7)
			(size 1.13 1.13)
			(layers "F.Paste")
			(roundrect_rratio 0.221239)
		)
		(pad "" smd roundrect
			(at 0.699 0.699)
			(size 1.13 1.13)
			(layers "F.Paste")
			(roundrect_rratio 0.221239)
		)
		(pad "" smd roundrect
			(at 0.699 2.1)
			(size 1.13 1.13)
			(layers "F.Paste")
			(roundrect_rratio 0.221239)
		)
		(pad "" smd roundrect
			(at 2.1 -2.101)
			(size 1.13 1.13)
			(layers "F.Paste")
			(roundrect_rratio 0.221239)
		)
		(pad "" smd roundrect
			(at 2.1 -0.7)
			(size 1.13 1.13)
			(layers "F.Paste")
			(roundrect_rratio 0.221239)
		)
		(pad "" smd roundrect
			(at 2.1 0.699)
			(size 1.13 1.13)
			(layers "F.Paste")
			(roundrect_rratio 0.221239)
		)
		(pad "" smd roundrect
			(at 2.1 2.1)
			(size 1.13 1.13)
			(layers "F.Paste")
			(roundrect_rratio 0.221239)
		)
		(pad "1" smd roundrect
			(at -3.938 -3.25)
			(size 0.875 0.3)
			(layers "F.Cu" "F.Mask" "F.Paste")
			(roundrect_rratio 0.25)
			(net 780 "/Debug FTDI + VNA/FTDI_EECS")
			(pinfunction "EECS")
			(pintype "bidirectional")
		)
		(pad "2" smd roundrect
			(at -3.938 -2.75)
			(size 0.875 0.3)
			(layers "F.Cu" "F.Mask" "F.Paste")
			(roundrect_rratio 0.25)
			(net 34 "/Debug FTDI + VNA/FTDI_VCORE")
			(pinfunction "V_{CORE}")
			(pintype "power_in")
		)
		(pad "3" smd roundrect
			(at -3.938 -2.25)
			(size 0.875 0.3)
			(layers "F.Cu" "F.Mask" "F.Paste")
			(roundrect_rratio 0.25)
			(net 4 "/Debug FTDI + VNA/FTDI_XI")
			(pinfunction "OSCI")
			(pintype "input")
		)
		(pad "4" smd roundrect
			(at -3.938 -1.75)
			(size 0.875 0.3)
			(layers "F.Cu" "F.Mask" "F.Paste")
			(roundrect_rratio 0.25)
			(net 7 "/Debug FTDI + VNA/FTDI_XO")
			(pinfunction "OSCO")
			(pintype "output")
		)
		(pad "5" smd roundrect
			(at -3.938 -1.25)
			(size 0.875 0.3)
			(layers "F.Cu" "F.Mask" "F.Paste")
			(roundrect_rratio 0.25)
			(net 5 "/Debug FTDI + VNA/FTDI_VPHY")
			(pinfunction "V_{PHY}")
			(pintype "power_in")
		)
		(pad "6" smd roundrect
			(at -3.938 -0.75)
			(size 0.875 0.3)
			(layers "F.Cu" "F.Mask" "F.Paste")
			(roundrect_rratio 0.25)
			(net 293 "Net-(U6-REF)")
			(pinfunction "REF")
			(pintype "input")
		)
		(pad "7" smd roundrect
			(at -3.938 -0.25)
			(size 0.875 0.3)
			(layers "F.Cu" "F.Mask" "F.Paste")
			(roundrect_rratio 0.25)
			(net 365 "/Debug FTDI + VNA/DBG_USB_N")
			(pinfunction "D-")
			(pintype "bidirectional")
		)
		(pad "8" smd roundrect
			(at -3.938 0.249)
			(size 0.875 0.3)
			(layers "F.Cu" "F.Mask" "F.Paste")
			(roundrect_rratio 0.25)
			(net 364 "/Debug FTDI + VNA/DBG_USB_P")
			(pinfunction "D+")
			(pintype "bidirectional")
		)
		(pad "9" smd roundrect
			(at -3.938 0.749)
			(size 0.875 0.3)
			(layers "F.Cu" "F.Mask" "F.Paste")
			(roundrect_rratio 0.25)
			(net 3 "/Debug FTDI + VNA/FTDI_VPLL")
			(pinfunction "V_{PLL}")
			(pintype "power_in")
		)
		(pad "10" smd roundrect
			(at -3.938 1.249)
			(size 0.875 0.3)
			(layers "F.Cu" "F.Mask" "F.Paste")
			(roundrect_rratio 0.25)
			(net 1 "GND")
			(pinfunction "TEST")
			(pintype "input")
		)
		(pad "11" smd roundrect
			(at -3.938 1.749)
			(size 0.875 0.3)
			(layers "F.Cu" "F.Mask" "F.Paste")
			(roundrect_rratio 0.25)
			(net 289 "Net-(U6-~{RESET})")
			(pinfunction "~{RESET}")
			(pintype "input")
		)
		(pad "12" smd roundrect
			(at -3.938 2.249)
			(size 0.875 0.3)
			(layers "F.Cu" "F.Mask" "F.Paste")
			(roundrect_rratio 0.25)
			(net 781 "/Debug FTDI + VNA/FTDI_JTAG_TCK")
			(pinfunction "ADBUS0")
			(pintype "bidirectional")
		)
		(pad "13" smd roundrect
			(at -3.938 2.749)
			(size 0.875 0.3)
			(layers "F.Cu" "F.Mask" "F.Paste")
			(roundrect_rratio 0.25)
			(net 786 "/Debug FTDI + VNA/FTDI_JTAG_TDI")
			(pinfunction "ADBUS1")
			(pintype "bidirectional")
		)
		(pad "14" smd roundrect
			(at -3.938 3.249)
			(size 0.875 0.3)
			(layers "F.Cu" "F.Mask" "F.Paste")
			(roundrect_rratio 0.25)
			(net 787 "/Debug FTDI + VNA/FTDI_JTAG_TDO")
			(pinfunction "ADBUS2")
			(pintype "bidirectional")
		)
		(pad "15" smd roundrect
			(at -3.25 3.937 90)
			(size 0.875 0.3)
			(layers "F.Cu" "F.Mask" "F.Paste")
			(roundrect_rratio 0.25)
			(net 788 "/Debug FTDI + VNA/FTDI_JTAG_TMS")
			(pinfunction "ADBUS3")
			(pintype "bidirectional")
		)
		(pad "16" smd roundrect
			(at -2.75 3.937 90)
			(size 0.875 0.3)
			(layers "F.Cu" "F.Mask" "F.Paste")
			(roundrect_rratio 0.25)
			(net 6 "/Debug FTDI + VNA/FTDI_3V3")
			(pinfunction "V_{CCIO}")
			(pintype "power_in")
		)
		(pad "17" smd roundrect
			(at -2.25 3.937 90)
			(size 0.875 0.3)
			(layers "F.Cu" "F.Mask" "F.Paste")
			(roundrect_rratio 0.25)
			(net 312 "unconnected-(U6-ADBUS4-Pad17)")
			(pinfunction "ADBUS4")
			(pintype "bidirectional+no_connect")
		)
		(pad "18" smd roundrect
			(at -1.75 3.937 90)
			(size 0.875 0.3)
			(layers "F.Cu" "F.Mask" "F.Paste")
			(roundrect_rratio 0.25)
			(net 776 "/Debug FTDI + VNA/FTDI_JTAG_RST")
			(pinfunction "ADBUS5")
			(pintype "bidirectional")
		)
		(pad "19" smd roundrect
			(at -1.25 3.937 90)
			(size 0.875 0.3)
			(layers "F.Cu" "F.Mask" "F.Paste")
			(roundrect_rratio 0.25)
			(net 313 "unconnected-(U6-ADBUS6-Pad19)")
			(pinfunction "ADBUS6")
			(pintype "bidirectional+no_connect")
		)
		(pad "20" smd roundrect
			(at -0.75 3.937 90)
			(size 0.875 0.3)
			(layers "F.Cu" "F.Mask" "F.Paste")
			(roundrect_rratio 0.25)
			(net 314 "unconnected-(U6-ADBUS7-Pad20)")
			(pinfunction "ADBUS7")
			(pintype "bidirectional+no_connect")
		)
		(pad "21" smd roundrect
			(at -0.25 3.937 90)
			(size 0.875 0.3)
			(layers "F.Cu" "F.Mask" "F.Paste")
			(roundrect_rratio 0.25)
			(net 1 "GND")
			(pinfunction "GND")
			(pintype "power_in")
		)
		(pad "22" smd roundrect
			(at 0.249 3.937 90)
			(size 0.875 0.3)
			(layers "F.Cu" "F.Mask" "F.Paste")
			(roundrect_rratio 0.25)
			(net 379 "/Debug FTDI + VNA/BDBUS0")
			(pinfunction "BDBUS0")
			(pintype "bidirectional")
		)
		(pad "23" smd roundrect
			(at 0.749 3.937 90)
			(size 0.875 0.3)
			(layers "F.Cu" "F.Mask" "F.Paste")
			(roundrect_rratio 0.25)
			(net 390 "/Debug FTDI + VNA/BDBUS1")
			(pinfunction "BDBUS1")
			(pintype "bidirectional")
		)
		(pad "24" smd roundrect
			(at 1.249 3.937 90)
			(size 0.875 0.3)
			(layers "F.Cu" "F.Mask" "F.Paste")
			(roundrect_rratio 0.25)
			(net 392 "/Debug FTDI + VNA/BDBUS2")
			(pinfunction "BDBUS2")
			(pintype "bidirectional")
		)
		(pad "25" smd roundrect
			(at 1.749 3.937 90)
			(size 0.875 0.3)
			(layers "F.Cu" "F.Mask" "F.Paste")
			(roundrect_rratio 0.25)
			(net 407 "/Debug FTDI + VNA/BDBUS3")
			(pinfunction "BDBUS3")
			(pintype "bidirectional")
		)
		(pad "26" smd roundrect
			(at 2.249 3.937 90)
			(size 0.875 0.3)
			(layers "F.Cu" "F.Mask" "F.Paste")
			(roundrect_rratio 0.25)
			(net 315 "unconnected-(U6-BDBUS4-Pad26)")
			(pinfunction "BDBUS4")
			(pintype "bidirectional+no_connect")
		)
		(pad "27" smd roundrect
			(at 2.749 3.937 90)
			(size 0.875 0.3)
			(layers "F.Cu" "F.Mask" "F.Paste")
			(roundrect_rratio 0.25)
			(net 441 "/Debug FTDI + VNA/I2C_EN")
			(pinfunction "BDBUS5")
			(pintype "bidirectional")
		)
		(pad "28" smd roundrect
			(at 3.249 3.937 90)
			(size 0.875 0.3)
			(layers "F.Cu" "F.Mask" "F.Paste")
			(roundrect_rratio 0.25)
			(net 316 "unconnected-(U6-BDBUS6-Pad28)")
			(pinfunction "BDBUS6")
			(pintype "bidirectional+no_connect")
		)
		(pad "29" smd roundrect
			(at 3.937 3.249)
			(size 0.875 0.3)
			(layers "F.Cu" "F.Mask" "F.Paste")
			(roundrect_rratio 0.25)
			(net 317 "unconnected-(U6-BDBUS7-Pad29)")
			(pinfunction "BDBUS7")
			(pintype "bidirectional+no_connect")
		)
		(pad "30" smd roundrect
			(at 3.937 2.749)
			(size 0.875 0.3)
			(layers "F.Cu" "F.Mask" "F.Paste")
			(roundrect_rratio 0.25)
			(net 318 "unconnected-(U6-~{SUSPEND}-Pad30)")
			(pinfunction "~{SUSPEND}")
			(pintype "output+no_connect")
		)
		(pad "31" smd roundrect
			(at 3.937 2.249)
			(size 0.875 0.3)
			(layers "F.Cu" "F.Mask" "F.Paste")
			(roundrect_rratio 0.25)
			(net 34 "/Debug FTDI + VNA/FTDI_VCORE")
			(pinfunction "V_{CORE}")
			(pintype "passive")
		)
		(pad "32" smd roundrect
			(at 3.937 1.749)
			(size 0.875 0.3)
			(layers "F.Cu" "F.Mask" "F.Paste")
			(roundrect_rratio 0.25)
			(net 789 "/Debug FTDI + VNA/FTDI_UART0_TX")
			(pinfunction "CDBUS0")
			(pintype "bidirectional")
		)
		(pad "33" smd roundrect
			(at 3.937 1.249)
			(size 0.875 0.3)
			(layers "F.Cu" "F.Mask" "F.Paste")
			(roundrect_rratio 0.25)
			(net 790 "/Debug FTDI + VNA/FTDI_UART0_RX")
			(pinfunction "CDBUS1")
			(pintype "bidirectional")
		)
		(pad "34" smd roundrect
			(at 3.937 0.749)
			(size 0.875 0.3)
			(layers "F.Cu" "F.Mask" "F.Paste")
			(roundrect_rratio 0.25)
			(net 319 "unconnected-(U6-CDBUS2-Pad34)")
			(pinfunction "CDBUS2")
			(pintype "bidirectional+no_connect")
		)
		(pad "35" smd roundrect
			(at 3.937 0.249)
			(size 0.875 0.3)
			(layers "F.Cu" "F.Mask" "F.Paste")
			(roundrect_rratio 0.25)
			(net 320 "unconnected-(U6-CDBUS3-Pad35)")
			(pinfunction "CDBUS3")
			(pintype "bidirectional+no_connect")
		)
		(pad "36" smd roundrect
			(at 3.937 -0.25)
			(size 0.875 0.3)
			(layers "F.Cu" "F.Mask" "F.Paste")
			(roundrect_rratio 0.25)
			(net 6 "/Debug FTDI + VNA/FTDI_3V3")
			(pinfunction "V_{CCIO}")
			(pintype "passive")
		)
		(pad "37" smd roundrect
			(at 3.937 -0.75)
			(size 0.875 0.3)
			(layers "F.Cu" "F.Mask" "F.Paste")
			(roundrect_rratio 0.25)
			(net 326 "unconnected-(U6-CDBUS4-Pad37)")
			(pinfunction "CDBUS4")
			(pintype "bidirectional+no_connect")
		)
		(pad "38" smd roundrect
			(at 3.937 -1.25)
			(size 0.875 0.3)
			(layers "F.Cu" "F.Mask" "F.Paste")
			(roundrect_rratio 0.25)
			(net 327 "unconnected-(U6-CDBUS5-Pad38)")
			(pinfunction "CDBUS5")
			(pintype "bidirectional+no_connect")
		)
		(pad "39" smd roundrect
			(at 3.937 -1.75)
			(size 0.875 0.3)
			(layers "F.Cu" "F.Mask" "F.Paste")
			(roundrect_rratio 0.25)
			(net 328 "unconnected-(U6-CDBUS6-Pad39)")
			(pinfunction "CDBUS6")
			(pintype "bidirectional+no_connect")
		)
		(pad "40" smd roundrect
			(at 3.937 -2.25)
			(size 0.875 0.3)
			(layers "F.Cu" "F.Mask" "F.Paste")
			(roundrect_rratio 0.25)
			(net 329 "unconnected-(U6-CDBUS7-Pad40)")
			(pinfunction "CDBUS7")
			(pintype "bidirectional+no_connect")
		)
		(pad "41" smd roundrect
			(at 3.937 -2.75)
			(size 0.875 0.3)
			(layers "F.Cu" "F.Mask" "F.Paste")
			(roundrect_rratio 0.25)
			(net 1 "GND")
			(pinfunction "GND")
			(pintype "passive")
		)
		(pad "42" smd roundrect
			(at 3.937 -3.25)
			(size 0.875 0.3)
			(layers "F.Cu" "F.Mask" "F.Paste")
			(roundrect_rratio 0.25)
			(net 791 "/Debug FTDI + VNA/FTDI_UART1_TX")
			(pinfunction "DDBUS0")
			(pintype "bidirectional")
		)
		(pad "43" smd roundrect
			(at 3.249 -3.938 90)
			(size 0.875 0.3)
			(layers "F.Cu" "F.Mask" "F.Paste")
			(roundrect_rratio 0.25)
			(net 34 "/Debug FTDI + VNA/FTDI_VCORE")
			(pinfunction "V_{REGOUT}")
			(pintype "power_out")
		)
		(pad "44" smd roundrect
			(at 2.749 -3.938 90)
			(size 0.875 0.3)
			(layers "F.Cu" "F.Mask" "F.Paste")
			(roundrect_rratio 0.25)
			(net 6 "/Debug FTDI + VNA/FTDI_3V3")
			(pinfunction "V_{REGIN}")
			(pintype "power_in")
		)
		(pad "45" smd roundrect
			(at 2.249 -3.938 90)
			(size 0.875 0.3)
			(layers "F.Cu" "F.Mask" "F.Paste")
			(roundrect_rratio 0.25)
			(net 1 "GND")
			(pinfunction "GND")
			(pintype "passive")
		)
		(pad "46" smd roundrect
			(at 1.749 -3.938 90)
			(size 0.875 0.3)
			(layers "F.Cu" "F.Mask" "F.Paste")
			(roundrect_rratio 0.25)
			(net 792 "/Debug FTDI + VNA/FTDI_UART1_RX")
			(pinfunction "DDBUS1")
			(pintype "bidirectional")
		)
		(pad "47" smd roundrect
			(at 1.249 -3.938 90)
			(size 0.875 0.3)
			(layers "F.Cu" "F.Mask" "F.Paste")
			(roundrect_rratio 0.25)
			(net 343 "unconnected-(U6-DDBUS2-Pad47)")
			(pinfunction "DDBUS2")
			(pintype "bidirectional+no_connect")
		)
		(pad "48" smd roundrect
			(at 0.749 -3.938 90)
			(size 0.875 0.3)
			(layers "F.Cu" "F.Mask" "F.Paste")
			(roundrect_rratio 0.25)
			(net 345 "unconnected-(U6-DDBUS3-Pad48)")
			(pinfunction "DDBUS3")
			(pintype "bidirectional+no_connect")
		)
		(pad "49" smd roundrect
			(at 0.249 -3.938 90)
			(size 0.875 0.3)
			(layers "F.Cu" "F.Mask" "F.Paste")
			(roundrect_rratio 0.25)
			(net 347 "unconnected-(U6-DDBUS4-Pad49)")
			(pinfunction "DDBUS4")
			(pintype "bidirectional+no_connect")
		)
		(pad "50" smd roundrect
			(at -0.25 -3.938 90)
			(size 0.875 0.3)
			(layers "F.Cu" "F.Mask" "F.Paste")
			(roundrect_rratio 0.25)
			(net 6 "/Debug FTDI + VNA/FTDI_3V3")
			(pinfunction "V_{CCIO}")
			(pintype "passive")
		)
		(pad "51" smd roundrect
			(at -0.75 -3.938 90)
			(size 0.875 0.3)
			(layers "F.Cu" "F.Mask" "F.Paste")
			(roundrect_rratio 0.25)
			(net 411 "unconnected-(U6-DDBUS5-Pad51)")
			(pinfunction "DDBUS5")
			(pintype "bidirectional+no_connect")
		)
		(pad "52" smd roundrect
			(at -1.25 -3.938 90)
			(size 0.875 0.3)
			(layers "F.Cu" "F.Mask" "F.Paste")
			(roundrect_rratio 0.25)
			(net 412 "unconnected-(U6-DDBUS6-Pad52)")
			(pinfunction "DDBUS6")
			(pintype "bidirectional+no_connect")
		)
		(pad "53" smd roundrect
			(at -1.75 -3.938 90)
			(size 0.875 0.3)
			(layers "F.Cu" "F.Mask" "F.Paste")
			(roundrect_rratio 0.25)
			(net 413 "unconnected-(U6-DDBUS7-Pad53)")
			(pinfunction "DDBUS7")
			(pintype "bidirectional+no_connect")
		)
		(pad "54" smd roundrect
			(at -2.25 -3.938 90)
			(size 0.875 0.3)
			(layers "F.Cu" "F.Mask" "F.Paste")
			(roundrect_rratio 0.25)
			(net 372 "/Debug FTDI + VNA/FTDI_PWREN")
			(pinfunction "~{PWR_{EN}}")
			(pintype "output")
		)
		(pad "55" smd roundrect
			(at -2.75 -3.938 90)
			(size 0.875 0.3)
			(layers "F.Cu" "F.Mask" "F.Paste")
			(roundrect_rratio 0.25)
			(net 793 "/Debug FTDI + VNA/FTDI_EEDAT")
			(pinfunction "EEDATA")
			(pintype "bidirectional")
		)
		(pad "56" smd roundrect
			(at -3.25 -3.938 90)
			(size 0.875 0.3)
			(layers "F.Cu" "F.Mask" "F.Paste")
			(roundrect_rratio 0.25)
			(net 794 "/Debug FTDI + VNA/FTDI_EECLK")
			(pinfunction "EECLK")
			(pintype "output")
		)
		(pad "57" smd rect
			(at 0 0)
			(size 5.9 5.9)
			(layers "F.Cu" "F.Mask")
			(net 1 "GND")
			(pinfunction "GND")
			(pintype "passive")
		)
	)
	(footprint "antmicro-footprints:PinHeader_2x7_P2mm_SMD_Shrouded_no-locator"
		(layer "F.Cu")
		(at 225.472 146.85 90)
		(descr "Pin Header 2x7 SMD Shrouded no-locator")
		(property "Reference" "J1"
			(at -9.85 3.753 0)
			(layer "F.SilkS")
			(effects
				(font
					(size 0.7 0.7)
					(thickness 0.15)
				)
				(justify right bottom)
			)
		)
		(property "Value" "PinHeader_2x7_P2mm_SMD_Shrouded_no-locator"
			(at 0 5.038 90)
			(layer "F.Fab")
			(effects
				(font
					(size 0.7 0.7)
					(thickness 0.15)
				)
				(justify left bottom)
			)
		)
		(property "Datasheet" "https://www.molex.com/pdm_docs/ps/PS-87831-027-001.pdf"
			(at 0 0 90)
			(layer "F.Fab")
			(hide yes)
			(effects
				(font
					(size 1.27 1.27)
					(thickness 0.15)
				)
			)
		)
		(property "MPN" "878321412"
			(at 0 0 90)
			(unlocked yes)
			(layer "F.Fab")
			(hide yes)
			(effects
				(font
					(size 1 1)
					(thickness 0.15)
				)
			)
		)
		(property "Manufacturer" "Molex"
			(at 0 0 90)
			(unlocked yes)
			(layer "F.Fab")
			(hide yes)
			(effects
				(font
					(size 1 1)
					(thickness 0.15)
				)
			)
		)
		(property "Author" "Antmicro"
			(at 0 0 90)
			(unlocked yes)
			(layer "F.Fab")
			(hide yes)
			(effects
				(font
					(size 1 1)
					(thickness 0.15)
				)
			)
		)
		(property "License" "Apache-2.0"
			(at 0 0 90)
			(unlocked yes)
			(layer "F.Fab")
			(hide yes)
			(effects
				(font
					(size 1 1)
					(thickness 0.15)
				)
			)
		)
		(sheetname "/FPGA Config/")
		(sheetfile "fpga-config.kicad_sch")
		(attr smd exclude_from_bom dnp)
		(fp_line
			(start 8.499 -3.301)
			(end 7.998 -3.301)
			(stroke
				(width 0.15)
				(type solid)
			)
			(layer "F.SilkS")
		)
		(fp_line
			(start 8.499 -3.301)
			(end 8.499 -2.801)
			(stroke
				(width 0.15)
				(type solid)
			)
			(layer "F.SilkS")
		)
		(fp_line
			(start -8.5 -3.301)
			(end -8 -3.301)
			(stroke
				(width 0.15)
				(type solid)
			)
			(layer "F.SilkS")
		)
		(fp_line
			(start -8.5 -3.301)
			(end -8.5 -2.801)
			(stroke
				(width 0.15)
				(type solid)
			)
			(layer "F.SilkS")
		)
		(fp_line
			(start -1.397 2.41)
			(end -0.9 2.41)
			(stroke
				(width 0.15)
				(type solid)
			)
			(layer "F.SilkS")
		)
		(fp_line
			(start -1.397 2.41)
			(end -1.397 2.91)
			(stroke
				(width 0.15)
				(type solid)
			)
			(layer "F.SilkS")
		)
		(fp_line
			(start 1.394 2.418)
			(end 0.897 2.418)
			(stroke
				(width 0.15)
				(type solid)
			)
			(layer "F.SilkS")
		)
		(fp_line
			(start 1.394 2.418)
			(end 1.394 2.918)
			(stroke
				(width 0.15)
				(type solid)
			)
			(layer "F.SilkS")
		)
		(fp_line
			(start 8.499 3.297)
			(end 8.499 2.797)
			(stroke
				(width 0.15)
				(type solid)
			)
			(layer "F.SilkS")
		)
		(fp_line
			(start 8.499 3.297)
			(end 7.998 3.297)
			(stroke
				(width 0.15)
				(type solid)
			)
			(layer "F.SilkS")
		)
		(fp_line
			(start -8.5 3.297)
			(end -8.5 2.797)
			(stroke
				(width 0.15)
				(type solid)
			)
			(layer "F.SilkS")
		)
		(fp_line
			(start -8.5 3.297)
			(end -8 3.297)
			(stroke
				(width 0.15)
				(type solid)
			)
			(layer "F.SilkS")
		)
		(fp_circle
			(center -6.8 3.4)
			(end -6.748 3.4)
			(stroke
				(width 0.15)
				(type solid)
			)
			(fill yes)
			(layer "F.SilkS")
		)
		(fp_rect
			(start -8.7 -3.7)
			(end 8.7 3.7)
			(stroke
				(width 0.05)
				(type solid)
			)
			(fill no)
			(layer "F.CrtYd")
		)
		(fp_line
			(start -8.325 -3.15)
			(end 8.323 -3.15)
			(stroke
				(width 0.15)
				(type solid)
			)
			(layer "F.Fab")
		)
		(fp_line
			(start 1.394 2.41)
			(end 1.394 3.14)
			(stroke
				(width 0.15)
				(type solid)
			)
			(layer "F.Fab")
		)
		(fp_line
			(start -1.397 2.41)
			(end 1.394 2.41)
			(stroke
				(width 0.15)
				(type solid)
			)
			(layer "F.Fab")
		)
		(fp_line
			(start -1.397 2.41)
			(end -1.397 3.14)
			(stroke
				(width 0.15)
				(type solid)
			)
			(layer "F.Fab")
		)
		(fp_line
			(start 8.323 3.148)
			(end 8.323 -3.15)
			(stroke
				(width 0.15)
				(type solid)
			)
			(layer "F.Fab")
		)
		(fp_line
			(start 1.394 3.148)
			(end 8.323 3.148)
			(stroke
				(width 0.15)
				(type solid)
			)
			(layer "F.Fab")
		)
		(fp_line
			(start -8.325 3.148)
			(end -8.325 -3.15)
			(stroke
				(width 0.15)
				(type solid)
			)
			(layer "F.Fab")
		)
		(fp_line
			(start -8.325 3.148)
			(end -1.397 3.148)
			(stroke
				(width 0.15)
				(type solid)
			)
			(layer "F.Fab")
		)
		(fp_text user "${REFERENCE}"
			(at -8.933 9.438 90)
			(layer "F.Fab")
			(effects
				(font
					(size 0.7 0.7)
					(thickness 0.15)
				)
				(justify left bottom)
			)
		)
		(fp_text user "Author: Antmicro"
			(at -8.933 8.237 90)
			(layer "F.Fab")
			(effects
				(font
					(size 0.7 0.7)
					(thickness 0.15)
				)
				(justify left bottom)
			)
		)
		(fp_text user "License: Apache-2.0"
			(at -8.933 7.038 90)
			(layer "F.Fab")
			(effects
				(font
					(size 0.7 0.7)
					(thickness 0.15)
				)
				(justify left bottom)
			)
		)
		(pad "1" smd rect
			(at -6 2.128 90)
			(size 1 2.75)
			(layers "F.Cu" "F.Mask" "F.Paste")
			(net 1 "GND")
			(pintype "passive")
		)
		(pad "2" smd rect
			(at -6 -2.13 90)
			(size 1 2.75)
			(layers "F.Cu" "F.Mask" "F.Paste")
			(net 797 "+1V8")
			(pintype "passive")
		)
		(pad "3" smd rect
			(at -4 2.128 90)
			(size 1 2.75)
			(layers "F.Cu" "F.Mask" "F.Paste")
			(net 1 "GND")
			(pintype "passive")
		)
		(pad "4" smd rect
			(at -4 -2.13 90)
			(size 1 2.75)
			(layers "F.Cu" "F.Mask" "F.Paste")
			(net 238 "/Debug FTDI + VNA/JTAG.TMS")
			(pintype "passive")
		)
		(pad "5" smd rect
			(at -2 2.128 90)
			(size 1 2.75)
			(layers "F.Cu" "F.Mask" "F.Paste")
			(net 1 "GND")
			(pintype "passive")
		)
		(pad "6" smd rect
			(at -2 -2.13 90)
			(size 1 2.75)
			(layers "F.Cu" "F.Mask" "F.Paste")
			(net 239 "/Debug FTDI + VNA/JTAG.TCK")
			(pintype "passive")
		)
		(pad "7" smd rect
			(at 0 2.128 90)
			(size 1 2.75)
			(layers "F.Cu" "F.Mask" "F.Paste")
			(net 1 "GND")
			(pintype "passive")
		)
		(pad "8" smd rect
			(at 0 -2.13 90)
			(size 1 2.75)
			(layers "F.Cu" "F.Mask" "F.Paste")
			(net 242 "/Debug FTDI + VNA/JTAG.TDO")
			(pintype "passive")
		)
		(pad "9" smd rect
			(at 1.999 2.128 90)
			(size 1 2.75)
			(layers "F.Cu" "F.Mask" "F.Paste")
			(net 1 "GND")
			(pintype "passive")
		)
		(pad "10" smd rect
			(at 1.999 -2.13 90)
			(size 1 2.75)
			(layers "F.Cu" "F.Mask" "F.Paste")
			(net 244 "/Debug FTDI + VNA/JTAG.TDI")
			(pintype "passive")
		)
		(pad "11" smd rect
			(at 3.999 2.128 90)
			(size 1 2.75)
			(layers "F.Cu" "F.Mask" "F.Paste")
			(net 1 "GND")
			(pintype "passive")
		)
		(pad "12" smd rect
			(at 3.999 -2.13 90)
			(size 1 2.75)
			(layers "F.Cu" "F.Mask" "F.Paste")
			(net 240 "unconnected-(J1-Pad12)")
			(pintype "passive+no_connect")
		)
		(pad "13" smd rect
			(at 5.998 2.128 90)
			(size 1 2.75)
			(layers "F.Cu" "F.Mask" "F.Paste")
			(net 1 "GND")
			(pintype "passive")
		)
		(pad "14" smd rect
			(at 5.998 -2.13 90)
			(size 1 2.75)
			(layers "F.Cu" "F.Mask" "F.Paste")
			(net 241 "unconnected-(J1-Pad14)")
			(pintype "passive+no_connect")
		)
	)
	(footprint "antmicro-footprints:BarrelJack_Pin2mm_694106106102"
		(layer "F.Cu")
		(at 259.67 119.47)
		(property "Reference" "J7"
			(at -7.17 -4.97 0)
			(layer "F.SilkS")
			(effects
				(font
					(size 0.7 0.7)
					(thickness 0.15)
				)
				(justify left bottom)
			)
		)
		(property "Value" "BarrelJack_Pin2mm_694106106102"
			(at -8.13 7.78 0)
			(layer "F.Fab")
			(effects
				(font
					(size 0.7 0.7)
					(thickness 0.15)
				)
				(justify left bottom)
			)
		)
		(property "Datasheet" "https://www.we-online.com/components/products/datasheet/694106106102.pdf"
			(at 2.55 0 0)
			(layer "F.Fab")
			(hide yes)
			(effects
				(font
					(size 0.7 0.7)
					(thickness 0.15)
				)
				(justify left bottom)
			)
		)
		(property "Description" "DC Power Connector, Jack, 5 A, 2 mm, PCB Mount, Surface Mount"
			(at 2.55 0 0)
			(layer "F.Fab")
			(hide yes)
			(effects
				(font
					(size 0.7 0.7)
					(thickness 0.15)
				)
				(justify left bottom)
			)
		)
		(property "MPN" "694106106102"
			(at 0 0 0)
			(unlocked yes)
			(layer "F.Fab")
			(hide yes)
			(effects
				(font
					(size 1 1)
					(thickness 0.15)
				)
			)
		)
		(property "Manufacturer" "Würth Elektronik"
			(at 0 0 0)
			(unlocked yes)
			(layer "F.Fab")
			(hide yes)
			(effects
				(font
					(size 1 1)
					(thickness 0.15)
				)
			)
		)
		(property "Author" "Antmicro"
			(at 0 0 0)
			(unlocked yes)
			(layer "F.Fab")
			(hide yes)
			(effects
				(font
					(size 1 1)
					(thickness 0.15)
				)
			)
		)
		(property "License" "Apache-2.0"
			(at 0 0 0)
			(unlocked yes)
			(layer "F.Fab")
			(hide yes)
			(effects
				(font
					(size 1 1)
					(thickness 0.15)
				)
			)
		)
		(sheetname "/Supply/")
		(sheetfile "supply.kicad_sch")
		(attr smd)
		(fp_line
			(start -7.3 -4.49)
			(end -7.3 -2.59)
			(stroke
				(width 0.15)
				(type solid)
			)
			(layer "F.SilkS")
		)
		(fp_line
			(start -7.3 -4.49)
			(end -5.1 -4.49)
			(stroke
				(width 0.15)
				(type solid)
			)
			(layer "F.SilkS")
		)
		(fp_line
			(start -6.54 4.98)
			(end -6.54 3.67)
			(stroke
				(width 0.15)
				(type solid)
			)
			(layer "F.SilkS")
		)
		(fp_line
			(start -6.54 4.98)
			(end -5.23 4.98)
			(stroke
				(width 0.15)
				(type solid)
			)
			(layer "F.SilkS")
		)
		(fp_line
			(start 0 -4.49)
			(end -1.9 -4.49)
			(stroke
				(width 0.15)
				(type solid)
			)
			(layer "F.SilkS")
		)
		(fp_line
			(start 0 4.9)
			(end -1.9 4.9)
			(stroke
				(width 0.15)
				(type solid)
			)
			(layer "F.SilkS")
		)
		(fp_line
			(start 3.905 -4.49)
			(end 3.915 4.51)
			(stroke
				(width 0.15)
				(type solid)
			)
			(layer "F.SilkS")
		)
		(fp_circle
			(center -8.05 5.4)
			(end -8 5.4)
			(stroke
				(width 0.15)
				(type solid)
			)
			(fill yes)
			(layer "F.SilkS")
		)
		(fp_rect
			(start -7.75 -6.8)
			(end 7.75 6.8)
			(stroke
				(width 0.05)
				(type solid)
			)
			(fill no)
			(layer "F.CrtYd")
		)
		(fp_rect
			(start -7.3 4.51)
			(end 7.4 -4.49)
			(stroke
				(width 0.15)
				(type solid)
			)
			(fill no)
			(layer "F.Fab")
		)
		(fp_rect
			(start 3.9 -4.49)
			(end 7.4 4.51)
			(stroke
				(width 0.15)
				(type solid)
			)
			(fill no)
			(layer "F.Fab")
		)
		(fp_text user "License: Apache-2.0"
			(at -8.1 8.8 0)
			(layer "F.Fab")
			(effects
				(font
					(size 0.7 0.7)
					(thickness 0.15)
				)
				(justify left bottom)
			)
		)
		(fp_text user "Author: Antmicro"
			(at -8.1 11.2 0)
			(layer "F.Fab")
			(effects
				(font
					(size 0.7 0.7)
					(thickness 0.15)
				)
				(justify left bottom)
			)
		)
		(fp_text user "${REFERENCE}"
			(at -8.1 10 0)
			(layer "F.Fab")
			(effects
				(font
					(size 0.7 0.7)
					(thickness 0.15)
				)
				(justify left bottom)
			)
		)
		(pad "" np_thru_hole circle
			(at -2.1 0 90)
			(size 1.8 1.8)
			(drill 1.8)
			(layers "*.Cu" "*.Mask")
		)
		(pad "" np_thru_hole circle
			(at 2.4 0 90)
			(size 1.6 1.6)
			(drill 1.6)
			(layers "*.Cu" "*.Mask")
		)
		(pad "1" smd roundrect
			(at -3.75 5.4 270)
			(size 2 2)
			(layers "F.Cu" "F.Mask" "F.Paste")
			(roundrect_rratio 0.1)
			(net 325 "/Supply/12V_aux")
			(pinfunction "1")
			(pintype "passive")
		)
		(pad "1" smd roundrect
			(at 2.4 5.4 270)
			(size 2 2)
			(layers "F.Cu" "F.Mask" "F.Paste")
			(roundrect_rratio 0.1)
			(net 325 "/Supply/12V_aux")
			(pinfunction "1")
			(pintype "passive")
		)
		(pad "2" smd roundrect
			(at 2.4 -5.4 270)
			(size 2 2)
			(layers "F.Cu" "F.Mask" "F.Paste")
			(roundrect_rratio 0.1)
			(net 1 "GND")
			(pinfunction "2")
			(pintype "passive")
		)
		(pad "3" smd roundrect
			(at -3.75 -5.4 270)
			(size 2 2)
			(layers "F.Cu" "F.Mask" "F.Paste")
			(roundrect_rratio 0.1)
			(net 1 "GND")
			(pinfunction "3")
			(pintype "passive")
		)
	)
	(footprint "antmicro-footprints:SW_DIP_SPSTx03_Slide_Copal_CVS-03xB_W5.9mm_P1mm"
		(layer "F.Cu")
		(at 149.3 181.75)
		(descr "SMD 3x-dip-switch SPST Copal_CVS-03xB, Slide, row spacing 5.9 mm (232 mils), body size  (see http://www.nidec-copal-electronics.com/e/catalog/switch/cvs.pdf)")
		(tags "SMD DIP Switch SPST Slide")
		(property "Reference" "SW1"
			(at 0.725 3.55 0)
			(layer "F.SilkS")
			(effects
				(font
					(size 0.7 0.7)
					(thickness 0.15)
				)
				(justify left bottom)
			)
		)
		(property "Value" "CVS-03B"
			(at 0.248 4.799 0)
			(layer "F.Fab")
			(effects
				(font
					(size 0.7 0.7)
					(thickness 0.15)
				)
				(justify left bottom)
			)
		)
		(property "Datasheet" "https://www.mouser.com/datasheet/2/972/cvs-1827291.pdf"
			(at 0 0 0)
			(layer "F.Fab")
			(hide yes)
			(effects
				(font
					(size 1.27 1.27)
					(thickness 0.15)
				)
			)
		)
		(property "MPN" "CVS-03B"
			(at 0 0 0)
			(unlocked yes)
			(layer "F.Fab")
			(hide yes)
			(effects
				(font
					(size 1 1)
					(thickness 0.15)
				)
			)
		)
		(property "Manufacturer" "Nidec Components"
			(at 0 0 0)
			(unlocked yes)
			(layer "F.Fab")
			(hide yes)
			(effects
				(font
					(size 1 1)
					(thickness 0.15)
				)
			)
		)
		(property "Author" "Antmicro"
			(at 0 0 0)
			(unlocked yes)
			(layer "F.Fab")
			(hide yes)
			(effects
				(font
					(size 1 1)
					(thickness 0.15)
				)
			)
		)
		(property "License" "Apache-2.0"
			(at 0 0 0)
			(unlocked yes)
			(layer "F.Fab")
			(hide yes)
			(effects
				(font
					(size 1 1)
					(thickness 0.15)
				)
			)
		)
		(property ki_fp_filters "SW?DIP?x2*")
		(sheetname "/PCIe connector/")
		(sheetfile "pcie-connector.kicad_sch")
		(attr smd)
		(fp_line
			(start -1.51 -2.411)
			(end 1.61 -2.411)
			(stroke
				(width 0.15)
				(type solid)
			)
			(layer "F.SilkS")
		)
		(fp_line
			(start -1.51 2.41)
			(end 1.61 2.41)
			(stroke
				(width 0.15)
				(type solid)
			)
			(layer "F.SilkS")
		)
		(fp_circle
			(center -3.33 -1.641)
			(end -3.281 -1.641)
			(stroke
				(width 0.15)
				(type solid)
			)
			(fill yes)
			(layer "F.SilkS")
		)
		(fp_rect
			(start -3.56 -2.5)
			(end 3.66 2.49)
			(stroke
				(width 0.05)
				(type solid)
			)
			(fill no)
			(layer "F.CrtYd")
		)
		(fp_line
			(start -2.301 -1)
			(end -1.301 -2)
			(stroke
				(width 0.15)
				(type solid)
			)
			(layer "F.Fab")
		)
		(fp_line
			(start -2.301 1.999)
			(end -2.301 -1)
			(stroke
				(width 0.15)
				(type solid)
			)
			(layer "F.Fab")
		)
		(fp_line
			(start -1.301 -2)
			(end 2.398 -2)
			(stroke
				(width 0.15)
				(type solid)
			)
			(layer "F.Fab")
		)
		(fp_line
			(start -0.951 -1.25)
			(end -0.951 -0.75)
			(stroke
				(width 0.15)
				(type solid)
			)
			(layer "F.Fab")
		)
		(fp_line
			(start -0.951 -1.151)
			(end -0.285 -1.151)
			(stroke
				(width 0.15)
				(type solid)
			)
			(layer "F.Fab")
		)
		(fp_line
			(start -0.951 -1.051)
			(end -0.285 -1.051)
			(stroke
				(width 0.15)
				(type solid)
			)
			(layer "F.Fab")
		)
		(fp_line
			(start -0.951 -0.952)
			(end -0.285 -0.952)
			(stroke
				(width 0.15)
				(type solid)
			)
			(layer "F.Fab")
		)
		(fp_line
			(start -0.951 -0.85)
			(end -0.285 -0.85)
			(stroke
				(width 0.15)
				(type solid)
			)
			(layer "F.Fab")
		)
		(fp_line
			(start -0.951 -0.75)
			(end 1.05 -0.75)
			(stroke
				(width 0.15)
				(type solid)
			)
			(layer "F.Fab")
		)
		(fp_line
			(start -0.951 -0.25)
			(end -0.951 0.247)
			(stroke
				(width 0.15)
				(type solid)
			)
			(layer "F.Fab")
		)
		(fp_line
			(start -0.951 -0.15)
			(end -0.285 -0.15)
			(stroke
				(width 0.15)
				(type solid)
			)
			(layer "F.Fab")
		)
		(fp_line
			(start -0.951 -0.053)
			(end -0.285 -0.053)
			(stroke
				(width 0.15)
				(type solid)
			)
			(layer "F.Fab")
		)
		(fp_line
			(start -0.951 0.05)
			(end -0.285 0.05)
			(stroke
				(width 0.15)
				(type solid)
			)
			(layer "F.Fab")
		)
		(fp_line
			(start -0.951 0.147)
			(end -0.285 0.147)
			(stroke
				(width 0.15)
				(type solid)
			)
			(layer "F.Fab")
		)
		(fp_line
			(start -0.951 0.247)
			(end 1.05 0.247)
			(stroke
				(width 0.15)
				(type solid)
			)
			(layer "F.Fab")
		)
		(fp_line
			(start -0.951 0.747)
			(end -0.951 1.249)
			(stroke
				(width 0.15)
				(type solid)
			)
			(layer "F.Fab")
		)
		(fp_line
			(start -0.951 0.847)
			(end -0.285 0.847)
			(stroke
				(width 0.15)
				(type solid)
			)
			(layer "F.Fab")
		)
		(fp_line
			(start -0.951 0.949)
			(end -0.285 0.949)
			(stroke
				(width 0.15)
				(type solid)
			)
			(layer "F.Fab")
		)
		(fp_line
			(start -0.951 1.05)
			(end -0.285 1.05)
			(stroke
				(width 0.15)
				(type solid)
			)
			(layer "F.Fab")
		)
		(fp_line
			(start -0.951 1.148)
			(end -0.285 1.148)
			(stroke
				(width 0.15)
				(type solid)
			)
			(layer "F.Fab")
		)
		(fp_line
			(start -0.951 1.249)
			(end 1.05 1.249)
			(stroke
				(width 0.15)
				(type solid)
			)
			(layer "F.Fab")
		)
		(fp_line
			(start -0.285 -1.25)
			(end -0.285 -0.75)
			(stroke
				(width 0.15)
				(type solid)
			)
			(layer "F.Fab")
		)
		(fp_line
			(start -0.285 -0.25)
			(end -0.285 0.247)
			(stroke
				(width 0.15)
				(type solid)
			)
			(layer "F.Fab")
		)
		(fp_line
			(start -0.285 0.747)
			(end -0.285 1.249)
			(stroke
				(width 0.15)
				(type solid)
			)
			(layer "F.Fab")
		)
		(fp_line
			(start 1.05 -1.25)
			(end -0.951 -1.25)
			(stroke
				(width 0.15)
				(type solid)
			)
			(layer "F.Fab")
		)
		(fp_line
			(start 1.05 -0.75)
			(end 1.05 -1.25)
			(stroke
				(width 0.15)
				(type solid)
			)
			(layer "F.Fab")
		)
		(fp_line
			(start 1.05 -0.25)
			(end -0.951 -0.25)
			(stroke
				(width 0.15)
				(type solid)
			)
			(layer "F.Fab")
		)
		(fp_line
			(start 1.05 0.247)
			(end 1.05 -0.25)
			(stroke
				(width 0.15)
				(type solid)
			)
			(layer "F.Fab")
		)
		(fp_line
			(start 1.05 0.747)
			(end -0.951 0.747)
			(stroke
				(width 0.15)
				(type solid)
			)
			(layer "F.Fab")
		)
		(fp_line
			(start 1.05 1.249)
			(end 1.05 0.747)
			(stroke
				(width 0.15)
				(type solid)
			)
			(layer "F.Fab")
		)
		(fp_line
			(start 2.398 -2)
			(end 2.398 1.999)
			(stroke
				(width 0.15)
				(type solid)
			)
			(layer "F.Fab")
		)
		(fp_line
			(start 2.398 1.999)
			(end -2.301 1.999)
			(stroke
				(width 0.15)
				(type solid)
			)
			(layer "F.Fab")
		)
		(fp_text user "Author: Antmicro"
			(at -3.56 7.999 0)
			(layer "F.Fab")
			(effects
				(font
					(size 0.7 0.7)
					(thickness 0.15)
				)
				(justify left bottom)
			)
		)
		(fp_text user "${REFERENCE}"
			(at -3.56 9.199 0)
			(layer "F.Fab")
			(effects
				(font
					(size 0.7 0.7)
					(thickness 0.15)
				)
				(justify left bottom)
			)
		)
		(fp_text user "on"
			(at -1.44 0.72 90)
			(layer "F.Fab")
			(effects
				(font
					(size 0.7 0.7)
					(thickness 0.15)
				)
				(justify left bottom)
			)
		)
		(fp_text user "License: Apache-2.0"
			(at -3.56 10.399 0)
			(layer "F.Fab")
			(effects
				(font
					(size 0.7 0.7)
					(thickness 0.15)
				)
				(justify left bottom)
			)
		)
		(pad "1" smd rect
			(at -2.899 -1)
			(size 1.2 0.5)
			(layers "F.Cu" "F.Mask" "F.Paste")
			(net 174 "/PCIe connector/PRSNT#1")
			(pinfunction "1")
			(pintype "passive")
		)
		(pad "2" smd rect
			(at -2.899 0)
			(size 1.2 0.5)
			(layers "F.Cu" "F.Mask" "F.Paste")
			(net 174 "/PCIe connector/PRSNT#1")
			(pinfunction "2")
			(pintype "passive")
		)
		(pad "3" smd rect
			(at -2.899 0.997)
			(size 1.2 0.5)
			(layers "F.Cu" "F.Mask" "F.Paste")
			(net 174 "/PCIe connector/PRSNT#1")
			(pinfunction "3")
			(pintype "passive")
		)
		(pad "4" smd rect
			(at 2.999 0.997)
			(size 1.2 0.5)
			(layers "F.Cu" "F.Mask" "F.Paste")
			(net 591 "/PCIe connector/x8")
			(pinfunction "4")
			(pintype "passive")
		)
		(pad "5" smd rect
			(at 2.999 0)
			(size 1.2 0.5)
			(layers "F.Cu" "F.Mask" "F.Paste")
			(net 176 "/PCIe connector/x4")
			(pinfunction "5")
			(pintype "passive")
		)
		(pad "6" smd rect
			(at 2.999 -1)
			(size 1.2 0.5)
			(layers "F.Cu" "F.Mask" "F.Paste")
			(net 175 "/PCIe connector/x1")
			(pinfunction "6")
			(pintype "passive")
		)
		(pad "7" smd rect
			(at -2.101 -2)
			(size 0.7 0.7)
			(layers "F.Cu" "F.Mask" "F.Paste")
			(net 1 "GND")
			(pinfunction "7")
			(pintype "power_in")
		)
		(pad "7" smd rect
			(at -2.101 1.999)
			(size 0.7 0.7)
			(layers "F.Cu" "F.Mask" "F.Paste")
			(net 1 "GND")
			(pinfunction "7")
			(pintype "power_in")
		)
		(pad "7" smd rect
			(at 2.201 -2)
			(size 0.7 0.7)
			(layers "F.Cu" "F.Mask" "F.Paste")
			(net 1 "GND")
			(pinfunction "7")
			(pintype "power_in")
		)
		(pad "7" smd rect
			(at 2.201 1.999)
			(size 0.7 0.7)
			(layers "F.Cu" "F.Mask" "F.Paste")
			(net 1 "GND")
			(pinfunction "7")
			(pintype "power_in")
		)
	)
	(footprint "antmicro-footprints:USON-10_2.5x1mm_P0.5mm"
		(layer "F.Cu")
		(at 113.530499 175.7685 180)
		(descr "USON-10 2.5x1mm_ Pitch 0.5mm")
		(tags "USON-10 2.5x1mm Pitch 0.5mm")
		(property "Reference" "U48"
			(at -1.799501 0.1985 90)
			(layer "F.SilkS")
			(effects
				(font
					(size 0.7 0.7)
					(thickness 0.15)
				)
				(justify right bottom)
			)
		)
		(property "Value" "TPD4E05U06QDQARQ1"
			(at 0.018 2.499 0)
			(layer "F.Fab")
			(effects
				(font
					(size 0.7 0.7)
					(thickness 0.15)
				)
				(justify right bottom)
			)
		)
		(property "Datasheet" "https://www.ti.com/lit/ds/symlink/tpd4e05u06-q1.pdf?HQS=dis-mous-null-mousermode-dsf-pf-null-wwe&ts=1663591265741&ref_url=https%253A%252F%252Fwww.mouser.com%252F"
			(at 0 0 180)
			(layer "F.Fab")
			(hide yes)
			(effects
				(font
					(size 1.27 1.27)
					(thickness 0.15)
				)
			)
		)
		(property "Manufacturer" "Texas Instruments"
			(at 0 0 180)
			(unlocked yes)
			(layer "F.Fab")
			(hide yes)
			(effects
				(font
					(size 1 1)
					(thickness 0.15)
				)
			)
		)
		(property "MPN" "TPD4E05U06QDQARQ1"
			(at 0 0 180)
			(unlocked yes)
			(layer "F.Fab")
			(hide yes)
			(effects
				(font
					(size 1 1)
					(thickness 0.15)
				)
			)
		)
		(property "Author" "Antmicro"
			(at 0 0 180)
			(unlocked yes)
			(layer "F.Fab")
			(hide yes)
			(effects
				(font
					(size 1 1)
					(thickness 0.15)
				)
			)
		)
		(property "License" "Apache-2.0"
			(at 0 0 180)
			(unlocked yes)
			(layer "F.Fab")
			(hide yes)
			(effects
				(font
					(size 1 1)
					(thickness 0.15)
				)
			)
		)
		(sheetname "/HDMI + SD Card/")
		(sheetfile "hdmi-sd-card.kicad_sch")
		(attr smd)
		(fp_line
			(start 0.498 1.398)
			(end -0.5 1.398)
			(stroke
				(width 0.15)
				(type solid)
			)
			(layer "F.SilkS")
		)
		(fp_line
			(start 0.498 -1.401)
			(end -0.5 -1.401)
			(stroke
				(width 0.15)
				(type solid)
			)
			(layer "F.SilkS")
		)
		(fp_circle
			(center -0.68 -1.27)
			(end -0.63 -1.27)
			(stroke
				(width 0.15)
				(type solid)
			)
			(fill yes)
			(layer "F.SilkS")
		)
		(fp_rect
			(start -0.8 -1.5)
			(end 0.8 1.499)
			(stroke
				(width 0.05)
				(type solid)
			)
			(fill no)
			(layer "F.CrtYd")
		)
		(fp_line
			(start 0.498 -1.25)
			(end 0.498 1.249)
			(stroke
				(width 0.15)
				(type solid)
			)
			(layer "F.Fab")
		)
		(fp_line
			(start 0.498 -1.25)
			(end -0.25 -1.25)
			(stroke
				(width 0.15)
				(type solid)
			)
			(layer "F.Fab")
		)
		(fp_line
			(start -0.25 -1.25)
			(end -0.5 -1)
			(stroke
				(width 0.15)
				(type solid)
			)
			(layer "F.Fab")
		)
		(fp_line
			(start -0.5 1.249)
			(end 0.498 1.249)
			(stroke
				(width 0.15)
				(type solid)
			)
			(layer "F.Fab")
		)
		(fp_line
			(start -0.5 -1)
			(end -0.5 1.249)
			(stroke
				(width 0.15)
				(type solid)
			)
			(layer "F.Fab")
		)
		(fp_text user "License: Apache-2.0"
			(at -0.802 6.9 180)
			(layer "F.Fab")
			(effects
				(font
					(size 0.7 0.7)
					(thickness 0.15)
				)
				(justify left bottom)
			)
		)
		(fp_text user "Author: Antmicro"
			(at -0.802 5.7 180)
			(layer "F.Fab")
			(effects
				(font
					(size 0.7 0.7)
					(thickness 0.15)
				)
				(justify left bottom)
			)
		)
		(fp_text user "${REFERENCE}"
			(at -0.802 4.498 180)
			(layer "F.Fab")
			(effects
				(font
					(size 0.7 0.7)
					(thickness 0.15)
				)
				(justify left bottom)
			)
		)
		(pad "1" smd roundrect
			(at -0.387 -1 90)
			(size 0.25 0.55)
			(layers "F.Cu" "F.Mask" "F.Paste")
			(roundrect_rratio 0.25)
			(net 467 "/HDMI + SD Card/HDMI_OUT_C.SCL")
			(pintype "passive")
		)
		(pad "2" smd roundrect
			(at -0.387 -0.5 90)
			(size 0.25 0.55)
			(layers "F.Cu" "F.Mask" "F.Paste")
			(roundrect_rratio 0.25)
			(net 468 "/HDMI + SD Card/HDMI_OUT_C.SDA")
			(pintype "passive")
		)
		(pad "3" smd roundrect
			(at -0.387 0 90)
			(size 0.4 0.55)
			(layers "F.Cu" "F.Mask" "F.Paste")
			(roundrect_rratio 0.25)
			(net 1 "GND")
			(pintype "power_in")
		)
		(pad "4" smd roundrect
			(at -0.387 0.498 90)
			(size 0.25 0.55)
			(layers "F.Cu" "F.Mask" "F.Paste")
			(roundrect_rratio 0.25)
			(net 8 "/HDMI + SD Card/HDMI_CONN_5V")
			(pintype "passive")
		)
		(pad "5" smd roundrect
			(at -0.387 0.998 90)
			(size 0.25 0.55)
			(layers "F.Cu" "F.Mask" "F.Paste")
			(roundrect_rratio 0.25)
			(net 605 "/HDMI + SD Card/HDMI0.HPD")
			(pintype "passive")
		)
		(pad "6" smd roundrect
			(at 0.385 0.998 90)
			(size 0.25 0.55)
			(layers "F.Cu" "F.Mask" "F.Paste")
			(roundrect_rratio 0.25)
			(net 605 "/HDMI + SD Card/HDMI0.HPD")
			(pintype "passive")
		)
		(pad "7" smd roundrect
			(at 0.385 0.498 90)
			(size 0.25 0.55)
			(layers "F.Cu" "F.Mask" "F.Paste")
			(roundrect_rratio 0.25)
			(net 8 "/HDMI + SD Card/HDMI_CONN_5V")
			(pintype "passive")
		)
		(pad "8" smd roundrect
			(at 0.385 0 90)
			(size 0.4 0.55)
			(layers "F.Cu" "F.Mask" "F.Paste")
			(roundrect_rratio 0.25)
			(net 1 "GND")
			(pintype "passive")
		)
		(pad "9" smd roundrect
			(at 0.385 -0.5 90)
			(size 0.25 0.55)
			(layers "F.Cu" "F.Mask" "F.Paste")
			(roundrect_rratio 0.25)
			(net 468 "/HDMI + SD Card/HDMI_OUT_C.SDA")
			(pintype "passive")
		)
		(pad "10" smd roundrect
			(at 0.385 -1 90)
			(size 0.25 0.55)
			(layers "F.Cu" "F.Mask" "F.Paste")
			(roundrect_rratio 0.25)
			(net 467 "/HDMI + SD Card/HDMI_OUT_C.SCL")
			(pintype "passive")
		)
	)
	(footprint "antmicro-footprints:R_0402_1005Metric"
		(layer "B.Cu")
		(at 141.124499 169.399 -90)
		(descr "Resistor SMD 0402")
		(tags "resistor SMD 0402")
		(property "Reference" "R56"
			(at -4.045 -0.505501 90)
			(layer "B.SilkS")
			(effects
				(font
					(size 0.7 0.7)
					(thickness 0.15)
				)
				(justify left bottom mirror)
			)
		)
		(property "Value" "R_22R_0402"
			(at -1.011843 -1.772047 90)
			(layer "B.Fab")
			(effects
				(font
					(size 0.7 0.7)
					(thickness 0.15)
				)
				(justify left bottom mirror)
			)
		)
		(property "Datasheet" "https://www.bourns.com/docs/product-datasheets/cr.pdf"
			(at 0 0 270)
			(layer "F.Fab")
			(hide yes)
			(effects
				(font
					(size 1.27 1.27)
					(thickness 0.15)
				)
			)
		)
		(property "Manufacturer" "Bourns"
			(at 0 0 270)
			(unlocked yes)
			(layer "B.Fab")
			(hide yes)
			(effects
				(font
					(size 1 1)
					(thickness 0.15)
				)
				(justify mirror)
			)
		)
		(property "MPN" "CR0402-FX-22R0GLF"
			(at 0 0 270)
			(unlocked yes)
			(layer "B.Fab")
			(hide yes)
			(effects
				(font
					(size 1 1)
					(thickness 0.15)
				)
				(justify mirror)
			)
		)
		(property "Val" "22R"
			(at 0 0 270)
			(unlocked yes)
			(layer "B.Fab")
			(hide yes)
			(effects
				(font
					(size 1 1)
					(thickness 0.15)
				)
				(justify mirror)
			)
		)
		(property "License" "Apache-2.0"
			(at 0 0 270)
			(unlocked yes)
			(layer "B.Fab")
			(hide yes)
			(effects
				(font
					(size 1 1)
					(thickness 0.15)
				)
				(justify mirror)
			)
		)
		(property "Author" "Antmicro"
			(at 0 0 270)
			(unlocked yes)
			(layer "B.Fab")
			(hide yes)
			(effects
				(font
					(size 1 1)
					(thickness 0.15)
				)
				(justify mirror)
			)
		)
		(property "Tolerance" "1%"
			(at 0 0 270)
			(unlocked yes)
			(layer "B.Fab")
			(hide yes)
			(effects
				(font
					(size 1 1)
					(thickness 0.15)
				)
				(justify mirror)
			)
		)
		(sheetname "/Debug FTDI + VNA/")
		(sheetfile "debug-ftdi.kicad_sch")
		(attr smd exclude_from_bom dnp)
		(fp_rect
			(start -0.925 0.47)
			(end 0.925 -0.47)
			(stroke
				(width 0.05)
				(type default)
			)
			(fill no)
			(layer "B.CrtYd")
		)
		(fp_rect
			(start -0.5 0.25)
			(end 0.5 -0.25)
			(stroke
				(width 0.15)
				(type solid)
			)
			(fill no)
			(layer "B.Fab")
		)
		(fp_text user "License: Apache-2.0"
			(at -0.95 -5.169 90)
			(layer "B.Fab")
			(effects
				(font
					(size 0.7 0.7)
					(thickness 0.15)
				)
				(justify left bottom mirror)
			)
		)
		(fp_text user "Author: Antmicro"
			(at -0.95 -4.169 90)
			(layer "B.Fab")
			(effects
				(font
					(size 0.7 0.7)
					(thickness 0.15)
				)
				(justify left bottom mirror)
			)
		)
		(fp_text user "${REFERENCE}"
			(at -0.95 -3.168 90)
			(layer "B.Fab")
			(effects
				(font
					(size 0.7 0.7)
					(thickness 0.15)
				)
				(justify left bottom mirror)
			)
		)
		(pad "1" smd roundrect
			(at -0.48 0 270)
			(size 0.59 0.64)
			(layers "B.Cu" "B.Mask" "B.Paste")
			(roundrect_rratio 0.25)
			(net 379 "/Debug FTDI + VNA/BDBUS0")
			(pintype "passive")
		)
		(pad "2" smd roundrect
			(at 0.48 0 270)
			(size 0.59 0.64)
			(layers "B.Cu" "B.Mask" "B.Paste")
			(roundrect_rratio 0.25)
			(net 388 "/Debug FTDI + VNA/AUX.TCK")
			(pintype "passive")
		)
	)
	(footprint "antmicro-footprints:R_0402_1005Metric"
		(layer "B.Cu")
		(at 142.174499 169.399 -90)
		(descr "Resistor SMD 0402")
		(tags "resistor SMD 0402")
		(property "Reference" "R57"
			(at -4.045 -0.505501 90)
			(layer "B.SilkS")
			(effects
				(font
					(size 0.7 0.7)
					(thickness 0.15)
				)
				(justify left bottom mirror)
			)
		)
		(property "Value" "R_22R_0402"
			(at -1.011843 -1.772047 90)
			(layer "B.Fab")
			(effects
				(font
					(size 0.7 0.7)
					(thickness 0.15)
				)
				(justify left bottom mirror)
			)
		)
		(property "Datasheet" "https://www.bourns.com/docs/product-datasheets/cr.pdf"
			(at 0 0 270)
			(layer "F.Fab")
			(hide yes)
			(effects
				(font
					(size 1.27 1.27)
					(thickness 0.15)
				)
			)
		)
		(property "Manufacturer" "Bourns"
			(at 0 0 270)
			(unlocked yes)
			(layer "B.Fab")
			(hide yes)
			(effects
				(font
					(size 1 1)
					(thickness 0.15)
				)
				(justify mirror)
			)
		)
		(property "MPN" "CR0402-FX-22R0GLF"
			(at 0 0 270)
			(unlocked yes)
			(layer "B.Fab")
			(hide yes)
			(effects
				(font
					(size 1 1)
					(thickness 0.15)
				)
				(justify mirror)
			)
		)
		(property "Val" "22R"
			(at 0 0 270)
			(unlocked yes)
			(layer "B.Fab")
			(hide yes)
			(effects
				(font
					(size 1 1)
					(thickness 0.15)
				)
				(justify mirror)
			)
		)
		(property "License" "Apache-2.0"
			(at 0 0 270)
			(unlocked yes)
			(layer "B.Fab")
			(hide yes)
			(effects
				(font
					(size 1 1)
					(thickness 0.15)
				)
				(justify mirror)
			)
		)
		(property "Author" "Antmicro"
			(at 0 0 270)
			(unlocked yes)
			(layer "B.Fab")
			(hide yes)
			(effects
				(font
					(size 1 1)
					(thickness 0.15)
				)
				(justify mirror)
			)
		)
		(property "Tolerance" "1%"
			(at 0 0 270)
			(unlocked yes)
			(layer "B.Fab")
			(hide yes)
			(effects
				(font
					(size 1 1)
					(thickness 0.15)
				)
				(justify mirror)
			)
		)
		(sheetname "/Debug FTDI + VNA/")
		(sheetfile "debug-ftdi.kicad_sch")
		(attr smd exclude_from_bom dnp)
		(fp_rect
			(start -0.925 0.47)
			(end 0.925 -0.47)
			(stroke
				(width 0.05)
				(type default)
			)
			(fill no)
			(layer "B.CrtYd")
		)
		(fp_rect
			(start -0.5 0.25)
			(end 0.5 -0.25)
			(stroke
				(width 0.15)
				(type solid)
			)
			(fill no)
			(layer "B.Fab")
		)
		(fp_text user "Author: Antmicro"
			(at -0.95 -4.169 90)
			(layer "B.Fab")
			(effects
				(font
					(size 0.7 0.7)
					(thickness 0.15)
				)
				(justify left bottom mirror)
			)
		)
		(fp_text user "${REFERENCE}"
			(at -0.95 -3.168 90)
			(layer "B.Fab")
			(effects
				(font
					(size 0.7 0.7)
					(thickness 0.15)
				)
				(justify left bottom mirror)
			)
		)
		(fp_text user "License: Apache-2.0"
			(at -0.95 -5.169 90)
			(layer "B.Fab")
			(effects
				(font
					(size 0.7 0.7)
					(thickness 0.15)
				)
				(justify left bottom mirror)
			)
		)
		(pad "1" smd roundrect
			(at -0.48 0 270)
			(size 0.59 0.64)
			(layers "B.Cu" "B.Mask" "B.Paste")
			(roundrect_rratio 0.25)
			(net 390 "/Debug FTDI + VNA/BDBUS1")
			(pintype "passive")
		)
		(pad "2" smd roundrect
			(at 0.48 0 270)
			(size 0.59 0.64)
			(layers "B.Cu" "B.Mask" "B.Paste")
			(roundrect_rratio 0.25)
			(net 391 "/Debug FTDI + VNA/AUX.TDI")
			(pintype "passive")
		)
	)
	(footprint "antmicro-footprints:R_0402_1005Metric"
		(layer "B.Cu")
		(at 143.224499 169.399 -90)
		(descr "Resistor SMD 0402")
		(tags "resistor SMD 0402")
		(property "Reference" "R58"
			(at -4.045 -0.505501 90)
			(layer "B.SilkS")
			(effects
				(font
					(size 0.7 0.7)
					(thickness 0.15)
				)
				(justify left bottom mirror)
			)
		)
		(property "Value" "R_22R_0402"
			(at -1.011843 -1.772047 90)
			(layer "B.Fab")
			(effects
				(font
					(size 0.7 0.7)
					(thickness 0.15)
				)
				(justify left bottom mirror)
			)
		)
		(property "Datasheet" "https://www.bourns.com/docs/product-datasheets/cr.pdf"
			(at 0 0 270)
			(layer "F.Fab")
			(hide yes)
			(effects
				(font
					(size 1.27 1.27)
					(thickness 0.15)
				)
			)
		)
		(property "Manufacturer" "Bourns"
			(at 0 0 270)
			(unlocked yes)
			(layer "B.Fab")
			(hide yes)
			(effects
				(font
					(size 1 1)
					(thickness 0.15)
				)
				(justify mirror)
			)
		)
		(property "MPN" "CR0402-FX-22R0GLF"
			(at 0 0 270)
			(unlocked yes)
			(layer "B.Fab")
			(hide yes)
			(effects
				(font
					(size 1 1)
					(thickness 0.15)
				)
				(justify mirror)
			)
		)
		(property "Val" "22R"
			(at 0 0 270)
			(unlocked yes)
			(layer "B.Fab")
			(hide yes)
			(effects
				(font
					(size 1 1)
					(thickness 0.15)
				)
				(justify mirror)
			)
		)
		(property "License" "Apache-2.0"
			(at 0 0 270)
			(unlocked yes)
			(layer "B.Fab")
			(hide yes)
			(effects
				(font
					(size 1 1)
					(thickness 0.15)
				)
				(justify mirror)
			)
		)
		(property "Author" "Antmicro"
			(at 0 0 270)
			(unlocked yes)
			(layer "B.Fab")
			(hide yes)
			(effects
				(font
					(size 1 1)
					(thickness 0.15)
				)
				(justify mirror)
			)
		)
		(property "Tolerance" "1%"
			(at 0 0 270)
			(unlocked yes)
			(layer "B.Fab")
			(hide yes)
			(effects
				(font
					(size 1 1)
					(thickness 0.15)
				)
				(justify mirror)
			)
		)
		(sheetname "/Debug FTDI + VNA/")
		(sheetfile "debug-ftdi.kicad_sch")
		(attr smd exclude_from_bom dnp)
		(fp_rect
			(start -0.925 0.47)
			(end 0.925 -0.47)
			(stroke
				(width 0.05)
				(type default)
			)
			(fill no)
			(layer "B.CrtYd")
		)
		(fp_rect
			(start -0.5 0.25)
			(end 0.5 -0.25)
			(stroke
				(width 0.15)
				(type solid)
			)
			(fill no)
			(layer "B.Fab")
		)
		(fp_text user "${REFERENCE}"
			(at -0.95 -3.168 90)
			(layer "B.Fab")
			(effects
				(font
					(size 0.7 0.7)
					(thickness 0.15)
				)
				(justify left bottom mirror)
			)
		)
		(fp_text user "License: Apache-2.0"
			(at -0.95 -5.169 90)
			(layer "B.Fab")
			(effects
				(font
					(size 0.7 0.7)
					(thickness 0.15)
				)
				(justify left bottom mirror)
			)
		)
		(fp_text user "Author: Antmicro"
			(at -0.95 -4.169 90)
			(layer "B.Fab")
			(effects
				(font
					(size 0.7 0.7)
					(thickness 0.15)
				)
				(justify left bottom mirror)
			)
		)
		(pad "1" smd roundrect
			(at -0.48 0 270)
			(size 0.59 0.64)
			(layers "B.Cu" "B.Mask" "B.Paste")
			(roundrect_rratio 0.25)
			(net 392 "/Debug FTDI + VNA/BDBUS2")
			(pintype "passive")
		)
		(pad "2" smd roundrect
			(at 0.48 0 270)
			(size 0.59 0.64)
			(layers "B.Cu" "B.Mask" "B.Paste")
			(roundrect_rratio 0.25)
			(net 406 "/Debug FTDI + VNA/AUX.TDO")
			(pintype "passive")
		)
	)
	(footprint "antmicro-footprints:R_0402_1005Metric"
		(layer "B.Cu")
		(at 145.324499 169.399 -90)
		(descr "Resistor SMD 0402")
		(tags "resistor SMD 0402")
		(property "Reference" "R60"
			(at -4.045 -0.505501 90)
			(layer "B.SilkS")
			(effects
				(font
					(size 0.7 0.7)
					(thickness 0.15)
				)
				(justify left bottom mirror)
			)
		)
		(property "Value" "R_22R_0402"
			(at -1.011843 -1.772047 90)
			(layer "B.Fab")
			(effects
				(font
					(size 0.7 0.7)
					(thickness 0.15)
				)
				(justify left bottom mirror)
			)
		)
		(property "Datasheet" "https://www.bourns.com/docs/product-datasheets/cr.pdf"
			(at 0 0 270)
			(layer "F.Fab")
			(hide yes)
			(effects
				(font
					(size 1.27 1.27)
					(thickness 0.15)
				)
			)
		)
		(property "Manufacturer" "Bourns"
			(at 0 0 270)
			(unlocked yes)
			(layer "B.Fab")
			(hide yes)
			(effects
				(font
					(size 1 1)
					(thickness 0.15)
				)
				(justify mirror)
			)
		)
		(property "MPN" "CR0402-FX-22R0GLF"
			(at 0 0 270)
			(unlocked yes)
			(layer "B.Fab")
			(hide yes)
			(effects
				(font
					(size 1 1)
					(thickness 0.15)
				)
				(justify mirror)
			)
		)
		(property "Val" "22R"
			(at 0 0 270)
			(unlocked yes)
			(layer "B.Fab")
			(hide yes)
			(effects
				(font
					(size 1 1)
					(thickness 0.15)
				)
				(justify mirror)
			)
		)
		(property "License" "Apache-2.0"
			(at 0 0 270)
			(unlocked yes)
			(layer "B.Fab")
			(hide yes)
			(effects
				(font
					(size 1 1)
					(thickness 0.15)
				)
				(justify mirror)
			)
		)
		(property "Author" "Antmicro"
			(at 0 0 270)
			(unlocked yes)
			(layer "B.Fab")
			(hide yes)
			(effects
				(font
					(size 1 1)
					(thickness 0.15)
				)
				(justify mirror)
			)
		)
		(property "Tolerance" "1%"
			(at 0 0 270)
			(unlocked yes)
			(layer "B.Fab")
			(hide yes)
			(effects
				(font
					(size 1 1)
					(thickness 0.15)
				)
				(justify mirror)
			)
		)
		(sheetname "/Debug FTDI + VNA/")
		(sheetfile "debug-ftdi.kicad_sch")
		(attr smd exclude_from_bom dnp)
		(fp_rect
			(start -0.925 0.47)
			(end 0.925 -0.47)
			(stroke
				(width 0.05)
				(type default)
			)
			(fill no)
			(layer "B.CrtYd")
		)
		(fp_rect
			(start -0.5 0.25)
			(end 0.5 -0.25)
			(stroke
				(width 0.15)
				(type solid)
			)
			(fill no)
			(layer "B.Fab")
		)
		(fp_text user "Author: Antmicro"
			(at -0.95 -4.169 90)
			(layer "B.Fab")
			(effects
				(font
					(size 0.7 0.7)
					(thickness 0.15)
				)
				(justify left bottom mirror)
			)
		)
		(fp_text user "License: Apache-2.0"
			(at -0.95 -5.169 90)
			(layer "B.Fab")
			(effects
				(font
					(size 0.7 0.7)
					(thickness 0.15)
				)
				(justify left bottom mirror)
			)
		)
		(fp_text user "${REFERENCE}"
			(at -0.95 -3.168 90)
			(layer "B.Fab")
			(effects
				(font
					(size 0.7 0.7)
					(thickness 0.15)
				)
				(justify left bottom mirror)
			)
		)
		(pad "1" smd roundrect
			(at -0.48 0 270)
			(size 0.59 0.64)
			(layers "B.Cu" "B.Mask" "B.Paste")
			(roundrect_rratio 0.25)
			(net 441 "/Debug FTDI + VNA/I2C_EN")
			(pintype "passive")
		)
		(pad "2" smd roundrect
			(at 0.48 0 270)
			(size 0.59 0.64)
			(layers "B.Cu" "B.Mask" "B.Paste")
			(roundrect_rratio 0.25)
			(net 442 "/Debug FTDI + VNA/AUX.RST")
			(pintype "passive")
		)
	)
	(footprint "antmicro-footprints:R_0402_1005Metric"
		(layer "B.Cu")
		(at 144.274499 169.399 -90)
		(descr "Resistor SMD 0402")
		(tags "resistor SMD 0402")
		(property "Reference" "R59"
			(at -4.045 -0.505501 90)
			(layer "B.SilkS")
			(effects
				(font
					(size 0.7 0.7)
					(thickness 0.15)
				)
				(justify left bottom mirror)
			)
		)
		(property "Value" "R_22R_0402"
			(at -1.011843 -1.772047 90)
			(layer "B.Fab")
			(effects
				(font
					(size 0.7 0.7)
					(thickness 0.15)
				)
				(justify left bottom mirror)
			)
		)
		(property "Datasheet" "https://www.bourns.com/docs/product-datasheets/cr.pdf"
			(at 0 0 270)
			(layer "F.Fab")
			(hide yes)
			(effects
				(font
					(size 1.27 1.27)
					(thickness 0.15)
				)
			)
		)
		(property "Manufacturer" "Bourns"
			(at 0 0 270)
			(unlocked yes)
			(layer "B.Fab")
			(hide yes)
			(effects
				(font
					(size 1 1)
					(thickness 0.15)
				)
				(justify mirror)
			)
		)
		(property "MPN" "CR0402-FX-22R0GLF"
			(at 0 0 270)
			(unlocked yes)
			(layer "B.Fab")
			(hide yes)
			(effects
				(font
					(size 1 1)
					(thickness 0.15)
				)
				(justify mirror)
			)
		)
		(property "Val" "22R"
			(at 0 0 270)
			(unlocked yes)
			(layer "B.Fab")
			(hide yes)
			(effects
				(font
					(size 1 1)
					(thickness 0.15)
				)
				(justify mirror)
			)
		)
		(property "License" "Apache-2.0"
			(at 0 0 270)
			(unlocked yes)
			(layer "B.Fab")
			(hide yes)
			(effects
				(font
					(size 1 1)
					(thickness 0.15)
				)
				(justify mirror)
			)
		)
		(property "Author" "Antmicro"
			(at 0 0 270)
			(unlocked yes)
			(layer "B.Fab")
			(hide yes)
			(effects
				(font
					(size 1 1)
					(thickness 0.15)
				)
				(justify mirror)
			)
		)
		(property "Tolerance" "1%"
			(at 0 0 270)
			(unlocked yes)
			(layer "B.Fab")
			(hide yes)
			(effects
				(font
					(size 1 1)
					(thickness 0.15)
				)
				(justify mirror)
			)
		)
		(sheetname "/Debug FTDI + VNA/")
		(sheetfile "debug-ftdi.kicad_sch")
		(attr smd exclude_from_bom dnp)
		(fp_rect
			(start -0.925 0.47)
			(end 0.925 -0.47)
			(stroke
				(width 0.05)
				(type default)
			)
			(fill no)
			(layer "B.CrtYd")
		)
		(fp_rect
			(start -0.5 0.25)
			(end 0.5 -0.25)
			(stroke
				(width 0.15)
				(type solid)
			)
			(fill no)
			(layer "B.Fab")
		)
		(fp_text user "License: Apache-2.0"
			(at -0.95 -5.169 90)
			(layer "B.Fab")
			(effects
				(font
					(size 0.7 0.7)
					(thickness 0.15)
				)
				(justify left bottom mirror)
			)
		)
		(fp_text user "${REFERENCE}"
			(at -0.95 -3.168 90)
			(layer "B.Fab")
			(effects
				(font
					(size 0.7 0.7)
					(thickness 0.15)
				)
				(justify left bottom mirror)
			)
		)
		(fp_text user "Author: Antmicro"
			(at -0.95 -4.169 90)
			(layer "B.Fab")
			(effects
				(font
					(size 0.7 0.7)
					(thickness 0.15)
				)
				(justify left bottom mirror)
			)
		)
		(pad "1" smd roundrect
			(at -0.48 0 270)
			(size 0.59 0.64)
			(layers "B.Cu" "B.Mask" "B.Paste")
			(roundrect_rratio 0.25)
			(net 407 "/Debug FTDI + VNA/BDBUS3")
			(pintype "passive")
		)
		(pad "2" smd roundrect
			(at 0.48 0 270)
			(size 0.59 0.64)
			(layers "B.Cu" "B.Mask" "B.Paste")
			(roundrect_rratio 0.25)
			(net 408 "/Debug FTDI + VNA/AUX.TMS")
			(pintype "passive")
		)
	)
	(footprint "antmicro-footprints:R_0402_1005Metric"
		(layer "B.Cu")
		(at 140.625 150.025 90)
		(descr "Resistor SMD 0402")
		(tags "resistor SMD 0402")
		(property "Reference" "R101"
			(at -10.375 0.409 90)
			(layer "B.SilkS")
			(effects
				(font
					(size 0.7 0.7)
					(thickness 0.15)
				)
				(justify right bottom mirror)
			)
		)
		(property "Value" "R_10k_0402"
			(at -1.011843 -1.772047 90)
			(layer "B.Fab")
			(effects
				(font
					(size 0.7 0.7)
					(thickness 0.15)
				)
				(justify right bottom mirror)
			)
		)
		(property "Datasheet" "https://www.bourns.com/docs/product-datasheets/cr.pdf"
			(at 0 0 90)
			(layer "F.Fab")
			(hide yes)
			(effects
				(font
					(size 1.27 1.27)
					(thickness 0.15)
				)
			)
		)
		(property "Manufacturer" "Bourns"
			(at 0 0 90)
			(unlocked yes)
			(layer "B.Fab")
			(hide yes)
			(effects
				(font
					(size 1 1)
					(thickness 0.15)
				)
				(justify mirror)
			)
		)
		(property "MPN" "CR0402-FX-1002GLF"
			(at 0 0 90)
			(unlocked yes)
			(layer "B.Fab")
			(hide yes)
			(effects
				(font
					(size 1 1)
					(thickness 0.15)
				)
				(justify mirror)
			)
		)
		(property "Val" "10k"
			(at 0 0 90)
			(unlocked yes)
			(layer "B.Fab")
			(hide yes)
			(effects
				(font
					(size 1 1)
					(thickness 0.15)
				)
				(justify mirror)
			)
		)
		(property "License" "Apache-2.0"
			(at 0 0 90)
			(unlocked yes)
			(layer "B.Fab")
			(hide yes)
			(effects
				(font
					(size 1 1)
					(thickness 0.15)
				)
				(justify mirror)
			)
		)
		(property "Author" "Antmicro"
			(at 0 0 90)
			(unlocked yes)
			(layer "B.Fab")
			(hide yes)
			(effects
				(font
					(size 1 1)
					(thickness 0.15)
				)
				(justify mirror)
			)
		)
		(property "Tolerance" "1%"
			(at 0 0 90)
			(unlocked yes)
			(layer "B.Fab")
			(hide yes)
			(effects
				(font
					(size 1 1)
					(thickness 0.15)
				)
				(justify mirror)
			)
		)
		(sheetname "/Ethernet/")
		(sheetfile "ethernet.kicad_sch")
		(attr smd exclude_from_bom dnp)
		(fp_rect
			(start -0.925 0.47)
			(end 0.925 -0.47)
			(stroke
				(width 0.05)
				(type default)
			)
			(fill no)
			(layer "B.CrtYd")
		)
		(fp_rect
			(start -0.5 0.25)
			(end 0.5 -0.25)
			(stroke
				(width 0.15)
				(type solid)
			)
			(fill no)
			(layer "B.Fab")
		)
		(fp_text user "License: Apache-2.0"
			(at -0.95 -5.169 270)
			(layer "B.Fab")
			(effects
				(font
					(size 0.7 0.7)
					(thickness 0.15)
				)
				(justify left bottom mirror)
			)
		)
		(fp_text user "Author: Antmicro"
			(at -0.95 -4.169 270)
			(layer "B.Fab")
			(effects
				(font
					(size 0.7 0.7)
					(thickness 0.15)
				)
				(justify left bottom mirror)
			)
		)
		(fp_text user "${REFERENCE}"
			(at -0.95 -3.168 270)
			(layer "B.Fab")
			(effects
				(font
					(size 0.7 0.7)
					(thickness 0.15)
				)
				(justify left bottom mirror)
			)
		)
		(pad "1" smd roundrect
			(at -0.48 0 90)
			(size 0.59 0.64)
			(layers "B.Cu" "B.Mask" "B.Paste")
			(roundrect_rratio 0.25)
			(net 393 "/Ethernet/ETH.RXD0")
			(pintype "passive")
		)
		(pad "2" smd roundrect
			(at 0.48 0 90)
			(size 0.59 0.64)
			(layers "B.Cu" "B.Mask" "B.Paste")
			(roundrect_rratio 0.25)
			(net 797 "+1V8")
			(pintype "passive")
		)
	)
	(footprint "antmicro-footprints:R_0402_1005Metric"
		(layer "B.Cu")
		(at 139.575 150.025 90)
		(descr "Resistor SMD 0402")
		(tags "resistor SMD 0402")
		(property "Reference" "R102"
			(at -10.375 0.409 90)
			(layer "B.SilkS")
			(effects
				(font
					(size 0.7 0.7)
					(thickness 0.15)
				)
				(justify right bottom mirror)
			)
		)
		(property "Value" "R_10k_0402"
			(at -1.011843 -1.772047 90)
			(layer "B.Fab")
			(effects
				(font
					(size 0.7 0.7)
					(thickness 0.15)
				)
				(justify right bottom mirror)
			)
		)
		(property "Datasheet" "https://www.bourns.com/docs/product-datasheets/cr.pdf"
			(at 0 0 90)
			(layer "F.Fab")
			(hide yes)
			(effects
				(font
					(size 1.27 1.27)
					(thickness 0.15)
				)
			)
		)
		(property "Manufacturer" "Bourns"
			(at 0 0 90)
			(unlocked yes)
			(layer "B.Fab")
			(hide yes)
			(effects
				(font
					(size 1 1)
					(thickness 0.15)
				)
				(justify mirror)
			)
		)
		(property "MPN" "CR0402-FX-1002GLF"
			(at 0 0 90)
			(unlocked yes)
			(layer "B.Fab")
			(hide yes)
			(effects
				(font
					(size 1 1)
					(thickness 0.15)
				)
				(justify mirror)
			)
		)
		(property "Val" "10k"
			(at 0 0 90)
			(unlocked yes)
			(layer "B.Fab")
			(hide yes)
			(effects
				(font
					(size 1 1)
					(thickness 0.15)
				)
				(justify mirror)
			)
		)
		(property "License" "Apache-2.0"
			(at 0 0 90)
			(unlocked yes)
			(layer "B.Fab")
			(hide yes)
			(effects
				(font
					(size 1 1)
					(thickness 0.15)
				)
				(justify mirror)
			)
		)
		(property "Author" "Antmicro"
			(at 0 0 90)
			(unlocked yes)
			(layer "B.Fab")
			(hide yes)
			(effects
				(font
					(size 1 1)
					(thickness 0.15)
				)
				(justify mirror)
			)
		)
		(property "Tolerance" "1%"
			(at 0 0 90)
			(unlocked yes)
			(layer "B.Fab")
			(hide yes)
			(effects
				(font
					(size 1 1)
					(thickness 0.15)
				)
				(justify mirror)
			)
		)
		(sheetname "/Ethernet/")
		(sheetfile "ethernet.kicad_sch")
		(attr smd exclude_from_bom dnp)
		(fp_rect
			(start -0.925 0.47)
			(end 0.925 -0.47)
			(stroke
				(width 0.05)
				(type default)
			)
			(fill no)
			(layer "B.CrtYd")
		)
		(fp_rect
			(start -0.5 0.25)
			(end 0.5 -0.25)
			(stroke
				(width 0.15)
				(type solid)
			)
			(fill no)
			(layer "B.Fab")
		)
		(fp_text user "${REFERENCE}"
			(at -0.95 -3.168 270)
			(layer "B.Fab")
			(effects
				(font
					(size 0.7 0.7)
					(thickness 0.15)
				)
				(justify left bottom mirror)
			)
		)
		(fp_text user "Author: Antmicro"
			(at -0.95 -4.169 270)
			(layer "B.Fab")
			(effects
				(font
					(size 0.7 0.7)
					(thickness 0.15)
				)
				(justify left bottom mirror)
			)
		)
		(fp_text user "License: Apache-2.0"
			(at -0.95 -5.169 270)
			(layer "B.Fab")
			(effects
				(font
					(size 0.7 0.7)
					(thickness 0.15)
				)
				(justify left bottom mirror)
			)
		)
		(pad "1" smd roundrect
			(at -0.48 0 90)
			(size 0.59 0.64)
			(layers "B.Cu" "B.Mask" "B.Paste")
			(roundrect_rratio 0.25)
			(net 394 "/Ethernet/ETH.RXD1")
			(pintype "passive")
		)
		(pad "2" smd roundrect
			(at 0.48 0 90)
			(size 0.59 0.64)
			(layers "B.Cu" "B.Mask" "B.Paste")
			(roundrect_rratio 0.25)
			(net 797 "+1V8")
			(pintype "passive")
		)
	)
	(footprint "antmicro-footprints:R_0402_1005Metric"
		(layer "B.Cu")
		(at 142.75 150.05 90)
		(descr "Resistor SMD 0402")
		(tags "resistor SMD 0402")
		(property "Reference" "R105"
			(at -10.375 0.409 90)
			(layer "B.SilkS")
			(effects
				(font
					(size 0.7 0.7)
					(thickness 0.15)
				)
				(justify right bottom mirror)
			)
		)
		(property "Value" "R_10k_0402"
			(at -1.011843 -1.772047 90)
			(layer "B.Fab")
			(effects
				(font
					(size 0.7 0.7)
					(thickness 0.15)
				)
				(justify right bottom mirror)
			)
		)
		(property "Datasheet" "https://www.bourns.com/docs/product-datasheets/cr.pdf"
			(at 0 0 90)
			(layer "F.Fab")
			(hide yes)
			(effects
				(font
					(size 1.27 1.27)
					(thickness 0.15)
				)
			)
		)
		(property "Manufacturer" "Bourns"
			(at 0 0 90)
			(unlocked yes)
			(layer "B.Fab")
			(hide yes)
			(effects
				(font
					(size 1 1)
					(thickness 0.15)
				)
				(justify mirror)
			)
		)
		(property "MPN" "CR0402-FX-1002GLF"
			(at 0 0 90)
			(unlocked yes)
			(layer "B.Fab")
			(hide yes)
			(effects
				(font
					(size 1 1)
					(thickness 0.15)
				)
				(justify mirror)
			)
		)
		(property "Val" "10k"
			(at 0 0 90)
			(unlocked yes)
			(layer "B.Fab")
			(hide yes)
			(effects
				(font
					(size 1 1)
					(thickness 0.15)
				)
				(justify mirror)
			)
		)
		(property "License" "Apache-2.0"
			(at 0 0 90)
			(unlocked yes)
			(layer "B.Fab")
			(hide yes)
			(effects
				(font
					(size 1 1)
					(thickness 0.15)
				)
				(justify mirror)
			)
		)
		(property "Author" "Antmicro"
			(at 0 0 90)
			(unlocked yes)
			(layer "B.Fab")
			(hide yes)
			(effects
				(font
					(size 1 1)
					(thickness 0.15)
				)
				(justify mirror)
			)
		)
		(property "Tolerance" "1%"
			(at 0 0 90)
			(unlocked yes)
			(layer "B.Fab")
			(hide yes)
			(effects
				(font
					(size 1 1)
					(thickness 0.15)
				)
				(justify mirror)
			)
		)
		(sheetname "/Ethernet/")
		(sheetfile "ethernet.kicad_sch")
		(attr smd exclude_from_bom dnp)
		(fp_rect
			(start -0.925 0.47)
			(end 0.925 -0.47)
			(stroke
				(width 0.05)
				(type default)
			)
			(fill no)
			(layer "B.CrtYd")
		)
		(fp_rect
			(start -0.5 0.25)
			(end 0.5 -0.25)
			(stroke
				(width 0.15)
				(type solid)
			)
			(fill no)
			(layer "B.Fab")
		)
		(fp_text user "${REFERENCE}"
			(at -0.95 -3.168 270)
			(layer "B.Fab")
			(effects
				(font
					(size 0.7 0.7)
					(thickness 0.15)
				)
				(justify left bottom mirror)
			)
		)
		(fp_text user "License: Apache-2.0"
			(at -0.95 -5.169 270)
			(layer "B.Fab")
			(effects
				(font
					(size 0.7 0.7)
					(thickness 0.15)
				)
				(justify left bottom mirror)
			)
		)
		(fp_text user "Author: Antmicro"
			(at -0.95 -4.169 270)
			(layer "B.Fab")
			(effects
				(font
					(size 0.7 0.7)
					(thickness 0.15)
				)
				(justify left bottom mirror)
			)
		)
		(pad "1" smd roundrect
			(at -0.48 0 90)
			(size 0.59 0.64)
			(layers "B.Cu" "B.Mask" "B.Paste")
			(roundrect_rratio 0.25)
			(net 397 "/Ethernet/ETH.RX_CTL")
			(pintype "passive")
		)
		(pad "2" smd roundrect
			(at 0.48 0 90)
			(size 0.59 0.64)
			(layers "B.Cu" "B.Mask" "B.Paste")
			(roundrect_rratio 0.25)
			(net 797 "+1V8")
			(pintype "passive")
		)
	)
	(footprint "antmicro-footprints:R_0402_1005Metric"
		(layer "B.Cu")
		(at 141.65 150.025 90)
		(descr "Resistor SMD 0402")
		(tags "resistor SMD 0402")
		(property "Reference" "R106"
			(at -10.375 0.409 90)
			(layer "B.SilkS")
			(effects
				(font
					(size 0.7 0.7)
					(thickness 0.15)
				)
				(justify right bottom mirror)
			)
		)
		(property "Value" "R_10k_0402"
			(at -1.011843 -1.772047 90)
			(layer "B.Fab")
			(effects
				(font
					(size 0.7 0.7)
					(thickness 0.15)
				)
				(justify right bottom mirror)
			)
		)
		(property "Datasheet" "https://www.bourns.com/docs/product-datasheets/cr.pdf"
			(at 0 0 90)
			(layer "F.Fab")
			(hide yes)
			(effects
				(font
					(size 1.27 1.27)
					(thickness 0.15)
				)
			)
		)
		(property "Manufacturer" "Bourns"
			(at 0 0 90)
			(unlocked yes)
			(layer "B.Fab")
			(hide yes)
			(effects
				(font
					(size 1 1)
					(thickness 0.15)
				)
				(justify mirror)
			)
		)
		(property "MPN" "CR0402-FX-1002GLF"
			(at 0 0 90)
			(unlocked yes)
			(layer "B.Fab")
			(hide yes)
			(effects
				(font
					(size 1 1)
					(thickness 0.15)
				)
				(justify mirror)
			)
		)
		(property "Val" "10k"
			(at 0 0 90)
			(unlocked yes)
			(layer "B.Fab")
			(hide yes)
			(effects
				(font
					(size 1 1)
					(thickness 0.15)
				)
				(justify mirror)
			)
		)
		(property "License" "Apache-2.0"
			(at 0 0 90)
			(unlocked yes)
			(layer "B.Fab")
			(hide yes)
			(effects
				(font
					(size 1 1)
					(thickness 0.15)
				)
				(justify mirror)
			)
		)
		(property "Author" "Antmicro"
			(at 0 0 90)
			(unlocked yes)
			(layer "B.Fab")
			(hide yes)
			(effects
				(font
					(size 1 1)
					(thickness 0.15)
				)
				(justify mirror)
			)
		)
		(property "Tolerance" "1%"
			(at 0 0 90)
			(unlocked yes)
			(layer "B.Fab")
			(hide yes)
			(effects
				(font
					(size 1 1)
					(thickness 0.15)
				)
				(justify mirror)
			)
		)
		(sheetname "/Ethernet/")
		(sheetfile "ethernet.kicad_sch")
		(attr smd exclude_from_bom dnp)
		(fp_rect
			(start -0.925 0.47)
			(end 0.925 -0.47)
			(stroke
				(width 0.05)
				(type default)
			)
			(fill no)
			(layer "B.CrtYd")
		)
		(fp_rect
			(start -0.5 0.25)
			(end 0.5 -0.25)
			(stroke
				(width 0.15)
				(type solid)
			)
			(fill no)
			(layer "B.Fab")
		)
		(fp_text user "License: Apache-2.0"
			(at -0.95 -5.169 270)
			(layer "B.Fab")
			(effects
				(font
					(size 0.7 0.7)
					(thickness 0.15)
				)
				(justify left bottom mirror)
			)
		)
		(fp_text user "${REFERENCE}"
			(at -0.95 -3.168 270)
			(layer "B.Fab")
			(effects
				(font
					(size 0.7 0.7)
					(thickness 0.15)
				)
				(justify left bottom mirror)
			)
		)
		(fp_text user "Author: Antmicro"
			(at -0.95 -4.169 270)
			(layer "B.Fab")
			(effects
				(font
					(size 0.7 0.7)
					(thickness 0.15)
				)
				(justify left bottom mirror)
			)
		)
		(pad "1" smd roundrect
			(at -0.48 0 90)
			(size 0.59 0.64)
			(layers "B.Cu" "B.Mask" "B.Paste")
			(roundrect_rratio 0.25)
			(net 398 "/Ethernet/ETH.RXC")
			(pintype "passive")
		)
		(pad "2" smd roundrect
			(at 0.48 0 90)
			(size 0.59 0.64)
			(layers "B.Cu" "B.Mask" "B.Paste")
			(roundrect_rratio 0.25)
			(net 797 "+1V8")
			(pintype "passive")
		)
	)
	(footprint "antmicro-footprints:R_0402_1005Metric"
		(layer "B.Cu")
		(at 136.433171 143.399 90)
		(descr "Resistor SMD 0402")
		(tags "resistor SMD 0402")
		(property "Reference" "R107"
			(at -1.701 -3.603171 90)
			(layer "B.SilkS")
			(hide yes)
			(effects
				(font
					(size 0.7 0.7)
					(thickness 0.15)
				)
				(justify right bottom mirror)
			)
		)
		(property "Value" "R_10k_0402"
			(at -1.011843 -1.772047 90)
			(layer "B.Fab")
			(effects
				(font
					(size 0.7 0.7)
					(thickness 0.15)
				)
				(justify right bottom mirror)
			)
		)
		(property "Datasheet" "https://www.bourns.com/docs/product-datasheets/cr.pdf"
			(at 0 0 90)
			(layer "F.Fab")
			(hide yes)
			(effects
				(font
					(size 1.27 1.27)
					(thickness 0.15)
				)
			)
		)
		(property "Manufacturer" "Bourns"
			(at 0 0 90)
			(unlocked yes)
			(layer "B.Fab")
			(hide yes)
			(effects
				(font
					(size 1 1)
					(thickness 0.15)
				)
				(justify mirror)
			)
		)
		(property "MPN" "CR0402-FX-1002GLF"
			(at 0 0 90)
			(unlocked yes)
			(layer "B.Fab")
			(hide yes)
			(effects
				(font
					(size 1 1)
					(thickness 0.15)
				)
				(justify mirror)
			)
		)
		(property "Val" "10k"
			(at 0 0 90)
			(unlocked yes)
			(layer "B.Fab")
			(hide yes)
			(effects
				(font
					(size 1 1)
					(thickness 0.15)
				)
				(justify mirror)
			)
		)
		(property "License" "Apache-2.0"
			(at 0 0 90)
			(unlocked yes)
			(layer "B.Fab")
			(hide yes)
			(effects
				(font
					(size 1 1)
					(thickness 0.15)
				)
				(justify mirror)
			)
		)
		(property "Author" "Antmicro"
			(at 0 0 90)
			(unlocked yes)
			(layer "B.Fab")
			(hide yes)
			(effects
				(font
					(size 1 1)
					(thickness 0.15)
				)
				(justify mirror)
			)
		)
		(property "Tolerance" "1%"
			(at 0 0 90)
			(unlocked yes)
			(layer "B.Fab")
			(hide yes)
			(effects
				(font
					(size 1 1)
					(thickness 0.15)
				)
				(justify mirror)
			)
		)
		(sheetname "/Ethernet/")
		(sheetfile "ethernet.kicad_sch")
		(attr smd)
		(fp_rect
			(start -0.925 0.47)
			(end 0.925 -0.47)
			(stroke
				(width 0.05)
				(type default)
			)
			(fill no)
			(layer "B.CrtYd")
		)
		(fp_rect
			(start -0.5 0.25)
			(end 0.5 -0.25)
			(stroke
				(width 0.15)
				(type solid)
			)
			(fill no)
			(layer "B.Fab")
		)
		(fp_text user "License: Apache-2.0"
			(at -0.95 -5.169 270)
			(layer "B.Fab")
			(effects
				(font
					(size 0.7 0.7)
					(thickness 0.15)
				)
				(justify left bottom mirror)
			)
		)
		(fp_text user "${REFERENCE}"
			(at -0.95 -3.168 270)
			(layer "B.Fab")
			(effects
				(font
					(size 0.7 0.7)
					(thickness 0.15)
				)
				(justify left bottom mirror)
			)
		)
		(fp_text user "Author: Antmicro"
			(at -0.95 -4.169 270)
			(layer "B.Fab")
			(effects
				(font
					(size 0.7 0.7)
					(thickness 0.15)
				)
				(justify left bottom mirror)
			)
		)
		(pad "1" smd roundrect
			(at -0.48 0 90)
			(size 0.59 0.64)
			(layers "B.Cu" "B.Mask" "B.Paste")
			(roundrect_rratio 0.25)
			(net 399 "/Ethernet/ETH.REF_CLK")
			(pintype "passive")
		)
		(pad "2" smd roundrect
			(at 0.48 0 90)
			(size 0.59 0.64)
			(layers "B.Cu" "B.Mask" "B.Paste")
			(roundrect_rratio 0.25)
			(net 797 "+1V8")
			(pintype "passive")
		)
	)
	(footprint "antmicro-footprints:R_0402_1005Metric"
		(layer "B.Cu")
		(at 139.224499 142.249)
		(descr "Resistor SMD 0402")
		(tags "resistor SMD 0402")
		(property "Reference" "R111"
			(at 0.983501 0.499 0)
			(layer "B.SilkS")
			(effects
				(font
					(size 0.7 0.7)
					(thickness 0.15)
				)
				(justify right bottom mirror)
			)
		)
		(property "Value" "R_10k_0402"
			(at -1.011843 -1.772047 0)
			(layer "B.Fab")
			(effects
				(font
					(size 0.7 0.7)
					(thickness 0.15)
				)
				(justify right bottom mirror)
			)
		)
		(property "Datasheet" "https://www.bourns.com/docs/product-datasheets/cr.pdf"
			(at 0 0 0)
			(layer "F.Fab")
			(hide yes)
			(effects
				(font
					(size 1.27 1.27)
					(thickness 0.15)
				)
			)
		)
		(property "Manufacturer" "Bourns"
			(at 0 0 0)
			(unlocked yes)
			(layer "B.Fab")
			(hide yes)
			(effects
				(font
					(size 1 1)
					(thickness 0.15)
				)
				(justify mirror)
			)
		)
		(property "MPN" "CR0402-FX-1002GLF"
			(at 0 0 0)
			(unlocked yes)
			(layer "B.Fab")
			(hide yes)
			(effects
				(font
					(size 1 1)
					(thickness 0.15)
				)
				(justify mirror)
			)
		)
		(property "Val" "10k"
			(at 0 0 0)
			(unlocked yes)
			(layer "B.Fab")
			(hide yes)
			(effects
				(font
					(size 1 1)
					(thickness 0.15)
				)
				(justify mirror)
			)
		)
		(property "License" "Apache-2.0"
			(at 0 0 0)
			(unlocked yes)
			(layer "B.Fab")
			(hide yes)
			(effects
				(font
					(size 1 1)
					(thickness 0.15)
				)
				(justify mirror)
			)
		)
		(property "Author" "Antmicro"
			(at 0 0 0)
			(unlocked yes)
			(layer "B.Fab")
			(hide yes)
			(effects
				(font
					(size 1 1)
					(thickness 0.15)
				)
				(justify mirror)
			)
		)
		(property "Tolerance" "1%"
			(at 0 0 0)
			(unlocked yes)
			(layer "B.Fab")
			(hide yes)
			(effects
				(font
					(size 1 1)
					(thickness 0.15)
				)
				(justify mirror)
			)
		)
		(sheetname "/Ethernet/")
		(sheetfile "ethernet.kicad_sch")
		(attr smd)
		(fp_rect
			(start -0.925 0.47)
			(end 0.925 -0.47)
			(stroke
				(width 0.05)
				(type default)
			)
			(fill no)
			(layer "B.CrtYd")
		)
		(fp_rect
			(start -0.5 0.25)
			(end 0.5 -0.25)
			(stroke
				(width 0.15)
				(type solid)
			)
			(fill no)
			(layer "B.Fab")
		)
		(fp_text user "License: Apache-2.0"
			(at -0.95 -5.169 180)
			(layer "B.Fab")
			(effects
				(font
					(size 0.7 0.7)
					(thickness 0.15)
				)
				(justify left bottom mirror)
			)
		)
		(fp_text user "Author: Antmicro"
			(at -0.95 -4.169 180)
			(layer "B.Fab")
			(effects
				(font
					(size 0.7 0.7)
					(thickness 0.15)
				)
				(justify left bottom mirror)
			)
		)
		(fp_text user "${REFERENCE}"
			(at -0.95 -3.168 180)
			(layer "B.Fab")
			(effects
				(font
					(size 0.7 0.7)
					(thickness 0.15)
				)
				(justify left bottom mirror)
			)
		)
		(pad "1" smd roundrect
			(at -0.48 0)
			(size 0.59 0.64)
			(layers "B.Cu" "B.Mask" "B.Paste")
			(roundrect_rratio 0.25)
			(net 401 "/Ethernet/ETH.~{RESET}")
			(pintype "passive")
		)
		(pad "2" smd roundrect
			(at 0.48 0)
			(size 0.59 0.64)
			(layers "B.Cu" "B.Mask" "B.Paste")
			(roundrect_rratio 0.25)
			(net 797 "+1V8")
			(pintype "passive")
		)
	)
	(footprint "antmicro-footprints:R_0402_1005Metric"
		(layer "B.Cu")
		(at 126.325 141.262149 180)
		(descr "Resistor SMD 0402")
		(tags "resistor SMD 0402")
		(property "Reference" "R108"
			(at 2.200501 -0.486851 0)
			(layer "B.SilkS")
			(effects
				(font
					(size 0.7 0.7)
					(thickness 0.15)
				)
				(justify left bottom mirror)
			)
		)
		(property "Value" "R_10k_0402"
			(at -1.011843 -1.772047 0)
			(layer "B.Fab")
			(effects
				(font
					(size 0.7 0.7)
					(thickness 0.15)
				)
				(justify left bottom mirror)
			)
		)
		(property "Datasheet" "https://www.bourns.com/docs/product-datasheets/cr.pdf"
			(at 0 0 180)
			(layer "F.Fab")
			(hide yes)
			(effects
				(font
					(size 1.27 1.27)
					(thickness 0.15)
				)
			)
		)
		(property "Manufacturer" "Bourns"
			(at 0 0 180)
			(unlocked yes)
			(layer "B.Fab")
			(hide yes)
			(effects
				(font
					(size 1 1)
					(thickness 0.15)
				)
				(justify mirror)
			)
		)
		(property "MPN" "CR0402-FX-1002GLF"
			(at 0 0 180)
			(unlocked yes)
			(layer "B.Fab")
			(hide yes)
			(effects
				(font
					(size 1 1)
					(thickness 0.15)
				)
				(justify mirror)
			)
		)
		(property "Val" "10k"
			(at 0 0 180)
			(unlocked yes)
			(layer "B.Fab")
			(hide yes)
			(effects
				(font
					(size 1 1)
					(thickness 0.15)
				)
				(justify mirror)
			)
		)
		(property "License" "Apache-2.0"
			(at 0 0 180)
			(unlocked yes)
			(layer "B.Fab")
			(hide yes)
			(effects
				(font
					(size 1 1)
					(thickness 0.15)
				)
				(justify mirror)
			)
		)
		(property "Author" "Antmicro"
			(at 0 0 180)
			(unlocked yes)
			(layer "B.Fab")
			(hide yes)
			(effects
				(font
					(size 1 1)
					(thickness 0.15)
				)
				(justify mirror)
			)
		)
		(property "Tolerance" "1%"
			(at 0 0 180)
			(unlocked yes)
			(layer "B.Fab")
			(hide yes)
			(effects
				(font
					(size 1 1)
					(thickness 0.15)
				)
				(justify mirror)
			)
		)
		(sheetname "/Ethernet/")
		(sheetfile "ethernet.kicad_sch")
		(attr smd)
		(fp_rect
			(start -0.925 0.47)
			(end 0.925 -0.47)
			(stroke
				(width 0.05)
				(type default)
			)
			(fill no)
			(layer "B.CrtYd")
		)
		(fp_rect
			(start -0.5 0.25)
			(end 0.5 -0.25)
			(stroke
				(width 0.15)
				(type solid)
			)
			(fill no)
			(layer "B.Fab")
		)
		(fp_text user "License: Apache-2.0"
			(at -0.95 -5.169 0)
			(layer "B.Fab")
			(effects
				(font
					(size 0.7 0.7)
					(thickness 0.15)
				)
				(justify left bottom mirror)
			)
		)
		(fp_text user "Author: Antmicro"
			(at -0.95 -4.169 0)
			(layer "B.Fab")
			(effects
				(font
					(size 0.7 0.7)
					(thickness 0.15)
				)
				(justify left bottom mirror)
			)
		)
		(fp_text user "${REFERENCE}"
			(at -0.95 -3.168 0)
			(layer "B.Fab")
			(effects
				(font
					(size 0.7 0.7)
					(thickness 0.15)
				)
				(justify left bottom mirror)
			)
		)
		(pad "1" smd roundrect
			(at -0.48 0 180)
			(size 0.59 0.64)
			(layers "B.Cu" "B.Mask" "B.Paste")
			(roundrect_rratio 0.25)
			(net 330 "/Ethernet/LED_SPD")
			(pintype "passive")
		)
		(pad "2" smd roundrect
			(at 0.48 0 180)
			(size 0.59 0.64)
			(layers "B.Cu" "B.Mask" "B.Paste")
			(roundrect_rratio 0.25)
			(net 797 "+1V8")
			(pintype "passive")
		)
	)
	(footprint "antmicro-footprints:R_0402_1005Metric"
		(layer "B.Cu")
		(at 126.325 142.762149 180)
		(descr "Resistor SMD 0402")
		(tags "resistor SMD 0402")
		(property "Reference" "R109"
			(at 2.2 -0.487851 0)
			(layer "B.SilkS")
			(effects
				(font
					(size 0.7 0.7)
					(thickness 0.15)
				)
				(justify left bottom mirror)
			)
		)
		(property "Value" "R_10k_0402"
			(at -1.011843 -1.772047 0)
			(layer "B.Fab")
			(effects
				(font
					(size 0.7 0.7)
					(thickness 0.15)
				)
				(justify left bottom mirror)
			)
		)
		(property "Datasheet" "https://www.bourns.com/docs/product-datasheets/cr.pdf"
			(at 0 0 180)
			(layer "F.Fab")
			(hide yes)
			(effects
				(font
					(size 1.27 1.27)
					(thickness 0.15)
				)
			)
		)
		(property "Manufacturer" "Bourns"
			(at 0 0 180)
			(unlocked yes)
			(layer "B.Fab")
			(hide yes)
			(effects
				(font
					(size 1 1)
					(thickness 0.15)
				)
				(justify mirror)
			)
		)
		(property "MPN" "CR0402-FX-1002GLF"
			(at 0 0 180)
			(unlocked yes)
			(layer "B.Fab")
			(hide yes)
			(effects
				(font
					(size 1 1)
					(thickness 0.15)
				)
				(justify mirror)
			)
		)
		(property "Val" "10k"
			(at 0 0 180)
			(unlocked yes)
			(layer "B.Fab")
			(hide yes)
			(effects
				(font
					(size 1 1)
					(thickness 0.15)
				)
				(justify mirror)
			)
		)
		(property "License" "Apache-2.0"
			(at 0 0 180)
			(unlocked yes)
			(layer "B.Fab")
			(hide yes)
			(effects
				(font
					(size 1 1)
					(thickness 0.15)
				)
				(justify mirror)
			)
		)
		(property "Author" "Antmicro"
			(at 0 0 180)
			(unlocked yes)
			(layer "B.Fab")
			(hide yes)
			(effects
				(font
					(size 1 1)
					(thickness 0.15)
				)
				(justify mirror)
			)
		)
		(property "Tolerance" "1%"
			(at 0 0 180)
			(unlocked yes)
			(layer "B.Fab")
			(hide yes)
			(effects
				(font
					(size 1 1)
					(thickness 0.15)
				)
				(justify mirror)
			)
		)
		(sheetname "/Ethernet/")
		(sheetfile "ethernet.kicad_sch")
		(attr smd)
		(fp_rect
			(start -0.925 0.47)
			(end 0.925 -0.47)
			(stroke
				(width 0.05)
				(type default)
			)
			(fill no)
			(layer "B.CrtYd")
		)
		(fp_rect
			(start -0.5 0.25)
			(end 0.5 -0.25)
			(stroke
				(width 0.15)
				(type solid)
			)
			(fill no)
			(layer "B.Fab")
		)
		(fp_text user "Author: Antmicro"
			(at -0.95 -4.169 0)
			(layer "B.Fab")
			(effects
				(font
					(size 0.7 0.7)
					(thickness 0.15)
				)
				(justify left bottom mirror)
			)
		)
		(fp_text user "${REFERENCE}"
			(at -0.95 -3.168 0)
			(layer "B.Fab")
			(effects
				(font
					(size 0.7 0.7)
					(thickness 0.15)
				)
				(justify left bottom mirror)
			)
		)
		(fp_text user "License: Apache-2.0"
			(at -0.95 -5.169 0)
			(layer "B.Fab")
			(effects
				(font
					(size 0.7 0.7)
					(thickness 0.15)
				)
				(justify left bottom mirror)
			)
		)
		(pad "1" smd roundrect
			(at -0.48 0 180)
			(size 0.59 0.64)
			(layers "B.Cu" "B.Mask" "B.Paste")
			(roundrect_rratio 0.25)
			(net 331 "/Ethernet/LED_LINK")
			(pintype "passive")
		)
		(pad "2" smd roundrect
			(at 0.48 0 180)
			(size 0.59 0.64)
			(layers "B.Cu" "B.Mask" "B.Paste")
			(roundrect_rratio 0.25)
			(net 797 "+1V8")
			(pintype "passive")
		)
	)
	(footprint "antmicro-footprints:C_0402_1005Metric"
		(layer "B.Cu")
		(at 139.224499 145.6)
		(descr "Capacitor SMD 0402")
		(tags "capacitor SMD 0402")
		(property "Reference" "C139"
			(at 1.005501 0.43 0)
			(layer "B.SilkS")
			(effects
				(font
					(size 0.7 0.7)
					(thickness 0.15)
				)
				(justify right bottom mirror)
			)
		)
		(property "Value" "C_4u7_0402"
			(at -1.022927 -2.155213 0)
			(layer "B.Fab")
			(effects
				(font
					(size 0.7 0.7)
					(thickness 0.15)
				)
				(justify right bottom mirror)
			)
		)
		(property "Datasheet" "https://www.murata.com/products/productdetail?partno=GRM155R61A475MEAA%23"
			(at 0 0 0)
			(layer "F.Fab")
			(hide yes)
			(effects
				(font
					(size 1.27 1.27)
					(thickness 0.15)
				)
			)
		)
		(property "Manufacturer" "Murata"
			(at 0 0 0)
			(unlocked yes)
			(layer "B.Fab")
			(hide yes)
			(effects
				(font
					(size 1 1)
					(thickness 0.15)
				)
				(justify mirror)
			)
		)
		(property "MPN" "GRM155R61A475MEAAD"
			(at 0 0 0)
			(unlocked yes)
			(layer "B.Fab")
			(hide yes)
			(effects
				(font
					(size 1 1)
					(thickness 0.15)
				)
				(justify mirror)
			)
		)
		(property "Val" "4u7"
			(at 0 0 0)
			(unlocked yes)
			(layer "B.Fab")
			(hide yes)
			(effects
				(font
					(size 1 1)
					(thickness 0.15)
				)
				(justify mirror)
			)
		)
		(property "License" "Apache-2.0"
			(at 0 0 0)
			(unlocked yes)
			(layer "B.Fab")
			(hide yes)
			(effects
				(font
					(size 1 1)
					(thickness 0.15)
				)
				(justify mirror)
			)
		)
		(property "Author" "Antmicro"
			(at 0 0 0)
			(unlocked yes)
			(layer "B.Fab")
			(hide yes)
			(effects
				(font
					(size 1 1)
					(thickness 0.15)
				)
				(justify mirror)
			)
		)
		(property "Voltage" ""
			(at 0 0 0)
			(unlocked yes)
			(layer "B.Fab")
			(hide yes)
			(effects
				(font
					(size 1 1)
					(thickness 0.15)
				)
				(justify mirror)
			)
		)
		(property "Dielectric" ""
			(at 0 0 0)
			(unlocked yes)
			(layer "B.Fab")
			(hide yes)
			(effects
				(font
					(size 1 1)
					(thickness 0.15)
				)
				(justify mirror)
			)
		)
		(sheetname "/Ethernet/")
		(sheetfile "ethernet.kicad_sch")
		(attr smd)
		(fp_rect
			(start -0.925 0.47)
			(end 0.925 -0.47)
			(stroke
				(width 0.05)
				(type default)
			)
			(fill no)
			(layer "B.CrtYd")
		)
		(fp_line
			(start -0.494 -0.248)
			(end -0.494 0.25)
			(stroke
				(width 0.15)
				(type solid)
			)
			(layer "B.Fab")
		)
		(fp_line
			(start -0.494 0.25)
			(end 0.504 0.25)
			(stroke
				(width 0.15)
				(type solid)
			)
			(layer "B.Fab")
		)
		(fp_line
			(start 0.504 -0.248)
			(end -0.494 -0.248)
			(stroke
				(width 0.15)
				(type solid)
			)
			(layer "B.Fab")
		)
		(fp_line
			(start 0.504 0.25)
			(end 0.504 -0.248)
			(stroke
				(width 0.15)
				(type solid)
			)
			(layer "B.Fab")
		)
		(fp_text user "${REFERENCE}"
			(at -0.939 -4.599 180)
			(layer "B.Fab")
			(effects
				(font
					(size 0.7 0.7)
					(thickness 0.15)
				)
				(justify left bottom mirror)
			)
		)
		(fp_text user "License: Apache-2.0"
			(at -0.939 -5.799 180)
			(layer "B.Fab")
			(effects
				(font
					(size 0.7 0.7)
					(thickness 0.15)
				)
				(justify left bottom mirror)
			)
		)
		(fp_text user "Author: Antmicro"
			(at -0.939 -3.399 180)
			(layer "B.Fab")
			(effects
				(font
					(size 0.7 0.7)
					(thickness 0.15)
				)
				(justify left bottom mirror)
			)
		)
		(pad "1" smd roundrect
			(at -0.48 0)
			(size 0.59 0.64)
			(layers "B.Cu" "B.Mask" "B.Paste")
			(roundrect_rratio 0.25)
			(net 150 "+1V2")
			(pintype "passive")
		)
		(pad "2" smd roundrect
			(at 0.48 0)
			(size 0.59 0.64)
			(layers "B.Cu" "B.Mask" "B.Paste")
			(roundrect_rratio 0.25)
			(net 1 "GND")
			(pintype "passive")
		)
	)
	(footprint "antmicro-footprints:C_0402_1005Metric"
		(layer "B.Cu")
		(at 139.224499 146.6)
		(descr "Capacitor SMD 0402")
		(tags "capacitor SMD 0402")
		(property "Reference" "C142"
			(at 1.005501 0.43 0)
			(layer "B.SilkS")
			(effects
				(font
					(size 0.7 0.7)
					(thickness 0.15)
				)
				(justify right bottom mirror)
			)
		)
		(property "Value" "C_470n_0402"
			(at -1.022927 -2.155213 0)
			(layer "B.Fab")
			(effects
				(font
					(size 0.7 0.7)
					(thickness 0.15)
				)
				(justify right bottom mirror)
			)
		)
		(property "Datasheet" "https://product.tdk.com/en/search/capacitor/ceramic/mlcc/info?part_no=C1005X5R1E474M050BB"
			(at 0 0 0)
			(layer "F.Fab")
			(hide yes)
			(effects
				(font
					(size 1.27 1.27)
					(thickness 0.15)
				)
			)
		)
		(property "Manufacturer" "TDK"
			(at 0 0 0)
			(unlocked yes)
			(layer "B.Fab")
			(hide yes)
			(effects
				(font
					(size 1 1)
					(thickness 0.15)
				)
				(justify mirror)
			)
		)
		(property "MPN" "C1005X5R1E474M050BB"
			(at 0 0 0)
			(unlocked yes)
			(layer "B.Fab")
			(hide yes)
			(effects
				(font
					(size 1 1)
					(thickness 0.15)
				)
				(justify mirror)
			)
		)
		(property "Val" "470n"
			(at 0 0 0)
			(unlocked yes)
			(layer "B.Fab")
			(hide yes)
			(effects
				(font
					(size 1 1)
					(thickness 0.15)
				)
				(justify mirror)
			)
		)
		(property "License" "Apache-2.0"
			(at 0 0 0)
			(unlocked yes)
			(layer "B.Fab")
			(hide yes)
			(effects
				(font
					(size 1 1)
					(thickness 0.15)
				)
				(justify mirror)
			)
		)
		(property "Author" "Antmicro"
			(at 0 0 0)
			(unlocked yes)
			(layer "B.Fab")
			(hide yes)
			(effects
				(font
					(size 1 1)
					(thickness 0.15)
				)
				(justify mirror)
			)
		)
		(property "Voltage" ""
			(at 0 0 0)
			(unlocked yes)
			(layer "B.Fab")
			(hide yes)
			(effects
				(font
					(size 1 1)
					(thickness 0.15)
				)
				(justify mirror)
			)
		)
		(property "Dielectric" ""
			(at 0 0 0)
			(unlocked yes)
			(layer "B.Fab")
			(hide yes)
			(effects
				(font
					(size 1 1)
					(thickness 0.15)
				)
				(justify mirror)
			)
		)
		(sheetname "/Ethernet/")
		(sheetfile "ethernet.kicad_sch")
		(attr smd)
		(fp_rect
			(start -0.925 0.47)
			(end 0.925 -0.47)
			(stroke
				(width 0.05)
				(type default)
			)
			(fill no)
			(layer "B.CrtYd")
		)
		(fp_line
			(start -0.494 -0.248)
			(end -0.494 0.25)
			(stroke
				(width 0.15)
				(type solid)
			)
			(layer "B.Fab")
		)
		(fp_line
			(start -0.494 0.25)
			(end 0.504 0.25)
			(stroke
				(width 0.15)
				(type solid)
			)
			(layer "B.Fab")
		)
		(fp_line
			(start 0.504 -0.248)
			(end -0.494 -0.248)
			(stroke
				(width 0.15)
				(type solid)
			)
			(layer "B.Fab")
		)
		(fp_line
			(start 0.504 0.25)
			(end 0.504 -0.248)
			(stroke
				(width 0.15)
				(type solid)
			)
			(layer "B.Fab")
		)
		(fp_text user "License: Apache-2.0"
			(at -0.939 -5.799 180)
			(layer "B.Fab")
			(effects
				(font
					(size 0.7 0.7)
					(thickness 0.15)
				)
				(justify left bottom mirror)
			)
		)
		(fp_text user "Author: Antmicro"
			(at -0.939 -3.399 180)
			(layer "B.Fab")
			(effects
				(font
					(size 0.7 0.7)
					(thickness 0.15)
				)
				(justify left bottom mirror)
			)
		)
		(fp_text user "${REFERENCE}"
			(at -0.939 -4.599 180)
			(layer "B.Fab")
			(effects
				(font
					(size 0.7 0.7)
					(thickness 0.15)
				)
				(justify left bottom mirror)
			)
		)
		(pad "1" smd roundrect
			(at -0.48 0)
			(size 0.59 0.64)
			(layers "B.Cu" "B.Mask" "B.Paste")
			(roundrect_rratio 0.25)
			(net 150 "+1V2")
			(pintype "passive")
		)
		(pad "2" smd roundrect
			(at 0.48 0)
			(size 0.59 0.64)
			(layers "B.Cu" "B.Mask" "B.Paste")
			(roundrect_rratio 0.25)
			(net 1 "GND")
			(pintype "passive")
		)
	)
	(footprint "antmicro-footprints:C_0402_1005Metric"
		(layer "B.Cu")
		(at 136.724499 138.749 90)
		(descr "Capacitor SMD 0402")
		(tags "capacitor SMD 0402")
		(property "Reference" "C146"
			(at 1.176157 0.344672 90)
			(layer "B.SilkS")
			(effects
				(font
					(size 0.7 0.7)
					(thickness 0.15)
				)
				(justify right bottom mirror)
			)
		)
		(property "Value" "C_4u7_0402"
			(at -1.022927 -2.155213 90)
			(layer "B.Fab")
			(effects
				(font
					(size 0.7 0.7)
					(thickness 0.15)
				)
				(justify right bottom mirror)
			)
		)
		(property "Datasheet" "https://www.murata.com/products/productdetail?partno=GRM155R61A475MEAA%23"
			(at 0 0 90)
			(layer "F.Fab")
			(hide yes)
			(effects
				(font
					(size 1.27 1.27)
					(thickness 0.15)
				)
			)
		)
		(property "Manufacturer" "Murata"
			(at 0 0 90)
			(unlocked yes)
			(layer "B.Fab")
			(hide yes)
			(effects
				(font
					(size 1 1)
					(thickness 0.15)
				)
				(justify mirror)
			)
		)
		(property "MPN" "GRM155R61A475MEAAD"
			(at 0 0 90)
			(unlocked yes)
			(layer "B.Fab")
			(hide yes)
			(effects
				(font
					(size 1 1)
					(thickness 0.15)
				)
				(justify mirror)
			)
		)
		(property "Val" "4u7"
			(at 0 0 90)
			(unlocked yes)
			(layer "B.Fab")
			(hide yes)
			(effects
				(font
					(size 1 1)
					(thickness 0.15)
				)
				(justify mirror)
			)
		)
		(property "License" "Apache-2.0"
			(at 0 0 90)
			(unlocked yes)
			(layer "B.Fab")
			(hide yes)
			(effects
				(font
					(size 1 1)
					(thickness 0.15)
				)
				(justify mirror)
			)
		)
		(property "Author" "Antmicro"
			(at 0 0 90)
			(unlocked yes)
			(layer "B.Fab")
			(hide yes)
			(effects
				(font
					(size 1 1)
					(thickness 0.15)
				)
				(justify mirror)
			)
		)
		(property "Voltage" ""
			(at 0 0 90)
			(unlocked yes)
			(layer "B.Fab")
			(hide yes)
			(effects
				(font
					(size 1 1)
					(thickness 0.15)
				)
				(justify mirror)
			)
		)
		(property "Dielectric" ""
			(at 0 0 90)
			(unlocked yes)
			(layer "B.Fab")
			(hide yes)
			(effects
				(font
					(size 1 1)
					(thickness 0.15)
				)
				(justify mirror)
			)
		)
		(sheetname "/Ethernet/")
		(sheetfile "ethernet.kicad_sch")
		(attr smd)
		(fp_rect
			(start -0.925 0.47)
			(end 0.925 -0.47)
			(stroke
				(width 0.05)
				(type default)
			)
			(fill no)
			(layer "B.CrtYd")
		)
		(fp_line
			(start 0.504 -0.248)
			(end -0.494 -0.248)
			(stroke
				(width 0.15)
				(type solid)
			)
			(layer "B.Fab")
		)
		(fp_line
			(start -0.494 -0.248)
			(end -0.494 0.25)
			(stroke
				(width 0.15)
				(type solid)
			)
			(layer "B.Fab")
		)
		(fp_line
			(start 0.504 0.25)
			(end 0.504 -0.248)
			(stroke
				(width 0.15)
				(type solid)
			)
			(layer "B.Fab")
		)
		(fp_line
			(start -0.494 0.25)
			(end 0.504 0.25)
			(stroke
				(width 0.15)
				(type solid)
			)
			(layer "B.Fab")
		)
		(fp_text user "${REFERENCE}"
			(at -0.939 -4.599 270)
			(layer "B.Fab")
			(effects
				(font
					(size 0.7 0.7)
					(thickness 0.15)
				)
				(justify left bottom mirror)
			)
		)
		(fp_text user "License: Apache-2.0"
			(at -0.939 -5.799 270)
			(layer "B.Fab")
			(effects
				(font
					(size 0.7 0.7)
					(thickness 0.15)
				)
				(justify left bottom mirror)
			)
		)
		(fp_text user "Author: Antmicro"
			(at -0.939 -3.399 270)
			(layer "B.Fab")
			(effects
				(font
					(size 0.7 0.7)
					(thickness 0.15)
				)
				(justify left bottom mirror)
			)
		)
		(pad "1" smd roundrect
			(at -0.48 0 90)
			(size 0.59 0.64)
			(layers "B.Cu" "B.Mask" "B.Paste")
			(roundrect_rratio 0.25)
			(net 95 "/Ethernet/AVDDL")
			(pintype "passive")
		)
		(pad "2" smd roundrect
			(at 0.48 0 90)
			(size 0.59 0.64)
			(layers "B.Cu" "B.Mask" "B.Paste")
			(roundrect_rratio 0.25)
			(net 1 "GND")
			(pintype "passive")
		)
	)
	(footprint "antmicro-footprints:C_0402_1005Metric"
		(layer "B.Cu")
		(at 134.433171 146.453992 90)
		(descr "Capacitor SMD 0402")
		(tags "capacitor SMD 0402")
		(property "Reference" "C145"
			(at -3.914008 0.202829 90)
			(layer "B.SilkS")
			(effects
				(font
					(size 0.7 0.7)
					(thickness 0.15)
				)
				(justify right bottom mirror)
			)
		)
		(property "Value" "C_470n_0402"
			(at -1.022927 -2.155213 90)
			(layer "B.Fab")
			(effects
				(font
					(size 0.7 0.7)
					(thickness 0.15)
				)
				(justify right bottom mirror)
			)
		)
		(property "Datasheet" "https://product.tdk.com/en/search/capacitor/ceramic/mlcc/info?part_no=C1005X5R1E474M050BB"
			(at 0 0 90)
			(layer "F.Fab")
			(hide yes)
			(effects
				(font
					(size 1.27 1.27)
					(thickness 0.15)
				)
			)
		)
		(property "Manufacturer" "TDK"
			(at 0 0 90)
			(unlocked yes)
			(layer "B.Fab")
			(hide yes)
			(effects
				(font
					(size 1 1)
					(thickness 0.15)
				)
				(justify mirror)
			)
		)
		(property "MPN" "C1005X5R1E474M050BB"
			(at 0 0 90)
			(unlocked yes)
			(layer "B.Fab")
			(hide yes)
			(effects
				(font
					(size 1 1)
					(thickness 0.15)
				)
				(justify mirror)
			)
		)
		(property "Val" "470n"
			(at 0 0 90)
			(unlocked yes)
			(layer "B.Fab")
			(hide yes)
			(effects
				(font
					(size 1 1)
					(thickness 0.15)
				)
				(justify mirror)
			)
		)
		(property "License" "Apache-2.0"
			(at 0 0 90)
			(unlocked yes)
			(layer "B.Fab")
			(hide yes)
			(effects
				(font
					(size 1 1)
					(thickness 0.15)
				)
				(justify mirror)
			)
		)
		(property "Author" "Antmicro"
			(at 0 0 90)
			(unlocked yes)
			(layer "B.Fab")
			(hide yes)
			(effects
				(font
					(size 1 1)
					(thickness 0.15)
				)
				(justify mirror)
			)
		)
		(property "Voltage" ""
			(at 0 0 90)
			(unlocked yes)
			(layer "B.Fab")
			(hide yes)
			(effects
				(font
					(size 1 1)
					(thickness 0.15)
				)
				(justify mirror)
			)
		)
		(property "Dielectric" ""
			(at 0 0 90)
			(unlocked yes)
			(layer "B.Fab")
			(hide yes)
			(effects
				(font
					(size 1 1)
					(thickness 0.15)
				)
				(justify mirror)
			)
		)
		(sheetname "/Ethernet/")
		(sheetfile "ethernet.kicad_sch")
		(attr smd)
		(fp_rect
			(start -0.925 0.47)
			(end 0.925 -0.47)
			(stroke
				(width 0.05)
				(type default)
			)
			(fill no)
			(layer "B.CrtYd")
		)
		(fp_line
			(start 0.504 -0.248)
			(end -0.494 -0.248)
			(stroke
				(width 0.15)
				(type solid)
			)
			(layer "B.Fab")
		)
		(fp_line
			(start -0.494 -0.248)
			(end -0.494 0.25)
			(stroke
				(width 0.15)
				(type solid)
			)
			(layer "B.Fab")
		)
		(fp_line
			(start 0.504 0.25)
			(end 0.504 -0.248)
			(stroke
				(width 0.15)
				(type solid)
			)
			(layer "B.Fab")
		)
		(fp_line
			(start -0.494 0.25)
			(end 0.504 0.25)
			(stroke
				(width 0.15)
				(type solid)
			)
			(layer "B.Fab")
		)
		(fp_text user "${REFERENCE}"
			(at -0.939 -4.599 270)
			(layer "B.Fab")
			(effects
				(font
					(size 0.7 0.7)
					(thickness 0.15)
				)
				(justify left bottom mirror)
			)
		)
		(fp_text user "Author: Antmicro"
			(at -0.939 -3.399 270)
			(layer "B.Fab")
			(effects
				(font
					(size 0.7 0.7)
					(thickness 0.15)
				)
				(justify left bottom mirror)
			)
		)
		(fp_text user "License: Apache-2.0"
			(at -0.939 -5.799 270)
			(layer "B.Fab")
			(effects
				(font
					(size 0.7 0.7)
					(thickness 0.15)
				)
				(justify left bottom mirror)
			)
		)
		(pad "1" smd roundrect
			(at -0.48 0 90)
			(size 0.59 0.64)
			(layers "B.Cu" "B.Mask" "B.Paste")
			(roundrect_rratio 0.25)
			(net 150 "+1V2")
			(pintype "passive")
		)
		(pad "2" smd roundrect
			(at 0.48 0 90)
			(size 0.59 0.64)
			(layers "B.Cu" "B.Mask" "B.Paste")
			(roundrect_rratio 0.25)
			(net 1 "GND")
			(pintype "passive")
		)
	)
	(footprint "antmicro-footprints:C_0402_1005Metric"
		(layer "B.Cu")
		(at 136.433171 146.453992 90)
		(descr "Capacitor SMD 0402")
		(tags "capacitor SMD 0402")
		(property "Reference" "C134"
			(at -3.914008 0.202829 90)
			(layer "B.SilkS")
			(effects
				(font
					(size 0.7 0.7)
					(thickness 0.15)
				)
				(justify right bottom mirror)
			)
		)
		(property "Value" "C_4u7_0402"
			(at -1.022927 -2.155213 90)
			(layer "B.Fab")
			(effects
				(font
					(size 0.7 0.7)
					(thickness 0.15)
				)
				(justify right bottom mirror)
			)
		)
		(property "Datasheet" "https://www.murata.com/products/productdetail?partno=GRM155R61A475MEAA%23"
			(at 0 0 90)
			(layer "F.Fab")
			(hide yes)
			(effects
				(font
					(size 1.27 1.27)
					(thickness 0.15)
				)
			)
		)
		(property "Manufacturer" "Murata"
			(at 0 0 90)
			(unlocked yes)
			(layer "B.Fab")
			(hide yes)
			(effects
				(font
					(size 1 1)
					(thickness 0.15)
				)
				(justify mirror)
			)
		)
		(property "MPN" "GRM155R61A475MEAAD"
			(at 0 0 90)
			(unlocked yes)
			(layer "B.Fab")
			(hide yes)
			(effects
				(font
					(size 1 1)
					(thickness 0.15)
				)
				(justify mirror)
			)
		)
		(property "Val" "4u7"
			(at 0 0 90)
			(unlocked yes)
			(layer "B.Fab")
			(hide yes)
			(effects
				(font
					(size 1 1)
					(thickness 0.15)
				)
				(justify mirror)
			)
		)
		(property "License" "Apache-2.0"
			(at 0 0 90)
			(unlocked yes)
			(layer "B.Fab")
			(hide yes)
			(effects
				(font
					(size 1 1)
					(thickness 0.15)
				)
				(justify mirror)
			)
		)
		(property "Author" "Antmicro"
			(at 0 0 90)
			(unlocked yes)
			(layer "B.Fab")
			(hide yes)
			(effects
				(font
					(size 1 1)
					(thickness 0.15)
				)
				(justify mirror)
			)
		)
		(property "Voltage" ""
			(at 0 0 90)
			(unlocked yes)
			(layer "B.Fab")
			(hide yes)
			(effects
				(font
					(size 1 1)
					(thickness 0.15)
				)
				(justify mirror)
			)
		)
		(property "Dielectric" ""
			(at 0 0 90)
			(unlocked yes)
			(layer "B.Fab")
			(hide yes)
			(effects
				(font
					(size 1 1)
					(thickness 0.15)
				)
				(justify mirror)
			)
		)
		(sheetname "/Ethernet/")
		(sheetfile "ethernet.kicad_sch")
		(attr smd)
		(fp_rect
			(start -0.925 0.47)
			(end 0.925 -0.47)
			(stroke
				(width 0.05)
				(type default)
			)
			(fill no)
			(layer "B.CrtYd")
		)
		(fp_line
			(start 0.504 -0.248)
			(end -0.494 -0.248)
			(stroke
				(width 0.15)
				(type solid)
			)
			(layer "B.Fab")
		)
		(fp_line
			(start -0.494 -0.248)
			(end -0.494 0.25)
			(stroke
				(width 0.15)
				(type solid)
			)
			(layer "B.Fab")
		)
		(fp_line
			(start 0.504 0.25)
			(end 0.504 -0.248)
			(stroke
				(width 0.15)
				(type solid)
			)
			(layer "B.Fab")
		)
		(fp_line
			(start -0.494 0.25)
			(end 0.504 0.25)
			(stroke
				(width 0.15)
				(type solid)
			)
			(layer "B.Fab")
		)
		(fp_text user "Author: Antmicro"
			(at -0.939 -3.399 270)
			(layer "B.Fab")
			(effects
				(font
					(size 0.7 0.7)
					(thickness 0.15)
				)
				(justify left bottom mirror)
			)
		)
		(fp_text user "${REFERENCE}"
			(at -0.939 -4.599 270)
			(layer "B.Fab")
			(effects
				(font
					(size 0.7 0.7)
					(thickness 0.15)
				)
				(justify left bottom mirror)
			)
		)
		(fp_text user "License: Apache-2.0"
			(at -0.939 -5.799 270)
			(layer "B.Fab")
			(effects
				(font
					(size 0.7 0.7)
					(thickness 0.15)
				)
				(justify left bottom mirror)
			)
		)
		(pad "1" smd roundrect
			(at -0.48 0 90)
			(size 0.59 0.64)
			(layers "B.Cu" "B.Mask" "B.Paste")
			(roundrect_rratio 0.25)
			(net 797 "+1V8")
			(pintype "passive")
		)
		(pad "2" smd roundrect
			(at 0.48 0 90)
			(size 0.59 0.64)
			(layers "B.Cu" "B.Mask" "B.Paste")
			(roundrect_rratio 0.25)
			(net 1 "GND")
			(pintype "passive")
		)
	)
	(footprint "antmicro-footprints:C_0402_1005Metric"
		(layer "B.Cu")
		(at 134.161328 138.732157 90)
		(descr "Capacitor SMD 0402")
		(tags "capacitor SMD 0402")
		(property "Reference" "C143"
			(at 1.176157 0.344672 90)
			(layer "B.SilkS")
			(effects
				(font
					(size 0.7 0.7)
					(thickness 0.15)
				)
				(justify right bottom mirror)
			)
		)
		(property "Value" "C_470n_0402"
			(at -1.022927 -2.155213 90)
			(layer "B.Fab")
			(effects
				(font
					(size 0.7 0.7)
					(thickness 0.15)
				)
				(justify right bottom mirror)
			)
		)
		(property "Datasheet" "https://product.tdk.com/en/search/capacitor/ceramic/mlcc/info?part_no=C1005X5R1E474M050BB"
			(at 0 0 90)
			(layer "F.Fab")
			(hide yes)
			(effects
				(font
					(size 1.27 1.27)
					(thickness 0.15)
				)
			)
		)
		(property "Manufacturer" "TDK"
			(at 0 0 90)
			(unlocked yes)
			(layer "B.Fab")
			(hide yes)
			(effects
				(font
					(size 1 1)
					(thickness 0.15)
				)
				(justify mirror)
			)
		)
		(property "MPN" "C1005X5R1E474M050BB"
			(at 0 0 90)
			(unlocked yes)
			(layer "B.Fab")
			(hide yes)
			(effects
				(font
					(size 1 1)
					(thickness 0.15)
				)
				(justify mirror)
			)
		)
		(property "Val" "470n"
			(at 0 0 90)
			(unlocked yes)
			(layer "B.Fab")
			(hide yes)
			(effects
				(font
					(size 1 1)
					(thickness 0.15)
				)
				(justify mirror)
			)
		)
		(property "License" "Apache-2.0"
			(at 0 0 90)
			(unlocked yes)
			(layer "B.Fab")
			(hide yes)
			(effects
				(font
					(size 1 1)
					(thickness 0.15)
				)
				(justify mirror)
			)
		)
		(property "Author" "Antmicro"
			(at 0 0 90)
			(unlocked yes)
			(layer "B.Fab")
			(hide yes)
			(effects
				(font
					(size 1 1)
					(thickness 0.15)
				)
				(justify mirror)
			)
		)
		(property "Voltage" ""
			(at 0 0 90)
			(unlocked yes)
			(layer "B.Fab")
			(hide yes)
			(effects
				(font
					(size 1 1)
					(thickness 0.15)
				)
				(justify mirror)
			)
		)
		(property "Dielectric" ""
			(at 0 0 90)
			(unlocked yes)
			(layer "B.Fab")
			(hide yes)
			(effects
				(font
					(size 1 1)
					(thickness 0.15)
				)
				(justify mirror)
			)
		)
		(sheetname "/Ethernet/")
		(sheetfile "ethernet.kicad_sch")
		(attr smd)
		(fp_rect
			(start -0.925 0.47)
			(end 0.925 -0.47)
			(stroke
				(width 0.05)
				(type default)
			)
			(fill no)
			(layer "B.CrtYd")
		)
		(fp_line
			(start 0.504 -0.248)
			(end -0.494 -0.248)
			(stroke
				(width 0.15)
				(type solid)
			)
			(layer "B.Fab")
		)
		(fp_line
			(start -0.494 -0.248)
			(end -0.494 0.25)
			(stroke
				(width 0.15)
				(type solid)
			)
			(layer "B.Fab")
		)
		(fp_line
			(start 0.504 0.25)
			(end 0.504 -0.248)
			(stroke
				(width 0.15)
				(type solid)
			)
			(layer "B.Fab")
		)
		(fp_line
			(start -0.494 0.25)
			(end 0.504 0.25)
			(stroke
				(width 0.15)
				(type solid)
			)
			(layer "B.Fab")
		)
		(fp_text user "License: Apache-2.0"
			(at -0.939 -5.799 270)
			(layer "B.Fab")
			(effects
				(font
					(size 0.7 0.7)
					(thickness 0.15)
				)
				(justify left bottom mirror)
			)
		)
		(fp_text user "${REFERENCE}"
			(at -0.939 -4.599 270)
			(layer "B.Fab")
			(effects
				(font
					(size 0.7 0.7)
					(thickness 0.15)
				)
				(justify left bottom mirror)
			)
		)
		(fp_text user "Author: Antmicro"
			(at -0.939 -3.399 270)
			(layer "B.Fab")
			(effects
				(font
					(size 0.7 0.7)
					(thickness 0.15)
				)
				(justify left bottom mirror)
			)
		)
		(pad "1" smd roundrect
			(at -0.48 0 90)
			(size 0.59 0.64)
			(layers "B.Cu" "B.Mask" "B.Paste")
			(roundrect_rratio 0.25)
			(net 95 "/Ethernet/AVDDL")
			(pintype "passive")
		)
		(pad "2" smd roundrect
			(at 0.48 0 90)
			(size 0.59 0.64)
			(layers "B.Cu" "B.Mask" "B.Paste")
			(roundrect_rratio 0.25)
			(net 1 "GND")
			(pintype "passive")
		)
	)
	(footprint "antmicro-footprints:C_0402_1005Metric"
		(layer "B.Cu")
		(at 132.274499 146.453992 90)
		(descr "Capacitor SMD 0402")
		(tags "capacitor SMD 0402")
		(property "Reference" "C148"
			(at -3.914008 0.202829 90)
			(layer "B.SilkS")
			(effects
				(font
					(size 0.7 0.7)
					(thickness 0.15)
				)
				(justify right bottom mirror)
			)
		)
		(property "Value" "C_470n_0402"
			(at -1.022927 -2.155213 90)
			(layer "B.Fab")
			(effects
				(font
					(size 0.7 0.7)
					(thickness 0.15)
				)
				(justify right bottom mirror)
			)
		)
		(property "Datasheet" "https://product.tdk.com/en/search/capacitor/ceramic/mlcc/info?part_no=C1005X5R1E474M050BB"
			(at 0 0 90)
			(layer "F.Fab")
			(hide yes)
			(effects
				(font
					(size 1.27 1.27)
					(thickness 0.15)
				)
			)
		)
		(property "Manufacturer" "TDK"
			(at 0 0 90)
			(unlocked yes)
			(layer "B.Fab")
			(hide yes)
			(effects
				(font
					(size 1 1)
					(thickness 0.15)
				)
				(justify mirror)
			)
		)
		(property "MPN" "C1005X5R1E474M050BB"
			(at 0 0 90)
			(unlocked yes)
			(layer "B.Fab")
			(hide yes)
			(effects
				(font
					(size 1 1)
					(thickness 0.15)
				)
				(justify mirror)
			)
		)
		(property "Val" "470n"
			(at 0 0 90)
			(unlocked yes)
			(layer "B.Fab")
			(hide yes)
			(effects
				(font
					(size 1 1)
					(thickness 0.15)
				)
				(justify mirror)
			)
		)
		(property "License" "Apache-2.0"
			(at 0 0 90)
			(unlocked yes)
			(layer "B.Fab")
			(hide yes)
			(effects
				(font
					(size 1 1)
					(thickness 0.15)
				)
				(justify mirror)
			)
		)
		(property "Author" "Antmicro"
			(at 0 0 90)
			(unlocked yes)
			(layer "B.Fab")
			(hide yes)
			(effects
				(font
					(size 1 1)
					(thickness 0.15)
				)
				(justify mirror)
			)
		)
		(property "Voltage" ""
			(at 0 0 90)
			(unlocked yes)
			(layer "B.Fab")
			(hide yes)
			(effects
				(font
					(size 1 1)
					(thickness 0.15)
				)
				(justify mirror)
			)
		)
		(property "Dielectric" ""
			(at 0 0 90)
			(unlocked yes)
			(layer "B.Fab")
			(hide yes)
			(effects
				(font
					(size 1 1)
					(thickness 0.15)
				)
				(justify mirror)
			)
		)
		(sheetname "/Ethernet/")
		(sheetfile "ethernet.kicad_sch")
		(attr smd)
		(fp_rect
			(start -0.925 0.47)
			(end 0.925 -0.47)
			(stroke
				(width 0.05)
				(type default)
			)
			(fill no)
			(layer "B.CrtYd")
		)
		(fp_line
			(start 0.504 -0.248)
			(end -0.494 -0.248)
			(stroke
				(width 0.15)
				(type solid)
			)
			(layer "B.Fab")
		)
		(fp_line
			(start -0.494 -0.248)
			(end -0.494 0.25)
			(stroke
				(width 0.15)
				(type solid)
			)
			(layer "B.Fab")
		)
		(fp_line
			(start 0.504 0.25)
			(end 0.504 -0.248)
			(stroke
				(width 0.15)
				(type solid)
			)
			(layer "B.Fab")
		)
		(fp_line
			(start -0.494 0.25)
			(end 0.504 0.25)
			(stroke
				(width 0.15)
				(type solid)
			)
			(layer "B.Fab")
		)
		(fp_text user "Author: Antmicro"
			(at -0.939 -3.399 270)
			(layer "B.Fab")
			(effects
				(font
					(size 0.7 0.7)
					(thickness 0.15)
				)
				(justify left bottom mirror)
			)
		)
		(fp_text user "License: Apache-2.0"
			(at -0.939 -5.799 270)
			(layer "B.Fab")
			(effects
				(font
					(size 0.7 0.7)
					(thickness 0.15)
				)
				(justify left bottom mirror)
			)
		)
		(fp_text user "${REFERENCE}"
			(at -0.939 -4.599 270)
			(layer "B.Fab")
			(effects
				(font
					(size 0.7 0.7)
					(thickness 0.15)
				)
				(justify left bottom mirror)
			)
		)
		(pad "1" smd roundrect
			(at -0.48 0 90)
			(size 0.59 0.64)
			(layers "B.Cu" "B.Mask" "B.Paste")
			(roundrect_rratio 0.25)
			(net 150 "+1V2")
			(pintype "passive")
		)
		(pad "2" smd roundrect
			(at 0.48 0 90)
			(size 0.59 0.64)
			(layers "B.Cu" "B.Mask" "B.Paste")
			(roundrect_rratio 0.25)
			(net 1 "GND")
			(pintype "passive")
		)
	)
	(footprint "antmicro-footprints:C_0402_1005Metric"
		(layer "B.Cu")
		(at 135.186328 138.732157 90)
		(descr "Capacitor SMD 0402")
		(tags "capacitor SMD 0402")
		(property "Reference" "C140"
			(at 1.176157 0.344672 90)
			(layer "B.SilkS")
			(effects
				(font
					(size 0.7 0.7)
					(thickness 0.15)
				)
				(justify right bottom mirror)
			)
		)
		(property "Value" "C_10n_0402"
			(at -1.022927 -2.155213 90)
			(layer "B.Fab")
			(effects
				(font
					(size 0.7 0.7)
					(thickness 0.15)
				)
				(justify right bottom mirror)
			)
		)
		(property "Datasheet" "https://www.murata.com/products/productdetail?partno=GRM155R71H103KA88%23"
			(at 0 0 90)
			(layer "F.Fab")
			(hide yes)
			(effects
				(font
					(size 1.27 1.27)
					(thickness 0.15)
				)
			)
		)
		(property "Manufacturer" "Murata"
			(at 0 0 90)
			(unlocked yes)
			(layer "B.Fab")
			(hide yes)
			(effects
				(font
					(size 1 1)
					(thickness 0.15)
				)
				(justify mirror)
			)
		)
		(property "MPN" "GRM155R71H103KA88D"
			(at 0 0 90)
			(unlocked yes)
			(layer "B.Fab")
			(hide yes)
			(effects
				(font
					(size 1 1)
					(thickness 0.15)
				)
				(justify mirror)
			)
		)
		(property "Val" "10n"
			(at 0 0 90)
			(unlocked yes)
			(layer "B.Fab")
			(hide yes)
			(effects
				(font
					(size 1 1)
					(thickness 0.15)
				)
				(justify mirror)
			)
		)
		(property "License" "Apache-2.0"
			(at 0 0 90)
			(unlocked yes)
			(layer "B.Fab")
			(hide yes)
			(effects
				(font
					(size 1 1)
					(thickness 0.15)
				)
				(justify mirror)
			)
		)
		(property "Author" "Antmicro"
			(at 0 0 90)
			(unlocked yes)
			(layer "B.Fab")
			(hide yes)
			(effects
				(font
					(size 1 1)
					(thickness 0.15)
				)
				(justify mirror)
			)
		)
		(property "Voltage" "50V"
			(at 0 0 90)
			(unlocked yes)
			(layer "B.Fab")
			(hide yes)
			(effects
				(font
					(size 1 1)
					(thickness 0.15)
				)
				(justify mirror)
			)
		)
		(property "Dielectric" "X7R"
			(at 0 0 90)
			(unlocked yes)
			(layer "B.Fab")
			(hide yes)
			(effects
				(font
					(size 1 1)
					(thickness 0.15)
				)
				(justify mirror)
			)
		)
		(sheetname "/Ethernet/")
		(sheetfile "ethernet.kicad_sch")
		(attr smd)
		(fp_rect
			(start -0.925 0.47)
			(end 0.925 -0.47)
			(stroke
				(width 0.05)
				(type default)
			)
			(fill no)
			(layer "B.CrtYd")
		)
		(fp_line
			(start 0.504 -0.248)
			(end -0.494 -0.248)
			(stroke
				(width 0.15)
				(type solid)
			)
			(layer "B.Fab")
		)
		(fp_line
			(start -0.494 -0.248)
			(end -0.494 0.25)
			(stroke
				(width 0.15)
				(type solid)
			)
			(layer "B.Fab")
		)
		(fp_line
			(start 0.504 0.25)
			(end 0.504 -0.248)
			(stroke
				(width 0.15)
				(type solid)
			)
			(layer "B.Fab")
		)
		(fp_line
			(start -0.494 0.25)
			(end 0.504 0.25)
			(stroke
				(width 0.15)
				(type solid)
			)
			(layer "B.Fab")
		)
		(fp_text user "Author: Antmicro"
			(at -0.939 -3.399 270)
			(layer "B.Fab")
			(effects
				(font
					(size 0.7 0.7)
					(thickness 0.15)
				)
				(justify left bottom mirror)
			)
		)
		(fp_text user "License: Apache-2.0"
			(at -0.939 -5.799 270)
			(layer "B.Fab")
			(effects
				(font
					(size 0.7 0.7)
					(thickness 0.15)
				)
				(justify left bottom mirror)
			)
		)
		(fp_text user "${REFERENCE}"
			(at -0.939 -4.599 270)
			(layer "B.Fab")
			(effects
				(font
					(size 0.7 0.7)
					(thickness 0.15)
				)
				(justify left bottom mirror)
			)
		)
		(pad "1" smd roundrect
			(at -0.48 0 90)
			(size 0.59 0.64)
			(layers "B.Cu" "B.Mask" "B.Paste")
			(roundrect_rratio 0.25)
			(net 95 "/Ethernet/AVDDL")
			(pintype "passive")
		)
		(pad "2" smd roundrect
			(at 0.48 0 90)
			(size 0.59 0.64)
			(layers "B.Cu" "B.Mask" "B.Paste")
			(roundrect_rratio 0.25)
			(net 1 "GND")
			(pintype "passive")
		)
	)
	(footprint "antmicro-footprints:C_0402_1005Metric"
		(layer "B.Cu")
		(at 135.433171 146.453992 90)
		(descr "Capacitor SMD 0402")
		(tags "capacitor SMD 0402")
		(property "Reference" "C141"
			(at -3.914008 0.202829 90)
			(layer "B.SilkS")
			(effects
				(font
					(size 0.7 0.7)
					(thickness 0.15)
				)
				(justify right bottom mirror)
			)
		)
		(property "Value" "C_10n_0402"
			(at -1.022927 -2.155213 90)
			(layer "B.Fab")
			(effects
				(font
					(size 0.7 0.7)
					(thickness 0.15)
				)
				(justify right bottom mirror)
			)
		)
		(property "Datasheet" "https://www.murata.com/products/productdetail?partno=GRM155R71H103KA88%23"
			(at 0 0 90)
			(layer "F.Fab")
			(hide yes)
			(effects
				(font
					(size 1.27 1.27)
					(thickness 0.15)
				)
			)
		)
		(property "Manufacturer" "Murata"
			(at 0 0 90)
			(unlocked yes)
			(layer "B.Fab")
			(hide yes)
			(effects
				(font
					(size 1 1)
					(thickness 0.15)
				)
				(justify mirror)
			)
		)
		(property "MPN" "GRM155R71H103KA88D"
			(at 0 0 90)
			(unlocked yes)
			(layer "B.Fab")
			(hide yes)
			(effects
				(font
					(size 1 1)
					(thickness 0.15)
				)
				(justify mirror)
			)
		)
		(property "Val" "10n"
			(at 0 0 90)
			(unlocked yes)
			(layer "B.Fab")
			(hide yes)
			(effects
				(font
					(size 1 1)
					(thickness 0.15)
				)
				(justify mirror)
			)
		)
		(property "License" "Apache-2.0"
			(at 0 0 90)
			(unlocked yes)
			(layer "B.Fab")
			(hide yes)
			(effects
				(font
					(size 1 1)
					(thickness 0.15)
				)
				(justify mirror)
			)
		)
		(property "Author" "Antmicro"
			(at 0 0 90)
			(unlocked yes)
			(layer "B.Fab")
			(hide yes)
			(effects
				(font
					(size 1 1)
					(thickness 0.15)
				)
				(justify mirror)
			)
		)
		(property "Voltage" "50V"
			(at 0 0 90)
			(unlocked yes)
			(layer "B.Fab")
			(hide yes)
			(effects
				(font
					(size 1 1)
					(thickness 0.15)
				)
				(justify mirror)
			)
		)
		(property "Dielectric" "X7R"
			(at 0 0 90)
			(unlocked yes)
			(layer "B.Fab")
			(hide yes)
			(effects
				(font
					(size 1 1)
					(thickness 0.15)
				)
				(justify mirror)
			)
		)
		(sheetname "/Ethernet/")
		(sheetfile "ethernet.kicad_sch")
		(attr smd)
		(fp_rect
			(start -0.925 0.47)
			(end 0.925 -0.47)
			(stroke
				(width 0.05)
				(type default)
			)
			(fill no)
			(layer "B.CrtYd")
		)
		(fp_line
			(start 0.504 -0.248)
			(end -0.494 -0.248)
			(stroke
				(width 0.15)
				(type solid)
			)
			(layer "B.Fab")
		)
		(fp_line
			(start -0.494 -0.248)
			(end -0.494 0.25)
			(stroke
				(width 0.15)
				(type solid)
			)
			(layer "B.Fab")
		)
		(fp_line
			(start 0.504 0.25)
			(end 0.504 -0.248)
			(stroke
				(width 0.15)
				(type solid)
			)
			(layer "B.Fab")
		)
		(fp_line
			(start -0.494 0.25)
			(end 0.504 0.25)
			(stroke
				(width 0.15)
				(type solid)
			)
			(layer "B.Fab")
		)
		(fp_text user "Author: Antmicro"
			(at -0.939 -3.399 270)
			(layer "B.Fab")
			(effects
				(font
					(size 0.7 0.7)
					(thickness 0.15)
				)
				(justify left bottom mirror)
			)
		)
		(fp_text user "License: Apache-2.0"
			(at -0.939 -5.799 270)
			(layer "B.Fab")
			(effects
				(font
					(size 0.7 0.7)
					(thickness 0.15)
				)
				(justify left bottom mirror)
			)
		)
		(fp_text user "${REFERENCE}"
			(at -0.939 -4.599 270)
			(layer "B.Fab")
			(effects
				(font
					(size 0.7 0.7)
					(thickness 0.15)
				)
				(justify left bottom mirror)
			)
		)
		(pad "1" smd roundrect
			(at -0.48 0 90)
			(size 0.59 0.64)
			(layers "B.Cu" "B.Mask" "B.Paste")
			(roundrect_rratio 0.25)
			(net 797 "+1V8")
			(pintype "passive")
		)
		(pad "2" smd roundrect
			(at 0.48 0 90)
			(size 0.59 0.64)
			(layers "B.Cu" "B.Mask" "B.Paste")
			(roundrect_rratio 0.25)
			(net 1 "GND")
			(pintype "passive")
		)
	)
	(footprint "antmicro-footprints:C_0402_1005Metric"
		(layer "B.Cu")
		(at 139.011328 139.257157)
		(descr "Capacitor SMD 0402")
		(tags "capacitor SMD 0402")
		(property "Reference" "C152"
			(at 1.450672 0.442843 0)
			(layer "B.SilkS")
			(effects
				(font
					(size 0.7 0.7)
					(thickness 0.15)
				)
				(justify right bottom mirror)
			)
		)
		(property "Value" "C_4u7_0402"
			(at -1.022927 -2.155213 0)
			(layer "B.Fab")
			(effects
				(font
					(size 0.7 0.7)
					(thickness 0.15)
				)
				(justify right bottom mirror)
			)
		)
		(property "Datasheet" "https://www.murata.com/products/productdetail?partno=GRM155R61A475MEAA%23"
			(at 0 0 0)
			(layer "F.Fab")
			(hide yes)
			(effects
				(font
					(size 1.27 1.27)
					(thickness 0.15)
				)
			)
		)
		(property "Manufacturer" "Murata"
			(at 0 0 0)
			(unlocked yes)
			(layer "B.Fab")
			(hide yes)
			(effects
				(font
					(size 1 1)
					(thickness 0.15)
				)
				(justify mirror)
			)
		)
		(property "MPN" "GRM155R61A475MEAAD"
			(at 0 0 0)
			(unlocked yes)
			(layer "B.Fab")
			(hide yes)
			(effects
				(font
					(size 1 1)
					(thickness 0.15)
				)
				(justify mirror)
			)
		)
		(property "Val" "4u7"
			(at 0 0 0)
			(unlocked yes)
			(layer "B.Fab")
			(hide yes)
			(effects
				(font
					(size 1 1)
					(thickness 0.15)
				)
				(justify mirror)
			)
		)
		(property "License" "Apache-2.0"
			(at 0 0 0)
			(unlocked yes)
			(layer "B.Fab")
			(hide yes)
			(effects
				(font
					(size 1 1)
					(thickness 0.15)
				)
				(justify mirror)
			)
		)
		(property "Author" "Antmicro"
			(at 0 0 0)
			(unlocked yes)
			(layer "B.Fab")
			(hide yes)
			(effects
				(font
					(size 1 1)
					(thickness 0.15)
				)
				(justify mirror)
			)
		)
		(property "Voltage" ""
			(at 0 0 0)
			(unlocked yes)
			(layer "B.Fab")
			(hide yes)
			(effects
				(font
					(size 1 1)
					(thickness 0.15)
				)
				(justify mirror)
			)
		)
		(property "Dielectric" ""
			(at 0 0 0)
			(unlocked yes)
			(layer "B.Fab")
			(hide yes)
			(effects
				(font
					(size 1 1)
					(thickness 0.15)
				)
				(justify mirror)
			)
		)
		(sheetname "/Ethernet/")
		(sheetfile "ethernet.kicad_sch")
		(attr smd)
		(fp_rect
			(start -0.925 0.47)
			(end 0.925 -0.47)
			(stroke
				(width 0.05)
				(type default)
			)
			(fill no)
			(layer "B.CrtYd")
		)
		(fp_line
			(start -0.494 -0.248)
			(end -0.494 0.25)
			(stroke
				(width 0.15)
				(type solid)
			)
			(layer "B.Fab")
		)
		(fp_line
			(start -0.494 0.25)
			(end 0.504 0.25)
			(stroke
				(width 0.15)
				(type solid)
			)
			(layer "B.Fab")
		)
		(fp_line
			(start 0.504 -0.248)
			(end -0.494 -0.248)
			(stroke
				(width 0.15)
				(type solid)
			)
			(layer "B.Fab")
		)
		(fp_line
			(start 0.504 0.25)
			(end 0.504 -0.248)
			(stroke
				(width 0.15)
				(type solid)
			)
			(layer "B.Fab")
		)
		(fp_text user "${REFERENCE}"
			(at -0.939 -4.599 180)
			(layer "B.Fab")
			(effects
				(font
					(size 0.7 0.7)
					(thickness 0.15)
				)
				(justify left bottom mirror)
			)
		)
		(fp_text user "Author: Antmicro"
			(at -0.939 -3.399 180)
			(layer "B.Fab")
			(effects
				(font
					(size 0.7 0.7)
					(thickness 0.15)
				)
				(justify left bottom mirror)
			)
		)
		(fp_text user "License: Apache-2.0"
			(at -0.939 -5.799 180)
			(layer "B.Fab")
			(effects
				(font
					(size 0.7 0.7)
					(thickness 0.15)
				)
				(justify left bottom mirror)
			)
		)
		(pad "1" smd roundrect
			(at -0.48 0)
			(size 0.59 0.64)
			(layers "B.Cu" "B.Mask" "B.Paste")
			(roundrect_rratio 0.25)
			(net 97 "/Ethernet/AVDDH")
			(pintype "passive")
		)
		(pad "2" smd roundrect
			(at 0.48 0)
			(size 0.59 0.64)
			(layers "B.Cu" "B.Mask" "B.Paste")
			(roundrect_rratio 0.25)
			(net 1 "GND")
			(pintype "passive")
		)
	)
	(footprint "antmicro-footprints:C_0402_1005Metric"
		(layer "B.Cu")
		(at 132.624499 138.732157 90)
		(descr "Capacitor SMD 0402")
		(tags "capacitor SMD 0402")
		(property "Reference" "C136"
			(at 1.176157 0.344672 90)
			(layer "B.SilkS")
			(effects
				(font
					(size 0.7 0.7)
					(thickness 0.15)
				)
				(justify right bottom mirror)
			)
		)
		(property "Value" "C_10n_0402"
			(at -1.022927 -2.155213 90)
			(layer "B.Fab")
			(effects
				(font
					(size 0.7 0.7)
					(thickness 0.15)
				)
				(justify right bottom mirror)
			)
		)
		(property "Datasheet" "https://www.murata.com/products/productdetail?partno=GRM155R71H103KA88%23"
			(at 0 0 90)
			(layer "F.Fab")
			(hide yes)
			(effects
				(font
					(size 1.27 1.27)
					(thickness 0.15)
				)
			)
		)
		(property "Manufacturer" "Murata"
			(at 0 0 90)
			(unlocked yes)
			(layer "B.Fab")
			(hide yes)
			(effects
				(font
					(size 1 1)
					(thickness 0.15)
				)
				(justify mirror)
			)
		)
		(property "MPN" "GRM155R71H103KA88D"
			(at 0 0 90)
			(unlocked yes)
			(layer "B.Fab")
			(hide yes)
			(effects
				(font
					(size 1 1)
					(thickness 0.15)
				)
				(justify mirror)
			)
		)
		(property "Val" "10n"
			(at 0 0 90)
			(unlocked yes)
			(layer "B.Fab")
			(hide yes)
			(effects
				(font
					(size 1 1)
					(thickness 0.15)
				)
				(justify mirror)
			)
		)
		(property "License" "Apache-2.0"
			(at 0 0 90)
			(unlocked yes)
			(layer "B.Fab")
			(hide yes)
			(effects
				(font
					(size 1 1)
					(thickness 0.15)
				)
				(justify mirror)
			)
		)
		(property "Author" "Antmicro"
			(at 0 0 90)
			(unlocked yes)
			(layer "B.Fab")
			(hide yes)
			(effects
				(font
					(size 1 1)
					(thickness 0.15)
				)
				(justify mirror)
			)
		)
		(property "Voltage" "50V"
			(at 0 0 90)
			(unlocked yes)
			(layer "B.Fab")
			(hide yes)
			(effects
				(font
					(size 1 1)
					(thickness 0.15)
				)
				(justify mirror)
			)
		)
		(property "Dielectric" "X7R"
			(at 0 0 90)
			(unlocked yes)
			(layer "B.Fab")
			(hide yes)
			(effects
				(font
					(size 1 1)
					(thickness 0.15)
				)
				(justify mirror)
			)
		)
		(sheetname "/Ethernet/")
		(sheetfile "ethernet.kicad_sch")
		(attr smd)
		(fp_rect
			(start -0.925 0.47)
			(end 0.925 -0.47)
			(stroke
				(width 0.05)
				(type default)
			)
			(fill no)
			(layer "B.CrtYd")
		)
		(fp_line
			(start 0.504 -0.248)
			(end -0.494 -0.248)
			(stroke
				(width 0.15)
				(type solid)
			)
			(layer "B.Fab")
		)
		(fp_line
			(start -0.494 -0.248)
			(end -0.494 0.25)
			(stroke
				(width 0.15)
				(type solid)
			)
			(layer "B.Fab")
		)
		(fp_line
			(start 0.504 0.25)
			(end 0.504 -0.248)
			(stroke
				(width 0.15)
				(type solid)
			)
			(layer "B.Fab")
		)
		(fp_line
			(start -0.494 0.25)
			(end 0.504 0.25)
			(stroke
				(width 0.15)
				(type solid)
			)
			(layer "B.Fab")
		)
		(fp_text user "${REFERENCE}"
			(at -0.939 -4.599 270)
			(layer "B.Fab")
			(effects
				(font
					(size 0.7 0.7)
					(thickness 0.15)
				)
				(justify left bottom mirror)
			)
		)
		(fp_text user "License: Apache-2.0"
			(at -0.939 -5.799 270)
			(layer "B.Fab")
			(effects
				(font
					(size 0.7 0.7)
					(thickness 0.15)
				)
				(justify left bottom mirror)
			)
		)
		(fp_text user "Author: Antmicro"
			(at -0.939 -3.399 270)
			(layer "B.Fab")
			(effects
				(font
					(size 0.7 0.7)
					(thickness 0.15)
				)
				(justify left bottom mirror)
			)
		)
		(pad "1" smd roundrect
			(at -0.48 0 90)
			(size 0.59 0.64)
			(layers "B.Cu" "B.Mask" "B.Paste")
			(roundrect_rratio 0.25)
			(net 95 "/Ethernet/AVDDL")
			(pintype "passive")
		)
		(pad "2" smd roundrect
			(at 0.48 0 90)
			(size 0.59 0.64)
			(layers "B.Cu" "B.Mask" "B.Paste")
			(roundrect_rratio 0.25)
			(net 1 "GND")
			(pintype "passive")
		)
	)
	(footprint "antmicro-footprints:C_0402_1005Metric"
		(layer "B.Cu")
		(at 139.224499 143.649)
		(descr "Capacitor SMD 0402")
		(tags "capacitor SMD 0402")
		(property "Reference" "C144"
			(at 0.983501 0.623 0)
			(layer "B.SilkS")
			(effects
				(font
					(size 0.7 0.7)
					(thickness 0.15)
				)
				(justify right bottom mirror)
			)
		)
		(property "Value" "C_10n_0402"
			(at -1.022927 -2.155213 0)
			(layer "B.Fab")
			(effects
				(font
					(size 0.7 0.7)
					(thickness 0.15)
				)
				(justify right bottom mirror)
			)
		)
		(property "Datasheet" "https://www.murata.com/products/productdetail?partno=GRM155R71H103KA88%23"
			(at 0 0 0)
			(layer "F.Fab")
			(hide yes)
			(effects
				(font
					(size 1.27 1.27)
					(thickness 0.15)
				)
			)
		)
		(property "Manufacturer" "Murata"
			(at 0 0 0)
			(unlocked yes)
			(layer "B.Fab")
			(hide yes)
			(effects
				(font
					(size 1 1)
					(thickness 0.15)
				)
				(justify mirror)
			)
		)
		(property "MPN" "GRM155R71H103KA88D"
			(at 0 0 0)
			(unlocked yes)
			(layer "B.Fab")
			(hide yes)
			(effects
				(font
					(size 1 1)
					(thickness 0.15)
				)
				(justify mirror)
			)
		)
		(property "Val" "10n"
			(at 0 0 0)
			(unlocked yes)
			(layer "B.Fab")
			(hide yes)
			(effects
				(font
					(size 1 1)
					(thickness 0.15)
				)
				(justify mirror)
			)
		)
		(property "License" "Apache-2.0"
			(at 0 0 0)
			(unlocked yes)
			(layer "B.Fab")
			(hide yes)
			(effects
				(font
					(size 1 1)
					(thickness 0.15)
				)
				(justify mirror)
			)
		)
		(property "Author" "Antmicro"
			(at 0 0 0)
			(unlocked yes)
			(layer "B.Fab")
			(hide yes)
			(effects
				(font
					(size 1 1)
					(thickness 0.15)
				)
				(justify mirror)
			)
		)
		(property "Voltage" "50V"
			(at 0 0 0)
			(unlocked yes)
			(layer "B.Fab")
			(hide yes)
			(effects
				(font
					(size 1 1)
					(thickness 0.15)
				)
				(justify mirror)
			)
		)
		(property "Dielectric" "X7R"
			(at 0 0 0)
			(unlocked yes)
			(layer "B.Fab")
			(hide yes)
			(effects
				(font
					(size 1 1)
					(thickness 0.15)
				)
				(justify mirror)
			)
		)
		(sheetname "/Ethernet/")
		(sheetfile "ethernet.kicad_sch")
		(attr smd)
		(fp_rect
			(start -0.925 0.47)
			(end 0.925 -0.47)
			(stroke
				(width 0.05)
				(type default)
			)
			(fill no)
			(layer "B.CrtYd")
		)
		(fp_line
			(start -0.494 -0.248)
			(end -0.494 0.25)
			(stroke
				(width 0.15)
				(type solid)
			)
			(layer "B.Fab")
		)
		(fp_line
			(start -0.494 0.25)
			(end 0.504 0.25)
			(stroke
				(width 0.15)
				(type solid)
			)
			(layer "B.Fab")
		)
		(fp_line
			(start 0.504 -0.248)
			(end -0.494 -0.248)
			(stroke
				(width 0.15)
				(type solid)
			)
			(layer "B.Fab")
		)
		(fp_line
			(start 0.504 0.25)
			(end 0.504 -0.248)
			(stroke
				(width 0.15)
				(type solid)
			)
			(layer "B.Fab")
		)
		(fp_text user "Author: Antmicro"
			(at -0.939 -3.399 180)
			(layer "B.Fab")
			(effects
				(font
					(size 0.7 0.7)
					(thickness 0.15)
				)
				(justify left bottom mirror)
			)
		)
		(fp_text user "${REFERENCE}"
			(at -0.939 -4.599 180)
			(layer "B.Fab")
			(effects
				(font
					(size 0.7 0.7)
					(thickness 0.15)
				)
				(justify left bottom mirror)
			)
		)
		(fp_text user "License: Apache-2.0"
			(at -0.939 -5.799 180)
			(layer "B.Fab")
			(effects
				(font
					(size 0.7 0.7)
					(thickness 0.15)
				)
				(justify left bottom mirror)
			)
		)
		(pad "1" smd roundrect
			(at -0.48 0)
			(size 0.59 0.64)
			(layers "B.Cu" "B.Mask" "B.Paste")
			(roundrect_rratio 0.25)
			(net 797 "+1V8")
			(pintype "passive")
		)
		(pad "2" smd roundrect
			(at 0.48 0)
			(size 0.59 0.64)
			(layers "B.Cu" "B.Mask" "B.Paste")
			(roundrect_rratio 0.25)
			(net 1 "GND")
			(pintype "passive")
		)
	)
	(footprint "antmicro-footprints:C_0402_1005Metric"
		(layer "B.Cu")
		(at 131.211328 138.082157 90)
		(descr "Capacitor SMD 0402")
		(tags "capacitor SMD 0402")
		(property "Reference" "C155"
			(at 1.176157 0.344672 90)
			(layer "B.SilkS")
			(effects
				(font
					(size 0.7 0.7)
					(thickness 0.15)
				)
				(justify right bottom mirror)
			)
		)
		(property "Value" "C_4u7_0402"
			(at -1.022927 -2.155213 90)
			(layer "B.Fab")
			(effects
				(font
					(size 0.7 0.7)
					(thickness 0.15)
				)
				(justify right bottom mirror)
			)
		)
		(property "Datasheet" "https://www.murata.com/products/productdetail?partno=GRM155R61A475MEAA%23"
			(at 0 0 90)
			(layer "F.Fab")
			(hide yes)
			(effects
				(font
					(size 1.27 1.27)
					(thickness 0.15)
				)
			)
		)
		(property "Manufacturer" "Murata"
			(at 0 0 90)
			(unlocked yes)
			(layer "B.Fab")
			(hide yes)
			(effects
				(font
					(size 1 1)
					(thickness 0.15)
				)
				(justify mirror)
			)
		)
		(property "MPN" "GRM155R61A475MEAAD"
			(at 0 0 90)
			(unlocked yes)
			(layer "B.Fab")
			(hide yes)
			(effects
				(font
					(size 1 1)
					(thickness 0.15)
				)
				(justify mirror)
			)
		)
		(property "Val" "4u7"
			(at 0 0 90)
			(unlocked yes)
			(layer "B.Fab")
			(hide yes)
			(effects
				(font
					(size 1 1)
					(thickness 0.15)
				)
				(justify mirror)
			)
		)
		(property "License" "Apache-2.0"
			(at 0 0 90)
			(unlocked yes)
			(layer "B.Fab")
			(hide yes)
			(effects
				(font
					(size 1 1)
					(thickness 0.15)
				)
				(justify mirror)
			)
		)
		(property "Author" "Antmicro"
			(at 0 0 90)
			(unlocked yes)
			(layer "B.Fab")
			(hide yes)
			(effects
				(font
					(size 1 1)
					(thickness 0.15)
				)
				(justify mirror)
			)
		)
		(property "Voltage" ""
			(at 0 0 90)
			(unlocked yes)
			(layer "B.Fab")
			(hide yes)
			(effects
				(font
					(size 1 1)
					(thickness 0.15)
				)
				(justify mirror)
			)
		)
		(property "Dielectric" ""
			(at 0 0 90)
			(unlocked yes)
			(layer "B.Fab")
			(hide yes)
			(effects
				(font
					(size 1 1)
					(thickness 0.15)
				)
				(justify mirror)
			)
		)
		(sheetname "/Ethernet/")
		(sheetfile "ethernet.kicad_sch")
		(attr smd)
		(fp_rect
			(start -0.925 0.47)
			(end 0.925 -0.47)
			(stroke
				(width 0.05)
				(type default)
			)
			(fill no)
			(layer "B.CrtYd")
		)
		(fp_line
			(start 0.504 -0.248)
			(end -0.494 -0.248)
			(stroke
				(width 0.15)
				(type solid)
			)
			(layer "B.Fab")
		)
		(fp_line
			(start -0.494 -0.248)
			(end -0.494 0.25)
			(stroke
				(width 0.15)
				(type solid)
			)
			(layer "B.Fab")
		)
		(fp_line
			(start 0.504 0.25)
			(end 0.504 -0.248)
			(stroke
				(width 0.15)
				(type solid)
			)
			(layer "B.Fab")
		)
		(fp_line
			(start -0.494 0.25)
			(end 0.504 0.25)
			(stroke
				(width 0.15)
				(type solid)
			)
			(layer "B.Fab")
		)
		(fp_text user "${REFERENCE}"
			(at -0.939 -4.599 270)
			(layer "B.Fab")
			(effects
				(font
					(size 0.7 0.7)
					(thickness 0.15)
				)
				(justify left bottom mirror)
			)
		)
		(fp_text user "Author: Antmicro"
			(at -0.939 -3.399 270)
			(layer "B.Fab")
			(effects
				(font
					(size 0.7 0.7)
					(thickness 0.15)
				)
				(justify left bottom mirror)
			)
		)
		(fp_text user "License: Apache-2.0"
			(at -0.939 -5.799 270)
			(layer "B.Fab")
			(effects
				(font
					(size 0.7 0.7)
					(thickness 0.15)
				)
				(justify left bottom mirror)
			)
		)
		(pad "1" smd roundrect
			(at -0.48 0 90)
			(size 0.59 0.64)
			(layers "B.Cu" "B.Mask" "B.Paste")
			(roundrect_rratio 0.25)
			(net 97 "/Ethernet/AVDDH")
			(pintype "passive")
		)
		(pad "2" smd roundrect
			(at 0.48 0 90)
			(size 0.59 0.64)
			(layers "B.Cu" "B.Mask" "B.Paste")
			(roundrect_rratio 0.25)
			(net 1 "GND")
			(pintype "passive")
		)
	)
	(footprint "antmicro-footprints:C_0402_1005Metric"
		(layer "B.Cu")
		(at 133.433171 146.453992 90)
		(descr "Capacitor SMD 0402")
		(tags "capacitor SMD 0402")
		(property "Reference" "C151"
			(at -3.914008 0.202829 90)
			(layer "B.SilkS")
			(effects
				(font
					(size 0.7 0.7)
					(thickness 0.15)
				)
				(justify right bottom mirror)
			)
		)
		(property "Value" "C_10n_0402"
			(at -1.022927 -2.155213 90)
			(layer "B.Fab")
			(effects
				(font
					(size 0.7 0.7)
					(thickness 0.15)
				)
				(justify right bottom mirror)
			)
		)
		(property "Datasheet" "https://www.murata.com/products/productdetail?partno=GRM155R71H103KA88%23"
			(at 0 0 90)
			(layer "F.Fab")
			(hide yes)
			(effects
				(font
					(size 1.27 1.27)
					(thickness 0.15)
				)
			)
		)
		(property "Manufacturer" "Murata"
			(at 0 0 90)
			(unlocked yes)
			(layer "B.Fab")
			(hide yes)
			(effects
				(font
					(size 1 1)
					(thickness 0.15)
				)
				(justify mirror)
			)
		)
		(property "MPN" "GRM155R71H103KA88D"
			(at 0 0 90)
			(unlocked yes)
			(layer "B.Fab")
			(hide yes)
			(effects
				(font
					(size 1 1)
					(thickness 0.15)
				)
				(justify mirror)
			)
		)
		(property "Val" "10n"
			(at 0 0 90)
			(unlocked yes)
			(layer "B.Fab")
			(hide yes)
			(effects
				(font
					(size 1 1)
					(thickness 0.15)
				)
				(justify mirror)
			)
		)
		(property "License" "Apache-2.0"
			(at 0 0 90)
			(unlocked yes)
			(layer "B.Fab")
			(hide yes)
			(effects
				(font
					(size 1 1)
					(thickness 0.15)
				)
				(justify mirror)
			)
		)
		(property "Author" "Antmicro"
			(at 0 0 90)
			(unlocked yes)
			(layer "B.Fab")
			(hide yes)
			(effects
				(font
					(size 1 1)
					(thickness 0.15)
				)
				(justify mirror)
			)
		)
		(property "Voltage" "50V"
			(at 0 0 90)
			(unlocked yes)
			(layer "B.Fab")
			(hide yes)
			(effects
				(font
					(size 1 1)
					(thickness 0.15)
				)
				(justify mirror)
			)
		)
		(property "Dielectric" "X7R"
			(at 0 0 90)
			(unlocked yes)
			(layer "B.Fab")
			(hide yes)
			(effects
				(font
					(size 1 1)
					(thickness 0.15)
				)
				(justify mirror)
			)
		)
		(sheetname "/Ethernet/")
		(sheetfile "ethernet.kicad_sch")
		(attr smd)
		(fp_rect
			(start -0.925 0.47)
			(end 0.925 -0.47)
			(stroke
				(width 0.05)
				(type default)
			)
			(fill no)
			(layer "B.CrtYd")
		)
		(fp_line
			(start 0.504 -0.248)
			(end -0.494 -0.248)
			(stroke
				(width 0.15)
				(type solid)
			)
			(layer "B.Fab")
		)
		(fp_line
			(start -0.494 -0.248)
			(end -0.494 0.25)
			(stroke
				(width 0.15)
				(type solid)
			)
			(layer "B.Fab")
		)
		(fp_line
			(start 0.504 0.25)
			(end 0.504 -0.248)
			(stroke
				(width 0.15)
				(type solid)
			)
			(layer "B.Fab")
		)
		(fp_line
			(start -0.494 0.25)
			(end 0.504 0.25)
			(stroke
				(width 0.15)
				(type solid)
			)
			(layer "B.Fab")
		)
		(fp_text user "License: Apache-2.0"
			(at -0.939 -5.799 270)
			(layer "B.Fab")
			(effects
				(font
					(size 0.7 0.7)
					(thickness 0.15)
				)
				(justify left bottom mirror)
			)
		)
		(fp_text user "Author: Antmicro"
			(at -0.939 -3.399 270)
			(layer "B.Fab")
			(effects
				(font
					(size 0.7 0.7)
					(thickness 0.15)
				)
				(justify left bottom mirror)
			)
		)
		(fp_text user "${REFERENCE}"
			(at -0.939 -4.599 270)
			(layer "B.Fab")
			(effects
				(font
					(size 0.7 0.7)
					(thickness 0.15)
				)
				(justify left bottom mirror)
			)
		)
		(pad "1" smd roundrect
			(at -0.48 0 90)
			(size 0.59 0.64)
			(layers "B.Cu" "B.Mask" "B.Paste")
			(roundrect_rratio 0.25)
			(net 150 "+1V2")
			(pintype "passive")
		)
		(pad "2" smd roundrect
			(at 0.48 0 90)
			(size 0.59 0.64)
			(layers "B.Cu" "B.Mask" "B.Paste")
			(roundrect_rratio 0.25)
			(net 1 "GND")
			(pintype "passive")
		)
	)
	(footprint "antmicro-footprints:C_0402_1005Metric"
		(layer "B.Cu")
		(at 130.211328 138.082157 90)
		(descr "Capacitor SMD 0402")
		(tags "capacitor SMD 0402")
		(property "Reference" "C158"
			(at 1.176157 0.344672 90)
			(layer "B.SilkS")
			(effects
				(font
					(size 0.7 0.7)
					(thickness 0.15)
				)
				(justify right bottom mirror)
			)
		)
		(property "Value" "C_4u7_0402"
			(at -1.022927 -2.155213 90)
			(layer "B.Fab")
			(effects
				(font
					(size 0.7 0.7)
					(thickness 0.15)
				)
				(justify right bottom mirror)
			)
		)
		(property "Datasheet" "https://www.murata.com/products/productdetail?partno=GRM155R61A475MEAA%23"
			(at 0 0 90)
			(layer "F.Fab")
			(hide yes)
			(effects
				(font
					(size 1.27 1.27)
					(thickness 0.15)
				)
			)
		)
		(property "Manufacturer" "Murata"
			(at 0 0 90)
			(unlocked yes)
			(layer "B.Fab")
			(hide yes)
			(effects
				(font
					(size 1 1)
					(thickness 0.15)
				)
				(justify mirror)
			)
		)
		(property "MPN" "GRM155R61A475MEAAD"
			(at 0 0 90)
			(unlocked yes)
			(layer "B.Fab")
			(hide yes)
			(effects
				(font
					(size 1 1)
					(thickness 0.15)
				)
				(justify mirror)
			)
		)
		(property "Val" "4u7"
			(at 0 0 90)
			(unlocked yes)
			(layer "B.Fab")
			(hide yes)
			(effects
				(font
					(size 1 1)
					(thickness 0.15)
				)
				(justify mirror)
			)
		)
		(property "License" "Apache-2.0"
			(at 0 0 90)
			(unlocked yes)
			(layer "B.Fab")
			(hide yes)
			(effects
				(font
					(size 1 1)
					(thickness 0.15)
				)
				(justify mirror)
			)
		)
		(property "Author" "Antmicro"
			(at 0 0 90)
			(unlocked yes)
			(layer "B.Fab")
			(hide yes)
			(effects
				(font
					(size 1 1)
					(thickness 0.15)
				)
				(justify mirror)
			)
		)
		(property "Voltage" ""
			(at 0 0 90)
			(unlocked yes)
			(layer "B.Fab")
			(hide yes)
			(effects
				(font
					(size 1 1)
					(thickness 0.15)
				)
				(justify mirror)
			)
		)
		(property "Dielectric" ""
			(at 0 0 90)
			(unlocked yes)
			(layer "B.Fab")
			(hide yes)
			(effects
				(font
					(size 1 1)
					(thickness 0.15)
				)
				(justify mirror)
			)
		)
		(sheetname "/Ethernet/")
		(sheetfile "ethernet.kicad_sch")
		(attr smd)
		(fp_rect
			(start -0.925 0.47)
			(end 0.925 -0.47)
			(stroke
				(width 0.05)
				(type default)
			)
			(fill no)
			(layer "B.CrtYd")
		)
		(fp_line
			(start 0.504 -0.248)
			(end -0.494 -0.248)
			(stroke
				(width 0.15)
				(type solid)
			)
			(layer "B.Fab")
		)
		(fp_line
			(start -0.494 -0.248)
			(end -0.494 0.25)
			(stroke
				(width 0.15)
				(type solid)
			)
			(layer "B.Fab")
		)
		(fp_line
			(start 0.504 0.25)
			(end 0.504 -0.248)
			(stroke
				(width 0.15)
				(type solid)
			)
			(layer "B.Fab")
		)
		(fp_line
			(start -0.494 0.25)
			(end 0.504 0.25)
			(stroke
				(width 0.15)
				(type solid)
			)
			(layer "B.Fab")
		)
		(fp_text user "Author: Antmicro"
			(at -0.939 -3.399 270)
			(layer "B.Fab")
			(effects
				(font
					(size 0.7 0.7)
					(thickness 0.15)
				)
				(justify left bottom mirror)
			)
		)
		(fp_text user "${REFERENCE}"
			(at -0.939 -4.599 270)
			(layer "B.Fab")
			(effects
				(font
					(size 0.7 0.7)
					(thickness 0.15)
				)
				(justify left bottom mirror)
			)
		)
		(fp_text user "License: Apache-2.0"
			(at -0.939 -5.799 270)
			(layer "B.Fab")
			(effects
				(font
					(size 0.7 0.7)
					(thickness 0.15)
				)
				(justify left bottom mirror)
			)
		)
		(pad "1" smd roundrect
			(at -0.48 0 90)
			(size 0.59 0.64)
			(layers "B.Cu" "B.Mask" "B.Paste")
			(roundrect_rratio 0.25)
			(net 97 "/Ethernet/AVDDH")
			(pintype "passive")
		)
		(pad "2" smd roundrect
			(at 0.48 0 90)
			(size 0.59 0.64)
			(layers "B.Cu" "B.Mask" "B.Paste")
			(roundrect_rratio 0.25)
			(net 1 "GND")
			(pintype "passive")
		)
	)
	(footprint "antmicro-footprints:C_0402_1005Metric"
		(layer "B.Cu")
		(at 131.233171 146.453992 90)
		(descr "Capacitor SMD 0402")
		(tags "capacitor SMD 0402")
		(property "Reference" "C153"
			(at -3.914008 0.202829 90)
			(layer "B.SilkS")
			(effects
				(font
					(size 0.7 0.7)
					(thickness 0.15)
				)
				(justify right bottom mirror)
			)
		)
		(property "Value" "C_10n_0402"
			(at -1.022927 -2.155213 90)
			(layer "B.Fab")
			(effects
				(font
					(size 0.7 0.7)
					(thickness 0.15)
				)
				(justify right bottom mirror)
			)
		)
		(property "Datasheet" "https://www.murata.com/products/productdetail?partno=GRM155R71H103KA88%23"
			(at 0 0 90)
			(layer "F.Fab")
			(hide yes)
			(effects
				(font
					(size 1.27 1.27)
					(thickness 0.15)
				)
			)
		)
		(property "Manufacturer" "Murata"
			(at 0 0 90)
			(unlocked yes)
			(layer "B.Fab")
			(hide yes)
			(effects
				(font
					(size 1 1)
					(thickness 0.15)
				)
				(justify mirror)
			)
		)
		(property "MPN" "GRM155R71H103KA88D"
			(at 0 0 90)
			(unlocked yes)
			(layer "B.Fab")
			(hide yes)
			(effects
				(font
					(size 1 1)
					(thickness 0.15)
				)
				(justify mirror)
			)
		)
		(property "Val" "10n"
			(at 0 0 90)
			(unlocked yes)
			(layer "B.Fab")
			(hide yes)
			(effects
				(font
					(size 1 1)
					(thickness 0.15)
				)
				(justify mirror)
			)
		)
		(property "License" "Apache-2.0"
			(at 0 0 90)
			(unlocked yes)
			(layer "B.Fab")
			(hide yes)
			(effects
				(font
					(size 1 1)
					(thickness 0.15)
				)
				(justify mirror)
			)
		)
		(property "Author" "Antmicro"
			(at 0 0 90)
			(unlocked yes)
			(layer "B.Fab")
			(hide yes)
			(effects
				(font
					(size 1 1)
					(thickness 0.15)
				)
				(justify mirror)
			)
		)
		(property "Voltage" "50V"
			(at 0 0 90)
			(unlocked yes)
			(layer "B.Fab")
			(hide yes)
			(effects
				(font
					(size 1 1)
					(thickness 0.15)
				)
				(justify mirror)
			)
		)
		(property "Dielectric" "X7R"
			(at 0 0 90)
			(unlocked yes)
			(layer "B.Fab")
			(hide yes)
			(effects
				(font
					(size 1 1)
					(thickness 0.15)
				)
				(justify mirror)
			)
		)
		(sheetname "/Ethernet/")
		(sheetfile "ethernet.kicad_sch")
		(attr smd)
		(fp_rect
			(start -0.925 0.47)
			(end 0.925 -0.47)
			(stroke
				(width 0.05)
				(type default)
			)
			(fill no)
			(layer "B.CrtYd")
		)
		(fp_line
			(start 0.504 -0.248)
			(end -0.494 -0.248)
			(stroke
				(width 0.15)
				(type solid)
			)
			(layer "B.Fab")
		)
		(fp_line
			(start -0.494 -0.248)
			(end -0.494 0.25)
			(stroke
				(width 0.15)
				(type solid)
			)
			(layer "B.Fab")
		)
		(fp_line
			(start 0.504 0.25)
			(end 0.504 -0.248)
			(stroke
				(width 0.15)
				(type solid)
			)
			(layer "B.Fab")
		)
		(fp_line
			(start -0.494 0.25)
			(end 0.504 0.25)
			(stroke
				(width 0.15)
				(type solid)
			)
			(layer "B.Fab")
		)
		(fp_text user "License: Apache-2.0"
			(at -0.939 -5.799 270)
			(layer "B.Fab")
			(effects
				(font
					(size 0.7 0.7)
					(thickness 0.15)
				)
				(justify left bottom mirror)
			)
		)
		(fp_text user "${REFERENCE}"
			(at -0.939 -4.599 270)
			(layer "B.Fab")
			(effects
				(font
					(size 0.7 0.7)
					(thickness 0.15)
				)
				(justify left bottom mirror)
			)
		)
		(fp_text user "Author: Antmicro"
			(at -0.939 -3.399 270)
			(layer "B.Fab")
			(effects
				(font
					(size 0.7 0.7)
					(thickness 0.15)
				)
				(justify left bottom mirror)
			)
		)
		(pad "1" smd roundrect
			(at -0.48 0 90)
			(size 0.59 0.64)
			(layers "B.Cu" "B.Mask" "B.Paste")
			(roundrect_rratio 0.25)
			(net 150 "+1V2")
			(pintype "passive")
		)
		(pad "2" smd roundrect
			(at 0.48 0 90)
			(size 0.59 0.64)
			(layers "B.Cu" "B.Mask" "B.Paste")
			(roundrect_rratio 0.25)
			(net 1 "GND")
			(pintype "passive")
		)
	)
	(footprint "antmicro-footprints:C_0402_1005Metric"
		(layer "B.Cu")
		(at 131.36 141.95 90)
		(descr "Capacitor SMD 0402")
		(tags "capacitor SMD 0402")
		(property "Reference" "C156"
			(at -3.5 -0.3 90)
			(layer "B.SilkS")
			(effects
				(font
					(size 0.7 0.7)
					(thickness 0.15)
				)
				(justify right bottom mirror)
			)
		)
		(property "Value" "C_10n_0402"
			(at -1.022927 -2.155213 90)
			(layer "B.Fab")
			(effects
				(font
					(size 0.7 0.7)
					(thickness 0.15)
				)
				(justify right bottom mirror)
			)
		)
		(property "Datasheet" "https://www.murata.com/products/productdetail?partno=GRM155R71H103KA88%23"
			(at 0 0 90)
			(layer "F.Fab")
			(hide yes)
			(effects
				(font
					(size 1.27 1.27)
					(thickness 0.15)
				)
			)
		)
		(property "Manufacturer" "Murata"
			(at 0 0 90)
			(unlocked yes)
			(layer "B.Fab")
			(hide yes)
			(effects
				(font
					(size 1 1)
					(thickness 0.15)
				)
				(justify mirror)
			)
		)
		(property "MPN" "GRM155R71H103KA88D"
			(at 0 0 90)
			(unlocked yes)
			(layer "B.Fab")
			(hide yes)
			(effects
				(font
					(size 1 1)
					(thickness 0.15)
				)
				(justify mirror)
			)
		)
		(property "Val" "10n"
			(at 0 0 90)
			(unlocked yes)
			(layer "B.Fab")
			(hide yes)
			(effects
				(font
					(size 1 1)
					(thickness 0.15)
				)
				(justify mirror)
			)
		)
		(property "License" "Apache-2.0"
			(at 0 0 90)
			(unlocked yes)
			(layer "B.Fab")
			(hide yes)
			(effects
				(font
					(size 1 1)
					(thickness 0.15)
				)
				(justify mirror)
			)
		)
		(property "Author" "Antmicro"
			(at 0 0 90)
			(unlocked yes)
			(layer "B.Fab")
			(hide yes)
			(effects
				(font
					(size 1 1)
					(thickness 0.15)
				)
				(justify mirror)
			)
		)
		(property "Voltage" "50V"
			(at 0 0 90)
			(unlocked yes)
			(layer "B.Fab")
			(hide yes)
			(effects
				(font
					(size 1 1)
					(thickness 0.15)
				)
				(justify mirror)
			)
		)
		(property "Dielectric" "X7R"
			(at 0 0 90)
			(unlocked yes)
			(layer "B.Fab")
			(hide yes)
			(effects
				(font
					(size 1 1)
					(thickness 0.15)
				)
				(justify mirror)
			)
		)
		(sheetname "/Ethernet/")
		(sheetfile "ethernet.kicad_sch")
		(attr smd)
		(fp_rect
			(start -0.925 0.47)
			(end 0.925 -0.47)
			(stroke
				(width 0.05)
				(type default)
			)
			(fill no)
			(layer "B.CrtYd")
		)
		(fp_line
			(start 0.504 -0.248)
			(end -0.494 -0.248)
			(stroke
				(width 0.15)
				(type solid)
			)
			(layer "B.Fab")
		)
		(fp_line
			(start -0.494 -0.248)
			(end -0.494 0.25)
			(stroke
				(width 0.15)
				(type solid)
			)
			(layer "B.Fab")
		)
		(fp_line
			(start 0.504 0.25)
			(end 0.504 -0.248)
			(stroke
				(width 0.15)
				(type solid)
			)
			(layer "B.Fab")
		)
		(fp_line
			(start -0.494 0.25)
			(end 0.504 0.25)
			(stroke
				(width 0.15)
				(type solid)
			)
			(layer "B.Fab")
		)
		(fp_text user "License: Apache-2.0"
			(at -0.939 -5.799 270)
			(layer "B.Fab")
			(effects
				(font
					(size 0.7 0.7)
					(thickness 0.15)
				)
				(justify left bottom mirror)
			)
		)
		(fp_text user "${REFERENCE}"
			(at -0.939 -4.599 270)
			(layer "B.Fab")
			(effects
				(font
					(size 0.7 0.7)
					(thickness 0.15)
				)
				(justify left bottom mirror)
			)
		)
		(fp_text user "Author: Antmicro"
			(at -0.939 -3.399 270)
			(layer "B.Fab")
			(effects
				(font
					(size 0.7 0.7)
					(thickness 0.15)
				)
				(justify left bottom mirror)
			)
		)
		(pad "1" smd roundrect
			(at -0.48 0 90)
			(size 0.59 0.64)
			(layers "B.Cu" "B.Mask" "B.Paste")
			(roundrect_rratio 0.25)
			(net 150 "+1V2")
			(pintype "passive")
		)
		(pad "2" smd roundrect
			(at 0.48 0 90)
			(size 0.59 0.64)
			(layers "B.Cu" "B.Mask" "B.Paste")
			(roundrect_rratio 0.25)
			(net 1 "GND")
			(pintype "passive")
		)
	)
	(footprint "antmicro-footprints:FB_0603_1608Metric"
		(layer "B.Cu")
		(at 139.325 138.007851 180)
		(property "Reference" "FB5"
			(at -3.931 -0.168149 0)
			(layer "B.SilkS")
			(effects
				(font
					(size 0.7 0.7)
					(thickness 0.15)
				)
				(justify left bottom mirror)
			)
		)
		(property "Value" "FB_120Z_2A_Murata-BLM18PG_0603"
			(at 0 -1.5 0)
			(layer "B.Fab")
			(effects
				(font
					(size 0.7 0.7)
					(thickness 0.15)
				)
				(justify left bottom mirror)
			)
		)
		(property "Datasheet" "https://www.murata.com/en-us/products/productdata/8796738650142/ENFA0003.pdf"
			(at 0 0 180)
			(layer "F.Fab")
			(hide yes)
			(effects
				(font
					(size 1.27 1.27)
					(thickness 0.15)
				)
			)
		)
		(property "Val" "120Z/2A"
			(at 0 0 180)
			(unlocked yes)
			(layer "B.Fab")
			(hide yes)
			(effects
				(font
					(size 1 1)
					(thickness 0.15)
				)
				(justify mirror)
			)
		)
		(property "MPN" "BLM18PG121SN1D"
			(at 0 0 180)
			(unlocked yes)
			(layer "B.Fab")
			(hide yes)
			(effects
				(font
					(size 1 1)
					(thickness 0.15)
				)
				(justify mirror)
			)
		)
		(property "Manufacturer" "Murata"
			(at 0 0 180)
			(unlocked yes)
			(layer "B.Fab")
			(hide yes)
			(effects
				(font
					(size 1 1)
					(thickness 0.15)
				)
				(justify mirror)
			)
		)
		(property "Author" "Antmicro"
			(at 0 0 180)
			(unlocked yes)
			(layer "B.Fab")
			(hide yes)
			(effects
				(font
					(size 1 1)
					(thickness 0.15)
				)
				(justify mirror)
			)
		)
		(property "License" "Apache-2.0"
			(at 0 0 180)
			(unlocked yes)
			(layer "B.Fab")
			(hide yes)
			(effects
				(font
					(size 1 1)
					(thickness 0.15)
				)
				(justify mirror)
			)
		)
		(sheetname "/Ethernet/")
		(sheetfile "ethernet.kicad_sch")
		(attr smd)
		(fp_line
			(start -0.15 0.4)
			(end 0.15 0.4)
			(stroke
				(width 0.15)
				(type solid)
			)
			(layer "B.SilkS")
		)
		(fp_line
			(start -0.15 -0.4)
			(end 0.15 -0.4)
			(stroke
				(width 0.15)
				(type solid)
			)
			(layer "B.SilkS")
		)
		(fp_rect
			(start -1.25 0.65)
			(end 1.25 -0.65)
			(stroke
				(width 0.05)
				(type solid)
			)
			(fill no)
			(layer "B.CrtYd")
		)
		(fp_line
			(start 0.8 0.408)
			(end 0.8 -0.406)
			(stroke
				(width 0.15)
				(type solid)
			)
			(layer "B.Fab")
		)
		(fp_line
			(start 0.8 0.408)
			(end -0.803 0.408)
			(stroke
				(width 0.15)
				(type solid)
			)
			(layer "B.Fab")
		)
		(fp_line
			(start 0.8 -0.406)
			(end -0.803 -0.406)
			(stroke
				(width 0.15)
				(type solid)
			)
			(layer "B.Fab")
		)
		(fp_line
			(start -0.803 -0.406)
			(end -0.803 0.408)
			(stroke
				(width 0.15)
				(type solid)
			)
			(layer "B.Fab")
		)
		(fp_text user "Author: Antmicro"
			(at -1.653 -3.162 0)
			(layer "B.Fab")
			(effects
				(font
					(size 0.7 0.7)
					(thickness 0.15)
				)
				(justify left bottom mirror)
			)
		)
		(fp_text user "License: Apache-2.0"
			(at -1.653 -5.9 0)
			(layer "B.Fab")
			(effects
				(font
					(size 0.7 0.7)
					(thickness 0.15)
				)
				(justify left bottom mirror)
			)
		)
		(fp_text user "${REFERENCE}"
			(at -1.653 -4.6 0)
			(layer "B.Fab")
			(effects
				(font
					(size 0.7 0.7)
					(thickness 0.15)
				)
				(justify left bottom mirror)
			)
		)
		(pad "1" smd roundrect
			(at -0.7 0 180)
			(size 0.8 1)
			(layers "B.Cu" "B.Mask" "B.Paste")
			(roundrect_rratio 0.2)
			(net 151 "+3V3")
			(pintype "passive")
		)
		(pad "2" smd roundrect
			(at 0.7 0 180)
			(size 0.8 1)
			(layers "B.Cu" "B.Mask" "B.Paste")
			(roundrect_rratio 0.2)
			(net 97 "/Ethernet/AVDDH")
			(pintype "passive")
		)
	)
	(footprint "antmicro-footprints:FB_0603_1608Metric"
		(layer "B.Cu")
		(at 134.211328 141.007157)
		(property "Reference" "FB4"
			(at 1.424672 0.470843 0)
			(layer "B.SilkS")
			(effects
				(font
					(size 0.7 0.7)
					(thickness 0.15)
				)
				(justify right bottom mirror)
			)
		)
		(property "Value" "FB_120Z_2A_Murata-BLM18PG_0603"
			(at 0 -1.5 0)
			(layer "B.Fab")
			(effects
				(font
					(size 0.7 0.7)
					(thickness 0.15)
				)
				(justify right bottom mirror)
			)
		)
		(property "Datasheet" "https://www.murata.com/en-us/products/productdata/8796738650142/ENFA0003.pdf"
			(at 0 0 0)
			(layer "F.Fab")
			(hide yes)
			(effects
				(font
					(size 1.27 1.27)
					(thickness 0.15)
				)
			)
		)
		(property "Val" "120Z/2A"
			(at 0 0 0)
			(unlocked yes)
			(layer "B.Fab")
			(hide yes)
			(effects
				(font
					(size 1 1)
					(thickness 0.15)
				)
				(justify mirror)
			)
		)
		(property "MPN" "BLM18PG121SN1D"
			(at 0 0 0)
			(unlocked yes)
			(layer "B.Fab")
			(hide yes)
			(effects
				(font
					(size 1 1)
					(thickness 0.15)
				)
				(justify mirror)
			)
		)
		(property "Manufacturer" "Murata"
			(at 0 0 0)
			(unlocked yes)
			(layer "B.Fab")
			(hide yes)
			(effects
				(font
					(size 1 1)
					(thickness 0.15)
				)
				(justify mirror)
			)
		)
		(property "Author" "Antmicro"
			(at 0 0 0)
			(unlocked yes)
			(layer "B.Fab")
			(hide yes)
			(effects
				(font
					(size 1 1)
					(thickness 0.15)
				)
				(justify mirror)
			)
		)
		(property "License" "Apache-2.0"
			(at 0 0 0)
			(unlocked yes)
			(layer "B.Fab")
			(hide yes)
			(effects
				(font
					(size 1 1)
					(thickness 0.15)
				)
				(justify mirror)
			)
		)
		(sheetname "/Ethernet/")
		(sheetfile "ethernet.kicad_sch")
		(attr smd)
		(fp_line
			(start -0.15 -0.4)
			(end 0.15 -0.4)
			(stroke
				(width 0.15)
				(type solid)
			)
			(layer "B.SilkS")
		)
		(fp_line
			(start -0.15 0.4)
			(end 0.15 0.4)
			(stroke
				(width 0.15)
				(type solid)
			)
			(layer "B.SilkS")
		)
		(fp_rect
			(start -1.25 0.65)
			(end 1.25 -0.65)
			(stroke
				(width 0.05)
				(type solid)
			)
			(fill no)
			(layer "B.CrtYd")
		)
		(fp_line
			(start -0.803 -0.406)
			(end -0.803 0.408)
			(stroke
				(width 0.15)
				(type solid)
			)
			(layer "B.Fab")
		)
		(fp_line
			(start 0.8 -0.406)
			(end -0.803 -0.406)
			(stroke
				(width 0.15)
				(type solid)
			)
			(layer "B.Fab")
		)
		(fp_line
			(start 0.8 0.408)
			(end -0.803 0.408)
			(stroke
				(width 0.15)
				(type solid)
			)
			(layer "B.Fab")
		)
		(fp_line
			(start 0.8 0.408)
			(end 0.8 -0.406)
			(stroke
				(width 0.15)
				(type solid)
			)
			(layer "B.Fab")
		)
		(fp_text user "Author: Antmicro"
			(at -1.653 -3.162 180)
			(layer "B.Fab")
			(effects
				(font
					(size 0.7 0.7)
					(thickness 0.15)
				)
				(justify left bottom mirror)
			)
		)
		(fp_text user "License: Apache-2.0"
			(at -1.653 -5.9 180)
			(layer "B.Fab")
			(effects
				(font
					(size 0.7 0.7)
					(thickness 0.15)
				)
				(justify left bottom mirror)
			)
		)
		(fp_text user "${REFERENCE}"
			(at -1.653 -4.6 180)
			(layer "B.Fab")
			(effects
				(font
					(size 0.7 0.7)
					(thickness 0.15)
				)
				(justify left bottom mirror)
			)
		)
		(pad "1" smd roundrect
			(at -0.7 0)
			(size 0.8 1)
			(layers "B.Cu" "B.Mask" "B.Paste")
			(roundrect_rratio 0.2)
			(net 150 "+1V2")
			(pintype "passive")
		)
		(pad "2" smd roundrect
			(at 0.7 0)
			(size 0.8 1)
			(layers "B.Cu" "B.Mask" "B.Paste")
			(roundrect_rratio 0.2)
			(net 95 "/Ethernet/AVDDL")
			(pintype "passive")
		)
	)
	(footprint "antmicro-footprints:R_0402_1005Metric"
		(layer "B.Cu")
		(at 106.874499 128.749 90)
		(descr "Resistor SMD 0402")
		(tags "resistor SMD 0402")
		(property "Reference" "R98"
			(at 1.495 0.313501 90)
			(layer "B.SilkS")
			(effects
				(font
					(size 0.7 0.7)
					(thickness 0.15)
				)
				(justify right bottom mirror)
			)
		)
		(property "Value" "R_220R_0402"
			(at -1.011843 -1.772047 90)
			(layer "B.Fab")
			(effects
				(font
					(size 0.7 0.7)
					(thickness 0.15)
				)
				(justify right bottom mirror)
			)
		)
		(property "Datasheet" "https://www.bourns.com/docs/product-datasheets/cr.pdf"
			(at 0 0 90)
			(layer "F.Fab")
			(hide yes)
			(effects
				(font
					(size 1.27 1.27)
					(thickness 0.15)
				)
			)
		)
		(property "Manufacturer" "Bourns"
			(at 0 0 90)
			(unlocked yes)
			(layer "B.Fab")
			(hide yes)
			(effects
				(font
					(size 1 1)
					(thickness 0.15)
				)
				(justify mirror)
			)
		)
		(property "MPN" "CR0402-FX-2200GLF"
			(at 0 0 90)
			(unlocked yes)
			(layer "B.Fab")
			(hide yes)
			(effects
				(font
					(size 1 1)
					(thickness 0.15)
				)
				(justify mirror)
			)
		)
		(property "Val" "220R"
			(at 0 0 90)
			(unlocked yes)
			(layer "B.Fab")
			(hide yes)
			(effects
				(font
					(size 1 1)
					(thickness 0.15)
				)
				(justify mirror)
			)
		)
		(property "License" "Apache-2.0"
			(at 0 0 90)
			(unlocked yes)
			(layer "B.Fab")
			(hide yes)
			(effects
				(font
					(size 1 1)
					(thickness 0.15)
				)
				(justify mirror)
			)
		)
		(property "Author" "Antmicro"
			(at 0 0 90)
			(unlocked yes)
			(layer "B.Fab")
			(hide yes)
			(effects
				(font
					(size 1 1)
					(thickness 0.15)
				)
				(justify mirror)
			)
		)
		(property "Tolerance" "1%"
			(at 0 0 90)
			(unlocked yes)
			(layer "B.Fab")
			(hide yes)
			(effects
				(font
					(size 1 1)
					(thickness 0.15)
				)
				(justify mirror)
			)
		)
		(sheetname "/Ethernet/")
		(sheetfile "ethernet.kicad_sch")
		(attr smd)
		(fp_rect
			(start -0.925 0.47)
			(end 0.925 -0.47)
			(stroke
				(width 0.05)
				(type default)
			)
			(fill no)
			(layer "B.CrtYd")
		)
		(fp_rect
			(start -0.5 0.25)
			(end 0.5 -0.25)
			(stroke
				(width 0.15)
				(type solid)
			)
			(fill no)
			(layer "B.Fab")
		)
		(fp_text user "Author: Antmicro"
			(at -0.95 -4.169 270)
			(layer "B.Fab")
			(effects
				(font
					(size 0.7 0.7)
					(thickness 0.15)
				)
				(justify left bottom mirror)
			)
		)
		(fp_text user "License: Apache-2.0"
			(at -0.95 -5.169 270)
			(layer "B.Fab")
			(effects
				(font
					(size 0.7 0.7)
					(thickness 0.15)
				)
				(justify left bottom mirror)
			)
		)
		(fp_text user "${REFERENCE}"
			(at -0.95 -3.168 270)
			(layer "B.Fab")
			(effects
				(font
					(size 0.7 0.7)
					(thickness 0.15)
				)
				(justify left bottom mirror)
			)
		)
		(pad "1" smd roundrect
			(at -0.48 0 90)
			(size 0.59 0.64)
			(layers "B.Cu" "B.Mask" "B.Paste")
			(roundrect_rratio 0.25)
			(net 824 "Net-(J6-LED_Y+)")
			(pintype "passive")
		)
		(pad "2" smd roundrect
			(at 0.48 0 90)
			(size 0.59 0.64)
			(layers "B.Cu" "B.Mask" "B.Paste")
			(roundrect_rratio 0.25)
			(net 151 "+3V3")
			(pintype "passive")
		)
	)
	(footprint "antmicro-footprints:R_0402_1005Metric"
		(layer "B.Cu")
		(at 106.895 122.335 -90)
		(descr "Resistor SMD 0402")
		(tags "resistor SMD 0402")
		(property "Reference" "R99"
			(at -3.209 -0.293 90)
			(layer "B.SilkS")
			(effects
				(font
					(size 0.7 0.7)
					(thickness 0.15)
				)
				(justify left bottom mirror)
			)
		)
		(property "Value" "R_220R_0402"
			(at -1.011843 -1.772047 90)
			(layer "B.Fab")
			(effects
				(font
					(size 0.7 0.7)
					(thickness 0.15)
				)
				(justify left bottom mirror)
			)
		)
		(property "Datasheet" "https://www.bourns.com/docs/product-datasheets/cr.pdf"
			(at 0 0 270)
			(layer "F.Fab")
			(hide yes)
			(effects
				(font
					(size 1.27 1.27)
					(thickness 0.15)
				)
			)
		)
		(property "Manufacturer" "Bourns"
			(at 0 0 270)
			(unlocked yes)
			(layer "B.Fab")
			(hide yes)
			(effects
				(font
					(size 1 1)
					(thickness 0.15)
				)
				(justify mirror)
			)
		)
		(property "MPN" "CR0402-FX-2200GLF"
			(at 0 0 270)
			(unlocked yes)
			(layer "B.Fab")
			(hide yes)
			(effects
				(font
					(size 1 1)
					(thickness 0.15)
				)
				(justify mirror)
			)
		)
		(property "Val" "220R"
			(at 0 0 270)
			(unlocked yes)
			(layer "B.Fab")
			(hide yes)
			(effects
				(font
					(size 1 1)
					(thickness 0.15)
				)
				(justify mirror)
			)
		)
		(property "License" "Apache-2.0"
			(at 0 0 270)
			(unlocked yes)
			(layer "B.Fab")
			(hide yes)
			(effects
				(font
					(size 1 1)
					(thickness 0.15)
				)
				(justify mirror)
			)
		)
		(property "Author" "Antmicro"
			(at 0 0 270)
			(unlocked yes)
			(layer "B.Fab")
			(hide yes)
			(effects
				(font
					(size 1 1)
					(thickness 0.15)
				)
				(justify mirror)
			)
		)
		(property "Tolerance" "1%"
			(at 0 0 270)
			(unlocked yes)
			(layer "B.Fab")
			(hide yes)
			(effects
				(font
					(size 1 1)
					(thickness 0.15)
				)
				(justify mirror)
			)
		)
		(sheetname "/Ethernet/")
		(sheetfile "ethernet.kicad_sch")
		(attr smd)
		(fp_rect
			(start -0.925 0.47)
			(end 0.925 -0.47)
			(stroke
				(width 0.05)
				(type default)
			)
			(fill no)
			(layer "B.CrtYd")
		)
		(fp_rect
			(start -0.5 0.25)
			(end 0.5 -0.25)
			(stroke
				(width 0.15)
				(type solid)
			)
			(fill no)
			(layer "B.Fab")
		)
		(fp_text user "${REFERENCE}"
			(at -0.95 -3.168 90)
			(layer "B.Fab")
			(effects
				(font
					(size 0.7 0.7)
					(thickness 0.15)
				)
				(justify left bottom mirror)
			)
		)
		(fp_text user "License: Apache-2.0"
			(at -0.95 -5.169 90)
			(layer "B.Fab")
			(effects
				(font
					(size 0.7 0.7)
					(thickness 0.15)
				)
				(justify left bottom mirror)
			)
		)
		(fp_text user "Author: Antmicro"
			(at -0.95 -4.169 90)
			(layer "B.Fab")
			(effects
				(font
					(size 0.7 0.7)
					(thickness 0.15)
				)
				(justify left bottom mirror)
			)
		)
		(pad "1" smd roundrect
			(at -0.48 0 270)
			(size 0.59 0.64)
			(layers "B.Cu" "B.Mask" "B.Paste")
			(roundrect_rratio 0.25)
			(net 823 "Net-(J6-LED_G+)")
			(pintype "passive")
		)
		(pad "2" smd roundrect
			(at 0.48 0 270)
			(size 0.59 0.64)
			(layers "B.Cu" "B.Mask" "B.Paste")
			(roundrect_rratio 0.25)
			(net 151 "+3V3")
			(pintype "passive")
		)
	)
	(footprint "antmicro-footprints:R_0402_1005Metric"
		(layer "B.Cu")
		(at 140.65 152.4 -90)
		(descr "Resistor SMD 0402")
		(tags "resistor SMD 0402")
		(property "Reference" "R113"
			(at 8 -0.375 90)
			(layer "B.SilkS")
			(effects
				(font
					(size 0.7 0.7)
					(thickness 0.15)
				)
				(justify left bottom mirror)
			)
		)
		(property "Value" "R_2k2_0402"
			(at -1.011843 -1.772047 90)
			(layer "B.Fab")
			(effects
				(font
					(size 0.7 0.7)
					(thickness 0.15)
				)
				(justify left bottom mirror)
			)
		)
		(property "Datasheet" "https://www.bourns.com/docs/product-datasheets/cr.pdf"
			(at 0 0 270)
			(layer "F.Fab")
			(hide yes)
			(effects
				(font
					(size 1.27 1.27)
					(thickness 0.15)
				)
			)
		)
		(property "Manufacturer" "Bourns"
			(at 0 0 270)
			(unlocked yes)
			(layer "B.Fab")
			(hide yes)
			(effects
				(font
					(size 1 1)
					(thickness 0.15)
				)
				(justify mirror)
			)
		)
		(property "MPN" "CR0402-FX-2201GLF"
			(at 0 0 270)
			(unlocked yes)
			(layer "B.Fab")
			(hide yes)
			(effects
				(font
					(size 1 1)
					(thickness 0.15)
				)
				(justify mirror)
			)
		)
		(property "Val" "2k2"
			(at 0 0 270)
			(unlocked yes)
			(layer "B.Fab")
			(hide yes)
			(effects
				(font
					(size 1 1)
					(thickness 0.15)
				)
				(justify mirror)
			)
		)
		(property "License" "Apache-2.0"
			(at 0 0 270)
			(unlocked yes)
			(layer "B.Fab")
			(hide yes)
			(effects
				(font
					(size 1 1)
					(thickness 0.15)
				)
				(justify mirror)
			)
		)
		(property "Author" "Antmicro"
			(at 0 0 270)
			(unlocked yes)
			(layer "B.Fab")
			(hide yes)
			(effects
				(font
					(size 1 1)
					(thickness 0.15)
				)
				(justify mirror)
			)
		)
		(property "Tolerance" "1%"
			(at 0 0 270)
			(unlocked yes)
			(layer "B.Fab")
			(hide yes)
			(effects
				(font
					(size 1 1)
					(thickness 0.15)
				)
				(justify mirror)
			)
		)
		(sheetname "/Ethernet/")
		(sheetfile "ethernet.kicad_sch")
		(attr smd)
		(fp_rect
			(start -0.925 0.47)
			(end 0.925 -0.47)
			(stroke
				(width 0.05)
				(type default)
			)
			(fill no)
			(layer "B.CrtYd")
		)
		(fp_rect
			(start -0.5 0.25)
			(end 0.5 -0.25)
			(stroke
				(width 0.15)
				(type solid)
			)
			(fill no)
			(layer "B.Fab")
		)
		(fp_text user "Author: Antmicro"
			(at -0.95 -4.169 90)
			(layer "B.Fab")
			(effects
				(font
					(size 0.7 0.7)
					(thickness 0.15)
				)
				(justify left bottom mirror)
			)
		)
		(fp_text user "License: Apache-2.0"
			(at -0.95 -5.169 90)
			(layer "B.Fab")
			(effects
				(font
					(size 0.7 0.7)
					(thickness 0.15)
				)
				(justify left bottom mirror)
			)
		)
		(fp_text user "${REFERENCE}"
			(at -0.95 -3.168 90)
			(layer "B.Fab")
			(effects
				(font
					(size 0.7 0.7)
					(thickness 0.15)
				)
				(justify left bottom mirror)
			)
		)
		(pad "1" smd roundrect
			(at -0.48 0 270)
			(size 0.59 0.64)
			(layers "B.Cu" "B.Mask" "B.Paste")
			(roundrect_rratio 0.25)
			(net 393 "/Ethernet/ETH.RXD0")
			(pintype "passive")
		)
		(pad "2" smd roundrect
			(at 0.48 0 270)
			(size 0.59 0.64)
			(layers "B.Cu" "B.Mask" "B.Paste")
			(roundrect_rratio 0.25)
			(net 1 "GND")
			(pintype "passive")
		)
	)
	(footprint "antmicro-footprints:R_0402_1005Metric"
		(layer "B.Cu")
		(at 139.22 148.17 180)
		(descr "Resistor SMD 0402")
		(tags "resistor SMD 0402")
		(property "Reference" "R110"
			(at -3.62 -0.46 0)
			(layer "B.SilkS")
			(effects
				(font
					(size 0.7 0.7)
					(thickness 0.15)
				)
				(justify left bottom mirror)
			)
		)
		(property "Value" "R_1k_0402"
			(at -1.011843 -1.772047 0)
			(layer "B.Fab")
			(effects
				(font
					(size 0.7 0.7)
					(thickness 0.15)
				)
				(justify left bottom mirror)
			)
		)
		(property "Datasheet" "https://www.bourns.com/docs/product-datasheets/cr.pdf"
			(at 0 0 180)
			(layer "F.Fab")
			(hide yes)
			(effects
				(font
					(size 1.27 1.27)
					(thickness 0.15)
				)
			)
		)
		(property "Manufacturer" "Bourns"
			(at 0 0 180)
			(unlocked yes)
			(layer "B.Fab")
			(hide yes)
			(effects
				(font
					(size 1 1)
					(thickness 0.15)
				)
				(justify mirror)
			)
		)
		(property "MPN" "CR0402-FX-1001GLF"
			(at 0 0 180)
			(unlocked yes)
			(layer "B.Fab")
			(hide yes)
			(effects
				(font
					(size 1 1)
					(thickness 0.15)
				)
				(justify mirror)
			)
		)
		(property "Val" "1k"
			(at 0 0 180)
			(unlocked yes)
			(layer "B.Fab")
			(hide yes)
			(effects
				(font
					(size 1 1)
					(thickness 0.15)
				)
				(justify mirror)
			)
		)
		(property "License" "Apache-2.0"
			(at 0 0 180)
			(unlocked yes)
			(layer "B.Fab")
			(hide yes)
			(effects
				(font
					(size 1 1)
					(thickness 0.15)
				)
				(justify mirror)
			)
		)
		(property "Author" "Antmicro"
			(at 0 0 180)
			(unlocked yes)
			(layer "B.Fab")
			(hide yes)
			(effects
				(font
					(size 1 1)
					(thickness 0.15)
				)
				(justify mirror)
			)
		)
		(property "Tolerance" "1%"
			(at 0 0 180)
			(unlocked yes)
			(layer "B.Fab")
			(hide yes)
			(effects
				(font
					(size 1 1)
					(thickness 0.15)
				)
				(justify mirror)
			)
		)
		(sheetname "/Ethernet/")
		(sheetfile "ethernet.kicad_sch")
		(attr smd)
		(fp_rect
			(start -0.925 0.47)
			(end 0.925 -0.47)
			(stroke
				(width 0.05)
				(type default)
			)
			(fill no)
			(layer "B.CrtYd")
		)
		(fp_rect
			(start -0.5 0.25)
			(end 0.5 -0.25)
			(stroke
				(width 0.15)
				(type solid)
			)
			(fill no)
			(layer "B.Fab")
		)
		(fp_text user "${REFERENCE}"
			(at -0.95 -3.168 0)
			(layer "B.Fab")
			(effects
				(font
					(size 0.7 0.7)
					(thickness 0.15)
				)
				(justify left bottom mirror)
			)
		)
		(fp_text user "Author: Antmicro"
			(at -0.95 -4.169 0)
			(layer "B.Fab")
			(effects
				(font
					(size 0.7 0.7)
					(thickness 0.15)
				)
				(justify left bottom mirror)
			)
		)
		(fp_text user "License: Apache-2.0"
			(at -0.95 -5.169 0)
			(layer "B.Fab")
			(effects
				(font
					(size 0.7 0.7)
					(thickness 0.15)
				)
				(justify left bottom mirror)
			)
		)
		(pad "1" smd roundrect
			(at -0.48 0 180)
			(size 0.59 0.64)
			(layers "B.Cu" "B.Mask" "B.Paste")
			(roundrect_rratio 0.25)
			(net 400 "/Ethernet/ETH.MDIO")
			(pintype "passive")
		)
		(pad "2" smd roundrect
			(at 0.48 0 180)
			(size 0.59 0.64)
			(layers "B.Cu" "B.Mask" "B.Paste")
			(roundrect_rratio 0.25)
			(net 797 "+1V8")
			(pintype "passive")
		)
	)
	(footprint "antmicro-footprints:R_0402_1005Metric"
		(layer "B.Cu")
		(at 138.55 152.4 -90)
		(descr "Resistor SMD 0402")
		(tags "resistor SMD 0402")
		(property "Reference" "R115"
			(at 8 -0.375 90)
			(layer "B.SilkS")
			(effects
				(font
					(size 0.7 0.7)
					(thickness 0.15)
				)
				(justify left bottom mirror)
			)
		)
		(property "Value" "R_2k2_0402"
			(at -1.011843 -1.772047 90)
			(layer "B.Fab")
			(effects
				(font
					(size 0.7 0.7)
					(thickness 0.15)
				)
				(justify left bottom mirror)
			)
		)
		(property "Datasheet" "https://www.bourns.com/docs/product-datasheets/cr.pdf"
			(at 0 0 270)
			(layer "F.Fab")
			(hide yes)
			(effects
				(font
					(size 1.27 1.27)
					(thickness 0.15)
				)
			)
		)
		(property "Manufacturer" "Bourns"
			(at 0 0 270)
			(unlocked yes)
			(layer "B.Fab")
			(hide yes)
			(effects
				(font
					(size 1 1)
					(thickness 0.15)
				)
				(justify mirror)
			)
		)
		(property "MPN" "CR0402-FX-2201GLF"
			(at 0 0 270)
			(unlocked yes)
			(layer "B.Fab")
			(hide yes)
			(effects
				(font
					(size 1 1)
					(thickness 0.15)
				)
				(justify mirror)
			)
		)
		(property "Val" "2k2"
			(at 0 0 270)
			(unlocked yes)
			(layer "B.Fab")
			(hide yes)
			(effects
				(font
					(size 1 1)
					(thickness 0.15)
				)
				(justify mirror)
			)
		)
		(property "License" "Apache-2.0"
			(at 0 0 270)
			(unlocked yes)
			(layer "B.Fab")
			(hide yes)
			(effects
				(font
					(size 1 1)
					(thickness 0.15)
				)
				(justify mirror)
			)
		)
		(property "Author" "Antmicro"
			(at 0 0 270)
			(unlocked yes)
			(layer "B.Fab")
			(hide yes)
			(effects
				(font
					(size 1 1)
					(thickness 0.15)
				)
				(justify mirror)
			)
		)
		(property "Tolerance" "1%"
			(at 0 0 270)
			(unlocked yes)
			(layer "B.Fab")
			(hide yes)
			(effects
				(font
					(size 1 1)
					(thickness 0.15)
				)
				(justify mirror)
			)
		)
		(sheetname "/Ethernet/")
		(sheetfile "ethernet.kicad_sch")
		(attr smd exclude_from_bom dnp)
		(fp_rect
			(start -0.925 0.47)
			(end 0.925 -0.47)
			(stroke
				(width 0.05)
				(type default)
			)
			(fill no)
			(layer "B.CrtYd")
		)
		(fp_rect
			(start -0.5 0.25)
			(end 0.5 -0.25)
			(stroke
				(width 0.15)
				(type solid)
			)
			(fill no)
			(layer "B.Fab")
		)
		(fp_text user "License: Apache-2.0"
			(at -0.95 -5.169 90)
			(layer "B.Fab")
			(effects
				(font
					(size 0.7 0.7)
					(thickness 0.15)
				)
				(justify left bottom mirror)
			)
		)
		(fp_text user "${REFERENCE}"
			(at -0.95 -3.168 90)
			(layer "B.Fab")
			(effects
				(font
					(size 0.7 0.7)
					(thickness 0.15)
				)
				(justify left bottom mirror)
			)
		)
		(fp_text user "Author: Antmicro"
			(at -0.95 -4.169 90)
			(layer "B.Fab")
			(effects
				(font
					(size 0.7 0.7)
					(thickness 0.15)
				)
				(justify left bottom mirror)
			)
		)
		(pad "1" smd roundrect
			(at -0.48 0 270)
			(size 0.59 0.64)
			(layers "B.Cu" "B.Mask" "B.Paste")
			(roundrect_rratio 0.25)
			(net 395 "/Ethernet/ETH.RXD2")
			(pintype "passive")
		)
		(pad "2" smd roundrect
			(at 0.48 0 270)
			(size 0.59 0.64)
			(layers "B.Cu" "B.Mask" "B.Paste")
			(roundrect_rratio 0.25)
			(net 1 "GND")
			(pintype "passive")
		)
	)
	(footprint "antmicro-footprints:R_0402_1005Metric"
		(layer "B.Cu")
		(at 142.75 152.4 -90)
		(descr "Resistor SMD 0402")
		(tags "resistor SMD 0402")
		(property "Reference" "R117"
			(at 8 -0.375 90)
			(layer "B.SilkS")
			(effects
				(font
					(size 0.7 0.7)
					(thickness 0.15)
				)
				(justify left bottom mirror)
			)
		)
		(property "Value" "R_2k2_0402"
			(at -1.011843 -1.772047 90)
			(layer "B.Fab")
			(effects
				(font
					(size 0.7 0.7)
					(thickness 0.15)
				)
				(justify left bottom mirror)
			)
		)
		(property "Datasheet" "https://www.bourns.com/docs/product-datasheets/cr.pdf"
			(at 0 0 270)
			(layer "F.Fab")
			(hide yes)
			(effects
				(font
					(size 1.27 1.27)
					(thickness 0.15)
				)
			)
		)
		(property "Manufacturer" "Bourns"
			(at 0 0 270)
			(unlocked yes)
			(layer "B.Fab")
			(hide yes)
			(effects
				(font
					(size 1 1)
					(thickness 0.15)
				)
				(justify mirror)
			)
		)
		(property "MPN" "CR0402-FX-2201GLF"
			(at 0 0 270)
			(unlocked yes)
			(layer "B.Fab")
			(hide yes)
			(effects
				(font
					(size 1 1)
					(thickness 0.15)
				)
				(justify mirror)
			)
		)
		(property "Val" "2k2"
			(at 0 0 270)
			(unlocked yes)
			(layer "B.Fab")
			(hide yes)
			(effects
				(font
					(size 1 1)
					(thickness 0.15)
				)
				(justify mirror)
			)
		)
		(property "License" "Apache-2.0"
			(at 0 0 270)
			(unlocked yes)
			(layer "B.Fab")
			(hide yes)
			(effects
				(font
					(size 1 1)
					(thickness 0.15)
				)
				(justify mirror)
			)
		)
		(property "Author" "Antmicro"
			(at 0 0 270)
			(unlocked yes)
			(layer "B.Fab")
			(hide yes)
			(effects
				(font
					(size 1 1)
					(thickness 0.15)
				)
				(justify mirror)
			)
		)
		(property "Tolerance" "1%"
			(at 0 0 270)
			(unlocked yes)
			(layer "B.Fab")
			(hide yes)
			(effects
				(font
					(size 1 1)
					(thickness 0.15)
				)
				(justify mirror)
			)
		)
		(sheetname "/Ethernet/")
		(sheetfile "ethernet.kicad_sch")
		(attr smd)
		(fp_rect
			(start -0.925 0.47)
			(end 0.925 -0.47)
			(stroke
				(width 0.05)
				(type default)
			)
			(fill no)
			(layer "B.CrtYd")
		)
		(fp_rect
			(start -0.5 0.25)
			(end 0.5 -0.25)
			(stroke
				(width 0.15)
				(type solid)
			)
			(fill no)
			(layer "B.Fab")
		)
		(fp_text user "Author: Antmicro"
			(at -0.95 -4.169 90)
			(layer "B.Fab")
			(effects
				(font
					(size 0.7 0.7)
					(thickness 0.15)
				)
				(justify left bottom mirror)
			)
		)
		(fp_text user "License: Apache-2.0"
			(at -0.95 -5.169 90)
			(layer "B.Fab")
			(effects
				(font
					(size 0.7 0.7)
					(thickness 0.15)
				)
				(justify left bottom mirror)
			)
		)
		(fp_text user "${REFERENCE}"
			(at -0.95 -3.168 90)
			(layer "B.Fab")
			(effects
				(font
					(size 0.7 0.7)
					(thickness 0.15)
				)
				(justify left bottom mirror)
			)
		)
		(pad "1" smd roundrect
			(at -0.48 0 270)
			(size 0.59 0.64)
			(layers "B.Cu" "B.Mask" "B.Paste")
			(roundrect_rratio 0.25)
			(net 397 "/Ethernet/ETH.RX_CTL")
			(pintype "passive")
		)
		(pad "2" smd roundrect
			(at 0.48 0 270)
			(size 0.59 0.64)
			(layers "B.Cu" "B.Mask" "B.Paste")
			(roundrect_rratio 0.25)
			(net 1 "GND")
			(pintype "passive")
		)
	)
	(footprint "antmicro-footprints:R_0402_1005Metric"
		(layer "B.Cu")
		(at 141.675 152.4 -90)
		(descr "Resistor SMD 0402")
		(tags "resistor SMD 0402")
		(property "Reference" "R118"
			(at 8 -0.375 90)
			(layer "B.SilkS")
			(effects
				(font
					(size 0.7 0.7)
					(thickness 0.15)
				)
				(justify left bottom mirror)
			)
		)
		(property "Value" "R_2k2_0402"
			(at -1.011843 -1.772047 90)
			(layer "B.Fab")
			(effects
				(font
					(size 0.7 0.7)
					(thickness 0.15)
				)
				(justify left bottom mirror)
			)
		)
		(property "Datasheet" "https://www.bourns.com/docs/product-datasheets/cr.pdf"
			(at 0 0 270)
			(layer "F.Fab")
			(hide yes)
			(effects
				(font
					(size 1.27 1.27)
					(thickness 0.15)
				)
			)
		)
		(property "Manufacturer" "Bourns"
			(at 0 0 270)
			(unlocked yes)
			(layer "B.Fab")
			(hide yes)
			(effects
				(font
					(size 1 1)
					(thickness 0.15)
				)
				(justify mirror)
			)
		)
		(property "MPN" "CR0402-FX-2201GLF"
			(at 0 0 270)
			(unlocked yes)
			(layer "B.Fab")
			(hide yes)
			(effects
				(font
					(size 1 1)
					(thickness 0.15)
				)
				(justify mirror)
			)
		)
		(property "Val" "2k2"
			(at 0 0 270)
			(unlocked yes)
			(layer "B.Fab")
			(hide yes)
			(effects
				(font
					(size 1 1)
					(thickness 0.15)
				)
				(justify mirror)
			)
		)
		(property "License" "Apache-2.0"
			(at 0 0 270)
			(unlocked yes)
			(layer "B.Fab")
			(hide yes)
			(effects
				(font
					(size 1 1)
					(thickness 0.15)
				)
				(justify mirror)
			)
		)
		(property "Author" "Antmicro"
			(at 0 0 270)
			(unlocked yes)
			(layer "B.Fab")
			(hide yes)
			(effects
				(font
					(size 1 1)
					(thickness 0.15)
				)
				(justify mirror)
			)
		)
		(property "Tolerance" "1%"
			(at 0 0 270)
			(unlocked yes)
			(layer "B.Fab")
			(hide yes)
			(effects
				(font
					(size 1 1)
					(thickness 0.15)
				)
				(justify mirror)
			)
		)
		(sheetname "/Ethernet/")
		(sheetfile "ethernet.kicad_sch")
		(attr smd)
		(fp_rect
			(start -0.925 0.47)
			(end 0.925 -0.47)
			(stroke
				(width 0.05)
				(type default)
			)
			(fill no)
			(layer "B.CrtYd")
		)
		(fp_rect
			(start -0.5 0.25)
			(end 0.5 -0.25)
			(stroke
				(width 0.15)
				(type solid)
			)
			(fill no)
			(layer "B.Fab")
		)
		(fp_text user "${REFERENCE}"
			(at -0.95 -3.168 90)
			(layer "B.Fab")
			(effects
				(font
					(size 0.7 0.7)
					(thickness 0.15)
				)
				(justify left bottom mirror)
			)
		)
		(fp_text user "Author: Antmicro"
			(at -0.95 -4.169 90)
			(layer "B.Fab")
			(effects
				(font
					(size 0.7 0.7)
					(thickness 0.15)
				)
				(justify left bottom mirror)
			)
		)
		(fp_text user "License: Apache-2.0"
			(at -0.95 -5.169 90)
			(layer "B.Fab")
			(effects
				(font
					(size 0.7 0.7)
					(thickness 0.15)
				)
				(justify left bottom mirror)
			)
		)
		(pad "1" smd roundrect
			(at -0.48 0 270)
			(size 0.59 0.64)
			(layers "B.Cu" "B.Mask" "B.Paste")
			(roundrect_rratio 0.25)
			(net 398 "/Ethernet/ETH.RXC")
			(pintype "passive")
		)
		(pad "2" smd roundrect
			(at 0.48 0 270)
			(size 0.59 0.64)
			(layers "B.Cu" "B.Mask" "B.Paste")
			(roundrect_rratio 0.25)
			(net 1 "GND")
			(pintype "passive")
		)
	)
	(footprint "antmicro-footprints:R_0402_1005Metric"
		(layer "B.Cu")
		(at 135.383171 143.399 90)
		(descr "Resistor SMD 0402")
		(tags "resistor SMD 0402")
		(property "Reference" "R119"
			(at -1.701 -3.603171 90)
			(layer "B.SilkS")
			(hide yes)
			(effects
				(font
					(size 0.7 0.7)
					(thickness 0.15)
				)
				(justify right bottom mirror)
			)
		)
		(property "Value" "R_2k2_0402"
			(at -1.011843 -1.772047 90)
			(layer "B.Fab")
			(effects
				(font
					(size 0.7 0.7)
					(thickness 0.15)
				)
				(justify right bottom mirror)
			)
		)
		(property "Datasheet" "https://www.bourns.com/docs/product-datasheets/cr.pdf"
			(at 0 0 90)
			(layer "F.Fab")
			(hide yes)
			(effects
				(font
					(size 1.27 1.27)
					(thickness 0.15)
				)
			)
		)
		(property "Manufacturer" "Bourns"
			(at 0 0 90)
			(unlocked yes)
			(layer "B.Fab")
			(hide yes)
			(effects
				(font
					(size 1 1)
					(thickness 0.15)
				)
				(justify mirror)
			)
		)
		(property "MPN" "CR0402-FX-2201GLF"
			(at 0 0 90)
			(unlocked yes)
			(layer "B.Fab")
			(hide yes)
			(effects
				(font
					(size 1 1)
					(thickness 0.15)
				)
				(justify mirror)
			)
		)
		(property "Val" "2k2"
			(at 0 0 90)
			(unlocked yes)
			(layer "B.Fab")
			(hide yes)
			(effects
				(font
					(size 1 1)
					(thickness 0.15)
				)
				(justify mirror)
			)
		)
		(property "License" "Apache-2.0"
			(at 0 0 90)
			(unlocked yes)
			(layer "B.Fab")
			(hide yes)
			(effects
				(font
					(size 1 1)
					(thickness 0.15)
				)
				(justify mirror)
			)
		)
		(property "Author" "Antmicro"
			(at 0 0 90)
			(unlocked yes)
			(layer "B.Fab")
			(hide yes)
			(effects
				(font
					(size 1 1)
					(thickness 0.15)
				)
				(justify mirror)
			)
		)
		(property "Tolerance" "1%"
			(at 0 0 90)
			(unlocked yes)
			(layer "B.Fab")
			(hide yes)
			(effects
				(font
					(size 1 1)
					(thickness 0.15)
				)
				(justify mirror)
			)
		)
		(sheetname "/Ethernet/")
		(sheetfile "ethernet.kicad_sch")
		(attr smd exclude_from_bom dnp)
		(fp_rect
			(start -0.925 0.47)
			(end 0.925 -0.47)
			(stroke
				(width 0.05)
				(type default)
			)
			(fill no)
			(layer "B.CrtYd")
		)
		(fp_rect
			(start -0.5 0.25)
			(end 0.5 -0.25)
			(stroke
				(width 0.15)
				(type solid)
			)
			(fill no)
			(layer "B.Fab")
		)
		(fp_text user "Author: Antmicro"
			(at -0.95 -4.169 270)
			(layer "B.Fab")
			(effects
				(font
					(size 0.7 0.7)
					(thickness 0.15)
				)
				(justify left bottom mirror)
			)
		)
		(fp_text user "License: Apache-2.0"
			(at -0.95 -5.169 270)
			(layer "B.Fab")
			(effects
				(font
					(size 0.7 0.7)
					(thickness 0.15)
				)
				(justify left bottom mirror)
			)
		)
		(fp_text user "${REFERENCE}"
			(at -0.95 -3.168 270)
			(layer "B.Fab")
			(effects
				(font
					(size 0.7 0.7)
					(thickness 0.15)
				)
				(justify left bottom mirror)
			)
		)
		(pad "1" smd roundrect
			(at -0.48 0 90)
			(size 0.59 0.64)
			(layers "B.Cu" "B.Mask" "B.Paste")
			(roundrect_rratio 0.25)
			(net 399 "/Ethernet/ETH.REF_CLK")
			(pintype "passive")
		)
		(pad "2" smd roundrect
			(at 0.48 0 90)
			(size 0.59 0.64)
			(layers "B.Cu" "B.Mask" "B.Paste")
			(roundrect_rratio 0.25)
			(net 1 "GND")
			(pintype "passive")
		)
	)
	(footprint "antmicro-footprints:R_0402_1005Metric"
		(layer "B.Cu")
		(at 126.805 139.802149 90)
		(descr "Resistor SMD 0402")
		(tags "resistor SMD 0402")
		(property "Reference" "R120"
			(at -0.659851 -1.837 90)
			(layer "B.SilkS")
			(effects
				(font
					(size 0.7 0.7)
					(thickness 0.15)
				)
				(justify right bottom mirror)
			)
		)
		(property "Value" "R_2k2_0402"
			(at -1.011843 -1.772047 90)
			(layer "B.Fab")
			(effects
				(font
					(size 0.7 0.7)
					(thickness 0.15)
				)
				(justify right bottom mirror)
			)
		)
		(property "Datasheet" "https://www.bourns.com/docs/product-datasheets/cr.pdf"
			(at 0 0 90)
			(layer "F.Fab")
			(hide yes)
			(effects
				(font
					(size 1.27 1.27)
					(thickness 0.15)
				)
			)
		)
		(property "Manufacturer" "Bourns"
			(at 0 0 90)
			(unlocked yes)
			(layer "B.Fab")
			(hide yes)
			(effects
				(font
					(size 1 1)
					(thickness 0.15)
				)
				(justify mirror)
			)
		)
		(property "MPN" "CR0402-FX-2201GLF"
			(at 0 0 90)
			(unlocked yes)
			(layer "B.Fab")
			(hide yes)
			(effects
				(font
					(size 1 1)
					(thickness 0.15)
				)
				(justify mirror)
			)
		)
		(property "Val" "2k2"
			(at 0 0 90)
			(unlocked yes)
			(layer "B.Fab")
			(hide yes)
			(effects
				(font
					(size 1 1)
					(thickness 0.15)
				)
				(justify mirror)
			)
		)
		(property "License" "Apache-2.0"
			(at 0 0 90)
			(unlocked yes)
			(layer "B.Fab")
			(hide yes)
			(effects
				(font
					(size 1 1)
					(thickness 0.15)
				)
				(justify mirror)
			)
		)
		(property "Author" "Antmicro"
			(at 0 0 90)
			(unlocked yes)
			(layer "B.Fab")
			(hide yes)
			(effects
				(font
					(size 1 1)
					(thickness 0.15)
				)
				(justify mirror)
			)
		)
		(property "Tolerance" "1%"
			(at 0 0 90)
			(unlocked yes)
			(layer "B.Fab")
			(hide yes)
			(effects
				(font
					(size 1 1)
					(thickness 0.15)
				)
				(justify mirror)
			)
		)
		(sheetname "/Ethernet/")
		(sheetfile "ethernet.kicad_sch")
		(attr smd exclude_from_bom dnp)
		(fp_rect
			(start -0.925 0.47)
			(end 0.925 -0.47)
			(stroke
				(width 0.05)
				(type default)
			)
			(fill no)
			(layer "B.CrtYd")
		)
		(fp_rect
			(start -0.5 0.25)
			(end 0.5 -0.25)
			(stroke
				(width 0.15)
				(type solid)
			)
			(fill no)
			(layer "B.Fab")
		)
		(fp_text user "Author: Antmicro"
			(at -0.95 -4.169 270)
			(layer "B.Fab")
			(effects
				(font
					(size 0.7 0.7)
					(thickness 0.15)
				)
				(justify left bottom mirror)
			)
		)
		(fp_text user "${REFERENCE}"
			(at -0.95 -3.168 270)
			(layer "B.Fab")
			(effects
				(font
					(size 0.7 0.7)
					(thickness 0.15)
				)
				(justify left bottom mirror)
			)
		)
		(fp_text user "License: Apache-2.0"
			(at -0.95 -5.169 270)
			(layer "B.Fab")
			(effects
				(font
					(size 0.7 0.7)
					(thickness 0.15)
				)
				(justify left bottom mirror)
			)
		)
		(pad "1" smd roundrect
			(at -0.48 0 90)
			(size 0.59 0.64)
			(layers "B.Cu" "B.Mask" "B.Paste")
			(roundrect_rratio 0.25)
			(net 330 "/Ethernet/LED_SPD")
			(pintype "passive")
		)
		(pad "2" smd roundrect
			(at 0.48 0 90)
			(size 0.59 0.64)
			(layers "B.Cu" "B.Mask" "B.Paste")
			(roundrect_rratio 0.25)
			(net 1 "GND")
			(pintype "passive")
		)
	)
	(footprint "antmicro-footprints:R_0402_1005Metric"
		(layer "B.Cu")
		(at 126.805 144.212149 -90)
		(descr "Resistor SMD 0402")
		(tags "resistor SMD 0402")
		(property "Reference" "R121"
			(at -0.702149 1.837 90)
			(layer "B.SilkS")
			(effects
				(font
					(size 0.7 0.7)
					(thickness 0.15)
				)
				(justify left bottom mirror)
			)
		)
		(property "Value" "R_2k2_0402"
			(at -1.011843 -1.772047 90)
			(layer "B.Fab")
			(effects
				(font
					(size 0.7 0.7)
					(thickness 0.15)
				)
				(justify left bottom mirror)
			)
		)
		(property "Datasheet" "https://www.bourns.com/docs/product-datasheets/cr.pdf"
			(at 0 0 270)
			(layer "F.Fab")
			(hide yes)
			(effects
				(font
					(size 1.27 1.27)
					(thickness 0.15)
				)
			)
		)
		(property "Manufacturer" "Bourns"
			(at 0 0 270)
			(unlocked yes)
			(layer "B.Fab")
			(hide yes)
			(effects
				(font
					(size 1 1)
					(thickness 0.15)
				)
				(justify mirror)
			)
		)
		(property "MPN" "CR0402-FX-2201GLF"
			(at 0 0 270)
			(unlocked yes)
			(layer "B.Fab")
			(hide yes)
			(effects
				(font
					(size 1 1)
					(thickness 0.15)
				)
				(justify mirror)
			)
		)
		(property "Val" "2k2"
			(at 0 0 270)
			(unlocked yes)
			(layer "B.Fab")
			(hide yes)
			(effects
				(font
					(size 1 1)
					(thickness 0.15)
				)
				(justify mirror)
			)
		)
		(property "License" "Apache-2.0"
			(at 0 0 270)
			(unlocked yes)
			(layer "B.Fab")
			(hide yes)
			(effects
				(font
					(size 1 1)
					(thickness 0.15)
				)
				(justify mirror)
			)
		)
		(property "Author" "Antmicro"
			(at 0 0 270)
			(unlocked yes)
			(layer "B.Fab")
			(hide yes)
			(effects
				(font
					(size 1 1)
					(thickness 0.15)
				)
				(justify mirror)
			)
		)
		(property "Tolerance" "1%"
			(at 0 0 270)
			(unlocked yes)
			(layer "B.Fab")
			(hide yes)
			(effects
				(font
					(size 1 1)
					(thickness 0.15)
				)
				(justify mirror)
			)
		)
		(sheetname "/Ethernet/")
		(sheetfile "ethernet.kicad_sch")
		(attr smd exclude_from_bom dnp)
		(fp_rect
			(start -0.925 0.47)
			(end 0.925 -0.47)
			(stroke
				(width 0.05)
				(type default)
			)
			(fill no)
			(layer "B.CrtYd")
		)
		(fp_rect
			(start -0.5 0.25)
			(end 0.5 -0.25)
			(stroke
				(width 0.15)
				(type solid)
			)
			(fill no)
			(layer "B.Fab")
		)
		(fp_text user "Author: Antmicro"
			(at -0.95 -4.169 90)
			(layer "B.Fab")
			(effects
				(font
					(size 0.7 0.7)
					(thickness 0.15)
				)
				(justify left bottom mirror)
			)
		)
		(fp_text user "License: Apache-2.0"
			(at -0.95 -5.169 90)
			(layer "B.Fab")
			(effects
				(font
					(size 0.7 0.7)
					(thickness 0.15)
				)
				(justify left bottom mirror)
			)
		)
		(fp_text user "${REFERENCE}"
			(at -0.95 -3.168 90)
			(layer "B.Fab")
			(effects
				(font
					(size 0.7 0.7)
					(thickness 0.15)
				)
				(justify left bottom mirror)
			)
		)
		(pad "1" smd roundrect
			(at -0.48 0 270)
			(size 0.59 0.64)
			(layers "B.Cu" "B.Mask" "B.Paste")
			(roundrect_rratio 0.25)
			(net 331 "/Ethernet/LED_LINK")
			(pintype "passive")
		)
		(pad "2" smd roundrect
			(at 0.48 0 270)
			(size 0.59 0.64)
			(layers "B.Cu" "B.Mask" "B.Paste")
			(roundrect_rratio 0.25)
			(net 1 "GND")
			(pintype "passive")
		)
	)
	(footprint "antmicro-footprints:R_0402_1005Metric"
		(layer "B.Cu")
		(at 137.5 150.025 90)
		(descr "Resistor SMD 0402")
		(tags "resistor SMD 0402")
		(property "Reference" "R104"
			(at -10.375 0.409 90)
			(layer "B.SilkS")
			(effects
				(font
					(size 0.7 0.7)
					(thickness 0.15)
				)
				(justify right bottom mirror)
			)
		)
		(property "Value" "R_10k_0402"
			(at -1.011843 -1.772047 90)
			(layer "B.Fab")
			(effects
				(font
					(size 0.7 0.7)
					(thickness 0.15)
				)
				(justify right bottom mirror)
			)
		)
		(property "Datasheet" "https://www.bourns.com/docs/product-datasheets/cr.pdf"
			(at 0 0 90)
			(layer "F.Fab")
			(hide yes)
			(effects
				(font
					(size 1.27 1.27)
					(thickness 0.15)
				)
			)
		)
		(property "Manufacturer" "Bourns"
			(at 0 0 90)
			(unlocked yes)
			(layer "B.Fab")
			(hide yes)
			(effects
				(font
					(size 1 1)
					(thickness 0.15)
				)
				(justify mirror)
			)
		)
		(property "MPN" "CR0402-FX-1002GLF"
			(at 0 0 90)
			(unlocked yes)
			(layer "B.Fab")
			(hide yes)
			(effects
				(font
					(size 1 1)
					(thickness 0.15)
				)
				(justify mirror)
			)
		)
		(property "Val" "10k"
			(at 0 0 90)
			(unlocked yes)
			(layer "B.Fab")
			(hide yes)
			(effects
				(font
					(size 1 1)
					(thickness 0.15)
				)
				(justify mirror)
			)
		)
		(property "License" "Apache-2.0"
			(at 0 0 90)
			(unlocked yes)
			(layer "B.Fab")
			(hide yes)
			(effects
				(font
					(size 1 1)
					(thickness 0.15)
				)
				(justify mirror)
			)
		)
		(property "Author" "Antmicro"
			(at 0 0 90)
			(unlocked yes)
			(layer "B.Fab")
			(hide yes)
			(effects
				(font
					(size 1 1)
					(thickness 0.15)
				)
				(justify mirror)
			)
		)
		(property "Tolerance" "1%"
			(at 0 0 90)
			(unlocked yes)
			(layer "B.Fab")
			(hide yes)
			(effects
				(font
					(size 1 1)
					(thickness 0.15)
				)
				(justify mirror)
			)
		)
		(sheetname "/Ethernet/")
		(sheetfile "ethernet.kicad_sch")
		(attr smd)
		(fp_rect
			(start -0.925 0.47)
			(end 0.925 -0.47)
			(stroke
				(width 0.05)
				(type default)
			)
			(fill no)
			(layer "B.CrtYd")
		)
		(fp_rect
			(start -0.5 0.25)
			(end 0.5 -0.25)
			(stroke
				(width 0.15)
				(type solid)
			)
			(fill no)
			(layer "B.Fab")
		)
		(fp_text user "${REFERENCE}"
			(at -0.95 -3.168 270)
			(layer "B.Fab")
			(effects
				(font
					(size 0.7 0.7)
					(thickness 0.15)
				)
				(justify left bottom mirror)
			)
		)
		(fp_text user "Author: Antmicro"
			(at -0.95 -4.169 270)
			(layer "B.Fab")
			(effects
				(font
					(size 0.7 0.7)
					(thickness 0.15)
				)
				(justify left bottom mirror)
			)
		)
		(fp_text user "License: Apache-2.0"
			(at -0.95 -5.169 270)
			(layer "B.Fab")
			(effects
				(font
					(size 0.7 0.7)
					(thickness 0.15)
				)
				(justify left bottom mirror)
			)
		)
		(pad "1" smd roundrect
			(at -0.48 0 90)
			(size 0.59 0.64)
			(layers "B.Cu" "B.Mask" "B.Paste")
			(roundrect_rratio 0.25)
			(net 396 "/Ethernet/ETH.RXD3")
			(pintype "passive")
		)
		(pad "2" smd roundrect
			(at 0.48 0 90)
			(size 0.59 0.64)
			(layers "B.Cu" "B.Mask" "B.Paste")
			(roundrect_rratio 0.25)
			(net 797 "+1V8")
			(pintype "passive")
		)
	)
	(footprint "antmicro-footprints:R_0402_1005Metric"
		(layer "B.Cu")
		(at 137.5 152.4 -90)
		(descr "Resistor SMD 0402")
		(tags "resistor SMD 0402")
		(property "Reference" "R116"
			(at 8 -0.375 90)
			(layer "B.SilkS")
			(effects
				(font
					(size 0.7 0.7)
					(thickness 0.15)
				)
				(justify left bottom mirror)
			)
		)
		(property "Value" "R_2k2_0402"
			(at -1.011843 -1.772047 90)
			(layer "B.Fab")
			(effects
				(font
					(size 0.7 0.7)
					(thickness 0.15)
				)
				(justify left bottom mirror)
			)
		)
		(property "Datasheet" "https://www.bourns.com/docs/product-datasheets/cr.pdf"
			(at 0 0 270)
			(layer "F.Fab")
			(hide yes)
			(effects
				(font
					(size 1.27 1.27)
					(thickness 0.15)
				)
			)
		)
		(property "Manufacturer" "Bourns"
			(at 0 0 270)
			(unlocked yes)
			(layer "B.Fab")
			(hide yes)
			(effects
				(font
					(size 1 1)
					(thickness 0.15)
				)
				(justify mirror)
			)
		)
		(property "MPN" "CR0402-FX-2201GLF"
			(at 0 0 270)
			(unlocked yes)
			(layer "B.Fab")
			(hide yes)
			(effects
				(font
					(size 1 1)
					(thickness 0.15)
				)
				(justify mirror)
			)
		)
		(property "Val" "2k2"
			(at 0 0 270)
			(unlocked yes)
			(layer "B.Fab")
			(hide yes)
			(effects
				(font
					(size 1 1)
					(thickness 0.15)
				)
				(justify mirror)
			)
		)
		(property "License" "Apache-2.0"
			(at 0 0 270)
			(unlocked yes)
			(layer "B.Fab")
			(hide yes)
			(effects
				(font
					(size 1 1)
					(thickness 0.15)
				)
				(justify mirror)
			)
		)
		(property "Author" "Antmicro"
			(at 0 0 270)
			(unlocked yes)
			(layer "B.Fab")
			(hide yes)
			(effects
				(font
					(size 1 1)
					(thickness 0.15)
				)
				(justify mirror)
			)
		)
		(property "Tolerance" "1%"
			(at 0 0 270)
			(unlocked yes)
			(layer "B.Fab")
			(hide yes)
			(effects
				(font
					(size 1 1)
					(thickness 0.15)
				)
				(justify mirror)
			)
		)
		(sheetname "/Ethernet/")
		(sheetfile "ethernet.kicad_sch")
		(attr smd exclude_from_bom dnp)
		(fp_rect
			(start -0.925 0.47)
			(end 0.925 -0.47)
			(stroke
				(width 0.05)
				(type default)
			)
			(fill no)
			(layer "B.CrtYd")
		)
		(fp_rect
			(start -0.5 0.25)
			(end 0.5 -0.25)
			(stroke
				(width 0.15)
				(type solid)
			)
			(fill no)
			(layer "B.Fab")
		)
		(fp_text user "Author: Antmicro"
			(at -0.95 -4.169 90)
			(layer "B.Fab")
			(effects
				(font
					(size 0.7 0.7)
					(thickness 0.15)
				)
				(justify left bottom mirror)
			)
		)
		(fp_text user "License: Apache-2.0"
			(at -0.95 -5.169 90)
			(layer "B.Fab")
			(effects
				(font
					(size 0.7 0.7)
					(thickness 0.15)
				)
				(justify left bottom mirror)
			)
		)
		(fp_text user "${REFERENCE}"
			(at -0.95 -3.168 90)
			(layer "B.Fab")
			(effects
				(font
					(size 0.7 0.7)
					(thickness 0.15)
				)
				(justify left bottom mirror)
			)
		)
		(pad "1" smd roundrect
			(at -0.48 0 270)
			(size 0.59 0.64)
			(layers "B.Cu" "B.Mask" "B.Paste")
			(roundrect_rratio 0.25)
			(net 396 "/Ethernet/ETH.RXD3")
			(pintype "passive")
		)
		(pad "2" smd roundrect
			(at 0.48 0 270)
			(size 0.59 0.64)
			(layers "B.Cu" "B.Mask" "B.Paste")
			(roundrect_rratio 0.25)
			(net 1 "GND")
			(pintype "passive")
		)
	)
	(footprint "antmicro-footprints:TP_SMD_1mm"
		(layer "B.Cu")
		(at 139.924499 166.499 -90)
		(property "Reference" "TP1"
			(at -0.95 0.8 90)
			(layer "B.SilkS")
			(effects
				(font
					(size 0.7 0.7)
					(thickness 0.15)
				)
				(justify left bottom mirror)
			)
		)
		(property "Value" "TP_1mm_SMD"
			(at 0 -1.4 90)
			(layer "B.Fab")
			(effects
				(font
					(size 0.7 0.7)
					(thickness 0.15)
				)
				(justify left bottom mirror)
			)
		)
		(property "MPN" ""
			(at 0 0 270)
			(unlocked yes)
			(layer "B.Fab")
			(hide yes)
			(effects
				(font
					(size 1 1)
					(thickness 0.15)
				)
				(justify mirror)
			)
		)
		(property "Manufacturer" ""
			(at 0 0 270)
			(unlocked yes)
			(layer "B.Fab")
			(hide yes)
			(effects
				(font
					(size 1 1)
					(thickness 0.15)
				)
				(justify mirror)
			)
		)
		(property "Author" "Antmicro"
			(at 0 0 270)
			(unlocked yes)
			(layer "B.Fab")
			(hide yes)
			(effects
				(font
					(size 1 1)
					(thickness 0.15)
				)
				(justify mirror)
			)
		)
		(property "License" "Apache-2.0"
			(at 0 0 270)
			(unlocked yes)
			(layer "B.Fab")
			(hide yes)
			(effects
				(font
					(size 1 1)
					(thickness 0.15)
				)
				(justify mirror)
			)
		)
		(sheetname "/Debug FTDI + VNA/")
		(sheetfile "debug-ftdi.kicad_sch")
		(attr exclude_from_pos_files)
		(fp_circle
			(center 0 0)
			(end 0.6 0)
			(stroke
				(width 0.05)
				(type default)
			)
			(fill no)
			(layer "B.CrtYd")
		)
		(fp_text user "Author: Antmicro"
			(at -0.5 -4 90)
			(layer "B.Fab")
			(effects
				(font
					(size 0.7 0.7)
					(thickness 0.15)
				)
				(justify left bottom mirror)
			)
		)
		(fp_text user "${REFERENCE}"
			(at -0.5 -2.8 90)
			(layer "B.Fab")
			(effects
				(font
					(size 0.7 0.7)
					(thickness 0.15)
				)
				(justify left bottom mirror)
			)
		)
		(fp_text user "License: Apache-2.0"
			(at -0.5 -5.2 90)
			(layer "B.Fab")
			(effects
				(font
					(size 0.7 0.7)
					(thickness 0.15)
				)
				(justify left bottom mirror)
			)
		)
		(pad "1" smd circle
			(at 0 0 270)
			(size 1 1)
			(layers "B.Cu" "B.Mask")
			(net 776 "/Debug FTDI + VNA/FTDI_JTAG_RST")
			(pinfunction "1")
			(pintype "passive")
		)
	)
	(footprint "antmicro-footprints:R_0402_1005Metric"
		(layer "B.Cu")
		(at 139.6 152.4 -90)
		(descr "Resistor SMD 0402")
		(tags "resistor SMD 0402")
		(property "Reference" "R114"
			(at 8 -0.375 90)
			(layer "B.SilkS")
			(effects
				(font
					(size 0.7 0.7)
					(thickness 0.15)
				)
				(justify left bottom mirror)
			)
		)
		(property "Value" "R_2k2_0402"
			(at -1.011843 -1.772047 90)
			(layer "B.Fab")
			(effects
				(font
					(size 0.7 0.7)
					(thickness 0.15)
				)
				(justify left bottom mirror)
			)
		)
		(property "Datasheet" "https://www.bourns.com/docs/product-datasheets/cr.pdf"
			(at 0 0 270)
			(layer "F.Fab")
			(hide yes)
			(effects
				(font
					(size 1.27 1.27)
					(thickness 0.15)
				)
			)
		)
		(property "Manufacturer" "Bourns"
			(at 0 0 270)
			(unlocked yes)
			(layer "B.Fab")
			(hide yes)
			(effects
				(font
					(size 1 1)
					(thickness 0.15)
				)
				(justify mirror)
			)
		)
		(property "MPN" "CR0402-FX-2201GLF"
			(at 0 0 270)
			(unlocked yes)
			(layer "B.Fab")
			(hide yes)
			(effects
				(font
					(size 1 1)
					(thickness 0.15)
				)
				(justify mirror)
			)
		)
		(property "Val" "2k2"
			(at 0 0 270)
			(unlocked yes)
			(layer "B.Fab")
			(hide yes)
			(effects
				(font
					(size 1 1)
					(thickness 0.15)
				)
				(justify mirror)
			)
		)
		(property "License" "Apache-2.0"
			(at 0 0 270)
			(unlocked yes)
			(layer "B.Fab")
			(hide yes)
			(effects
				(font
					(size 1 1)
					(thickness 0.15)
				)
				(justify mirror)
			)
		)
		(property "Author" "Antmicro"
			(at 0 0 270)
			(unlocked yes)
			(layer "B.Fab")
			(hide yes)
			(effects
				(font
					(size 1 1)
					(thickness 0.15)
				)
				(justify mirror)
			)
		)
		(property "Tolerance" "1%"
			(at 0 0 270)
			(unlocked yes)
			(layer "B.Fab")
			(hide yes)
			(effects
				(font
					(size 1 1)
					(thickness 0.15)
				)
				(justify mirror)
			)
		)
		(sheetname "/Ethernet/")
		(sheetfile "ethernet.kicad_sch")
		(attr smd)
		(fp_rect
			(start -0.925 0.47)
			(end 0.925 -0.47)
			(stroke
				(width 0.05)
				(type default)
			)
			(fill no)
			(layer "B.CrtYd")
		)
		(fp_rect
			(start -0.5 0.25)
			(end 0.5 -0.25)
			(stroke
				(width 0.15)
				(type solid)
			)
			(fill no)
			(layer "B.Fab")
		)
		(fp_text user "Author: Antmicro"
			(at -0.95 -4.169 90)
			(layer "B.Fab")
			(effects
				(font
					(size 0.7 0.7)
					(thickness 0.15)
				)
				(justify left bottom mirror)
			)
		)
		(fp_text user "License: Apache-2.0"
			(at -0.95 -5.169 90)
			(layer "B.Fab")
			(effects
				(font
					(size 0.7 0.7)
					(thickness 0.15)
				)
				(justify left bottom mirror)
			)
		)
		(fp_text user "${REFERENCE}"
			(at -0.95 -3.168 90)
			(layer "B.Fab")
			(effects
				(font
					(size 0.7 0.7)
					(thickness 0.15)
				)
				(justify left bottom mirror)
			)
		)
		(pad "1" smd roundrect
			(at -0.48 0 270)
			(size 0.59 0.64)
			(layers "B.Cu" "B.Mask" "B.Paste")
			(roundrect_rratio 0.25)
			(net 394 "/Ethernet/ETH.RXD1")
			(pintype "passive")
		)
		(pad "2" smd roundrect
			(at 0.48 0 270)
			(size 0.59 0.64)
			(layers "B.Cu" "B.Mask" "B.Paste")
			(roundrect_rratio 0.25)
			(net 1 "GND")
			(pintype "passive")
		)
	)
	(footprint "antmicro-footprints:R_0402_1005Metric"
		(layer "B.Cu")
		(at 138.55 150.025 90)
		(descr "Resistor SMD 0402")
		(tags "resistor SMD 0402")
		(property "Reference" "R103"
			(at -10.375 0.409 90)
			(layer "B.SilkS")
			(effects
				(font
					(size 0.7 0.7)
					(thickness 0.15)
				)
				(justify right bottom mirror)
			)
		)
		(property "Value" "R_10k_0402"
			(at -1.011843 -1.772047 90)
			(layer "B.Fab")
			(effects
				(font
					(size 0.7 0.7)
					(thickness 0.15)
				)
				(justify right bottom mirror)
			)
		)
		(property "Datasheet" "https://www.bourns.com/docs/product-datasheets/cr.pdf"
			(at 0 0 90)
			(layer "F.Fab")
			(hide yes)
			(effects
				(font
					(size 1.27 1.27)
					(thickness 0.15)
				)
			)
		)
		(property "Manufacturer" "Bourns"
			(at 0 0 90)
			(unlocked yes)
			(layer "B.Fab")
			(hide yes)
			(effects
				(font
					(size 1 1)
					(thickness 0.15)
				)
				(justify mirror)
			)
		)
		(property "MPN" "CR0402-FX-1002GLF"
			(at 0 0 90)
			(unlocked yes)
			(layer "B.Fab")
			(hide yes)
			(effects
				(font
					(size 1 1)
					(thickness 0.15)
				)
				(justify mirror)
			)
		)
		(property "Val" "10k"
			(at 0 0 90)
			(unlocked yes)
			(layer "B.Fab")
			(hide yes)
			(effects
				(font
					(size 1 1)
					(thickness 0.15)
				)
				(justify mirror)
			)
		)
		(property "License" "Apache-2.0"
			(at 0 0 90)
			(unlocked yes)
			(layer "B.Fab")
			(hide yes)
			(effects
				(font
					(size 1 1)
					(thickness 0.15)
				)
				(justify mirror)
			)
		)
		(property "Author" "Antmicro"
			(at 0 0 90)
			(unlocked yes)
			(layer "B.Fab")
			(hide yes)
			(effects
				(font
					(size 1 1)
					(thickness 0.15)
				)
				(justify mirror)
			)
		)
		(property "Tolerance" "1%"
			(at 0 0 90)
			(unlocked yes)
			(layer "B.Fab")
			(hide yes)
			(effects
				(font
					(size 1 1)
					(thickness 0.15)
				)
				(justify mirror)
			)
		)
		(sheetname "/Ethernet/")
		(sheetfile "ethernet.kicad_sch")
		(attr smd)
		(fp_rect
			(start -0.925 0.47)
			(end 0.925 -0.47)
			(stroke
				(width 0.05)
				(type default)
			)
			(fill no)
			(layer "B.CrtYd")
		)
		(fp_rect
			(start -0.5 0.25)
			(end 0.5 -0.25)
			(stroke
				(width 0.15)
				(type solid)
			)
			(fill no)
			(layer "B.Fab")
		)
		(fp_text user "Author: Antmicro"
			(at -0.95 -4.169 270)
			(layer "B.Fab")
			(effects
				(font
					(size 0.7 0.7)
					(thickness 0.15)
				)
				(justify left bottom mirror)
			)
		)
		(fp_text user "${REFERENCE}"
			(at -0.95 -3.168 270)
			(layer "B.Fab")
			(effects
				(font
					(size 0.7 0.7)
					(thickness 0.15)
				)
				(justify left bottom mirror)
			)
		)
		(fp_text user "License: Apache-2.0"
			(at -0.95 -5.169 270)
			(layer "B.Fab")
			(effects
				(font
					(size 0.7 0.7)
					(thickness 0.15)
				)
				(justify left bottom mirror)
			)
		)
		(pad "1" smd roundrect
			(at -0.48 0 90)
			(size 0.59 0.64)
			(layers "B.Cu" "B.Mask" "B.Paste")
			(roundrect_rratio 0.25)
			(net 395 "/Ethernet/ETH.RXD2")
			(pintype "passive")
		)
		(pad "2" smd roundrect
			(at 0.48 0 90)
			(size 0.59 0.64)
			(layers "B.Cu" "B.Mask" "B.Paste")
			(roundrect_rratio 0.25)
			(net 797 "+1V8")
			(pintype "passive")
		)
	)
	(footprint "antmicro-footprints:C_0603_1608Metric"
		(layer "B.Cu")
		(at 174.6 159.5 90)
		(descr "Capacitor SMD 0603")
		(tags "capacitor 0603")
		(property "Reference" "C14"
			(at -3.4 0.3 90)
			(layer "B.SilkS")
			(effects
				(font
					(size 0.7 0.7)
					(thickness 0.15)
				)
				(justify right bottom mirror)
			)
		)
		(property "Value" "C_47u_0603"
			(at -1.42757 -1.770288 90)
			(layer "B.Fab")
			(effects
				(font
					(size 0.7 0.7)
					(thickness 0.15)
				)
				(justify right bottom mirror)
			)
		)
		(property "Datasheet" "https://www.murata.com/products/productdetail?partno=GRM188R60J476ME15%23"
			(at 0 0 90)
			(layer "F.Fab")
			(hide yes)
			(effects
				(font
					(size 1.27 1.27)
					(thickness 0.15)
				)
			)
		)
		(property "Manufacturer" "Murata"
			(at 0 0 90)
			(unlocked yes)
			(layer "B.Fab")
			(hide yes)
			(effects
				(font
					(size 1 1)
					(thickness 0.15)
				)
				(justify mirror)
			)
		)
		(property "MPN" "GRM188R60J476ME15D"
			(at 0 0 90)
			(unlocked yes)
			(layer "B.Fab")
			(hide yes)
			(effects
				(font
					(size 1 1)
					(thickness 0.15)
				)
				(justify mirror)
			)
		)
		(property "Val" "47u"
			(at 0 0 90)
			(unlocked yes)
			(layer "B.Fab")
			(hide yes)
			(effects
				(font
					(size 1 1)
					(thickness 0.15)
				)
				(justify mirror)
			)
		)
		(property "License" "Apache-2.0"
			(at 0 0 90)
			(unlocked yes)
			(layer "B.Fab")
			(hide yes)
			(effects
				(font
					(size 1 1)
					(thickness 0.15)
				)
				(justify mirror)
			)
		)
		(property "Author" "Antmicro"
			(at 0 0 90)
			(unlocked yes)
			(layer "B.Fab")
			(hide yes)
			(effects
				(font
					(size 1 1)
					(thickness 0.15)
				)
				(justify mirror)
			)
		)
		(property "Voltage" ""
			(at 0 0 90)
			(unlocked yes)
			(layer "B.Fab")
			(hide yes)
			(effects
				(font
					(size 1 1)
					(thickness 0.15)
				)
				(justify mirror)
			)
		)
		(property "Dielectric" ""
			(at 0 0 90)
			(unlocked yes)
			(layer "B.Fab")
			(hide yes)
			(effects
				(font
					(size 1 1)
					(thickness 0.15)
				)
				(justify mirror)
			)
		)
		(sheetname "/FPGA power/")
		(sheetfile "fpga-power.kicad_sch")
		(attr smd)
		(fp_line
			(start -0.15 -0.4)
			(end 0.15 -0.4)
			(stroke
				(width 0.15)
				(type solid)
			)
			(layer "B.SilkS")
		)
		(fp_line
			(start -0.15 0.4)
			(end 0.15 0.4)
			(stroke
				(width 0.15)
				(type solid)
			)
			(layer "B.SilkS")
		)
		(fp_rect
			(start -1.25 0.65)
			(end 1.25 -0.65)
			(stroke
				(width 0.05)
				(type solid)
			)
			(fill no)
			(layer "B.CrtYd")
		)
		(fp_rect
			(start -0.8 0.4)
			(end 0.8 -0.4)
			(stroke
				(width 0.15)
				(type solid)
			)
			(fill no)
			(layer "B.Fab")
		)
		(fp_text user "${REFERENCE}"
			(at -1.682 -3.895 270)
			(layer "B.Fab")
			(effects
				(font
					(size 0.7 0.7)
					(thickness 0.15)
				)
				(justify left bottom mirror)
			)
		)
		(fp_text user "License: Apache-2.0"
			(at -1.682 -5.895 270)
			(layer "B.Fab")
			(effects
				(font
					(size 0.7 0.7)
					(thickness 0.15)
				)
				(justify left bottom mirror)
			)
		)
		(fp_text user "Author: Antmicro"
			(at -1.682 -4.894 270)
			(layer "B.Fab")
			(effects
				(font
					(size 0.7 0.7)
					(thickness 0.15)
				)
				(justify left bottom mirror)
			)
		)
		(pad "1" smd roundrect
			(at -0.7 0 90)
			(size 0.8 1)
			(layers "B.Cu" "B.Mask" "B.Paste")
			(roundrect_rratio 0.2)
			(net 172 "+1V2_MGTAVTT")
			(pintype "passive")
		)
		(pad "2" smd roundrect
			(at 0.7 0 90)
			(size 0.8 1)
			(layers "B.Cu" "B.Mask" "B.Paste")
			(roundrect_rratio 0.2)
			(net 1 "GND")
			(pintype "passive")
		)
	)
	(footprint "antmicro-footprints:C_0402_1005Metric"
		(layer "B.Cu")
		(at 166.1 150.44)
		(descr "Capacitor SMD 0402")
		(tags "capacitor SMD 0402")
		(property "Reference" "C3"
			(at -2.4 0.46 0)
			(layer "B.SilkS")
			(effects
				(font
					(size 0.7 0.7)
					(thickness 0.15)
				)
				(justify right bottom mirror)
			)
		)
		(property "Value" "C_100n_0402"
			(at -1.022927 -2.155213 0)
			(layer "B.Fab")
			(effects
				(font
					(size 0.7 0.7)
					(thickness 0.15)
				)
				(justify right bottom mirror)
			)
		)
		(property "Datasheet" "https://www.murata.com/products/productdetail?partno=GRM155R61H104KE14%23"
			(at 0 0 0)
			(layer "F.Fab")
			(hide yes)
			(effects
				(font
					(size 1.27 1.27)
					(thickness 0.15)
				)
			)
		)
		(property "Manufacturer" "Murata"
			(at 0 0 0)
			(unlocked yes)
			(layer "B.Fab")
			(hide yes)
			(effects
				(font
					(size 1 1)
					(thickness 0.15)
				)
				(justify mirror)
			)
		)
		(property "MPN" "GRM155R61H104KE14D"
			(at 0 0 0)
			(unlocked yes)
			(layer "B.Fab")
			(hide yes)
			(effects
				(font
					(size 1 1)
					(thickness 0.15)
				)
				(justify mirror)
			)
		)
		(property "Val" "100n"
			(at 0 0 0)
			(unlocked yes)
			(layer "B.Fab")
			(hide yes)
			(effects
				(font
					(size 1 1)
					(thickness 0.15)
				)
				(justify mirror)
			)
		)
		(property "License" "Apache-2.0"
			(at 0 0 0)
			(unlocked yes)
			(layer "B.Fab")
			(hide yes)
			(effects
				(font
					(size 1 1)
					(thickness 0.15)
				)
				(justify mirror)
			)
		)
		(property "Author" "Antmicro"
			(at 0 0 0)
			(unlocked yes)
			(layer "B.Fab")
			(hide yes)
			(effects
				(font
					(size 1 1)
					(thickness 0.15)
				)
				(justify mirror)
			)
		)
		(property "Voltage" "50V"
			(at 0 0 0)
			(unlocked yes)
			(layer "B.Fab")
			(hide yes)
			(effects
				(font
					(size 1 1)
					(thickness 0.15)
				)
				(justify mirror)
			)
		)
		(property "Dielectric" "X5R"
			(at 0 0 0)
			(unlocked yes)
			(layer "B.Fab")
			(hide yes)
			(effects
				(font
					(size 1 1)
					(thickness 0.15)
				)
				(justify mirror)
			)
		)
		(sheetname "/HyperRAM + QSPI Flash/")
		(sheetfile "hyperram-flash.kicad_sch")
		(attr smd)
		(fp_rect
			(start -0.925 0.47)
			(end 0.925 -0.47)
			(stroke
				(width 0.05)
				(type default)
			)
			(fill no)
			(layer "B.CrtYd")
		)
		(fp_line
			(start -0.494 -0.248)
			(end -0.494 0.25)
			(stroke
				(width 0.15)
				(type solid)
			)
			(layer "B.Fab")
		)
		(fp_line
			(start -0.494 0.25)
			(end 0.504 0.25)
			(stroke
				(width 0.15)
				(type solid)
			)
			(layer "B.Fab")
		)
		(fp_line
			(start 0.504 -0.248)
			(end -0.494 -0.248)
			(stroke
				(width 0.15)
				(type solid)
			)
			(layer "B.Fab")
		)
		(fp_line
			(start 0.504 0.25)
			(end 0.504 -0.248)
			(stroke
				(width 0.15)
				(type solid)
			)
			(layer "B.Fab")
		)
		(fp_text user "License: Apache-2.0"
			(at -0.939 -5.799 180)
			(layer "B.Fab")
			(effects
				(font
					(size 0.7 0.7)
					(thickness 0.15)
				)
				(justify left bottom mirror)
			)
		)
		(fp_text user "${REFERENCE}"
			(at -0.939 -4.599 180)
			(layer "B.Fab")
			(effects
				(font
					(size 0.7 0.7)
					(thickness 0.15)
				)
				(justify left bottom mirror)
			)
		)
		(fp_text user "Author: Antmicro"
			(at -0.939 -3.399 180)
			(layer "B.Fab")
			(effects
				(font
					(size 0.7 0.7)
					(thickness 0.15)
				)
				(justify left bottom mirror)
			)
		)
		(pad "1" smd roundrect
			(at -0.48 0)
			(size 0.59 0.64)
			(layers "B.Cu" "B.Mask" "B.Paste")
			(roundrect_rratio 0.25)
			(net 797 "+1V8")
			(pintype "passive")
		)
		(pad "2" smd roundrect
			(at 0.48 0)
			(size 0.59 0.64)
			(layers "B.Cu" "B.Mask" "B.Paste")
			(roundrect_rratio 0.25)
			(net 1 "GND")
			(pintype "passive")
		)
	)
	(footprint "antmicro-footprints:R_0402_1005Metric"
		(layer "B.Cu")
		(at 252.2 185.349)
		(descr "Resistor SMD 0402")
		(tags "resistor SMD 0402")
		(property "Reference" "R243"
			(at 1 0.491 0)
			(layer "B.SilkS")
			(effects
				(font
					(size 0.7 0.7)
					(thickness 0.15)
				)
				(justify right bottom mirror)
			)
		)
		(property "Value" "R_4k7_0402"
			(at -1.011843 -1.772047 0)
			(layer "B.Fab")
			(effects
				(font
					(size 0.7 0.7)
					(thickness 0.15)
				)
				(justify right bottom mirror)
			)
		)
		(property "Datasheet" "https://www.bourns.com/docs/product-datasheets/cr.pdf"
			(at 0 0 0)
			(layer "F.Fab")
			(hide yes)
			(effects
				(font
					(size 1.27 1.27)
					(thickness 0.15)
				)
			)
		)
		(property "MPN" "CR0402-FX-4701GLF"
			(at 0 0 0)
			(unlocked yes)
			(layer "B.Fab")
			(hide yes)
			(effects
				(font
					(size 1 1)
					(thickness 0.15)
				)
				(justify mirror)
			)
		)
		(property "Manufacturer" "Bourns"
			(at 0 0 0)
			(unlocked yes)
			(layer "B.Fab")
			(hide yes)
			(effects
				(font
					(size 1 1)
					(thickness 0.15)
				)
				(justify mirror)
			)
		)
		(property "License" "Apache-2.0"
			(at 0 0 0)
			(unlocked yes)
			(layer "B.Fab")
			(hide yes)
			(effects
				(font
					(size 1 1)
					(thickness 0.15)
				)
				(justify mirror)
			)
		)
		(property "Author" "Antmicro"
			(at 0 0 0)
			(unlocked yes)
			(layer "B.Fab")
			(hide yes)
			(effects
				(font
					(size 1 1)
					(thickness 0.15)
				)
				(justify mirror)
			)
		)
		(property "Val" "4k7"
			(at 0 0 0)
			(unlocked yes)
			(layer "B.Fab")
			(hide yes)
			(effects
				(font
					(size 1 1)
					(thickness 0.15)
				)
				(justify mirror)
			)
		)
		(property "Tolerance" "1%"
			(at 0 0 0)
			(unlocked yes)
			(layer "B.Fab")
			(hide yes)
			(effects
				(font
					(size 1 1)
					(thickness 0.15)
				)
				(justify mirror)
			)
		)
		(sheetname "/I^{2}C + I3C/")
		(sheetfile "i2c.kicad_sch")
		(attr smd)
		(fp_rect
			(start -0.925 0.47)
			(end 0.925 -0.47)
			(stroke
				(width 0.05)
				(type default)
			)
			(fill no)
			(layer "B.CrtYd")
		)
		(fp_rect
			(start -0.5 0.25)
			(end 0.5 -0.25)
			(stroke
				(width 0.15)
				(type solid)
			)
			(fill no)
			(layer "B.Fab")
		)
		(fp_text user "License: Apache-2.0"
			(at -0.95 -5.169 180)
			(layer "B.Fab")
			(effects
				(font
					(size 0.7 0.7)
					(thickness 0.15)
				)
				(justify left bottom mirror)
			)
		)
		(fp_text user "${REFERENCE}"
			(at -0.95 -3.168 180)
			(layer "B.Fab")
			(effects
				(font
					(size 0.7 0.7)
					(thickness 0.15)
				)
				(justify left bottom mirror)
			)
		)
		(fp_text user "Author: Antmicro"
			(at -0.95 -4.169 180)
			(layer "B.Fab")
			(effects
				(font
					(size 0.7 0.7)
					(thickness 0.15)
				)
				(justify left bottom mirror)
			)
		)
		(pad "1" smd roundrect
			(at -0.48 0)
			(size 0.59 0.64)
			(layers "B.Cu" "B.Mask" "B.Paste")
			(roundrect_rratio 0.25)
			(net 368 "/I^{2}C + I3C/I3C_EXT.SDA")
			(pintype "passive")
		)
		(pad "2" smd roundrect
			(at 0.48 0)
			(size 0.59 0.64)
			(layers "B.Cu" "B.Mask" "B.Paste")
			(roundrect_rratio 0.25)
			(net 782 "Net-(Q24-D)")
			(pintype "passive")
		)
	)
	(footprint "antmicro-footprints:C_0402_1005Metric_EIA"
		(layer "B.Cu")
		(at 185 154.499999 -90)
		(descr "Capacitor SMD 0402 (1005 Metric), square (rectangular) end terminal, IPC_7351 nominal, (Body size source: IPC-SM-782 page 76, https://www.pcb-3d.com/wordpress/wp-content/uploads/ipc-sm-782a_amendment_1_and_2.pdf)")
		(tags "capacitor 0402")
		(property "Reference" "C41"
			(at -12.024999 30.625 90)
			(layer "B.SilkS")
			(effects
				(font
					(size 0.7 0.7)
					(thickness 0.15)
				)
				(justify left bottom mirror)
			)
		)
		(property "Value" "C_1u_25V_0402"
			(at 0 -1.169 90)
			(layer "B.Fab")
			(effects
				(font
					(size 0.7 0.7)
					(thickness 0.15)
				)
				(justify left bottom mirror)
			)
		)
		(property "Datasheet" "https://www.murata.com/products/productdetail?partno=GRM155R61E105KE11%23"
			(at 0 0 270)
			(layer "F.Fab")
			(hide yes)
			(effects
				(font
					(size 1.27 1.27)
					(thickness 0.15)
				)
			)
		)
		(property "MPN" "GRM155R61E105KE11J"
			(at 0 0 270)
			(unlocked yes)
			(layer "B.Fab")
			(hide yes)
			(effects
				(font
					(size 1 1)
					(thickness 0.15)
				)
				(justify mirror)
			)
		)
		(property "Manufacturer" "Murata"
			(at 0 0 270)
			(unlocked yes)
			(layer "B.Fab")
			(hide yes)
			(effects
				(font
					(size 1 1)
					(thickness 0.15)
				)
				(justify mirror)
			)
		)
		(property "License" "Apache-2.0"
			(at 0 0 270)
			(unlocked yes)
			(layer "B.Fab")
			(hide yes)
			(effects
				(font
					(size 1 1)
					(thickness 0.15)
				)
				(justify mirror)
			)
		)
		(property "Author" "Antmicro"
			(at 0 0 270)
			(unlocked yes)
			(layer "B.Fab")
			(hide yes)
			(effects
				(font
					(size 1 1)
					(thickness 0.15)
				)
				(justify mirror)
			)
		)
		(property "Val" "1u"
			(at 0 0 270)
			(unlocked yes)
			(layer "B.Fab")
			(hide yes)
			(effects
				(font
					(size 1 1)
					(thickness 0.15)
				)
				(justify mirror)
			)
		)
		(property "Voltage" "25V"
			(at 0 0 270)
			(unlocked yes)
			(layer "B.Fab")
			(hide yes)
			(effects
				(font
					(size 1 1)
					(thickness 0.15)
				)
				(justify mirror)
			)
		)
		(property "Dielectric" "X5R"
			(at 0 0 270)
			(unlocked yes)
			(layer "B.Fab")
			(hide yes)
			(effects
				(font
					(size 1 1)
					(thickness 0.15)
				)
				(justify mirror)
			)
		)
		(sheetname "/FPGA power/")
		(sheetfile "fpga-power.kicad_sch")
		(attr smd)
		(fp_rect
			(start -0.95 0.45)
			(end 0.95 -0.45)
			(stroke
				(width 0.05)
				(type default)
			)
			(fill no)
			(layer "B.CrtYd")
		)
		(fp_line
			(start -0.5 0.25)
			(end 0.498 0.25)
			(stroke
				(width 0.15)
				(type solid)
			)
			(layer "B.Fab")
		)
		(fp_line
			(start 0.498 0.25)
			(end 0.498 -0.248)
			(stroke
				(width 0.15)
				(type solid)
			)
			(layer "B.Fab")
		)
		(fp_line
			(start -0.5 -0.248)
			(end -0.5 0.25)
			(stroke
				(width 0.15)
				(type solid)
			)
			(layer "B.Fab")
		)
		(fp_line
			(start 0.498 -0.248)
			(end -0.5 -0.248)
			(stroke
				(width 0.15)
				(type solid)
			)
			(layer "B.Fab")
		)
		(fp_text user "${REFERENCE}"
			(at -0.9656 -3.169 90)
			(layer "B.Fab")
			(effects
				(font
					(size 0.7 0.7)
					(thickness 0.15)
				)
				(justify left bottom mirror)
			)
		)
		(fp_text user "License: Apache-2.0"
			(at -0.9656 -4.369 90)
			(layer "B.Fab")
			(effects
				(font
					(size 0.7 0.7)
					(thickness 0.15)
				)
				(justify left bottom mirror)
			)
		)
		(fp_text user "Author: Antmicro"
			(at -0.9656 -5.569 90)
			(layer "B.Fab")
			(effects
				(font
					(size 0.7 0.7)
					(thickness 0.15)
				)
				(justify left bottom mirror)
			)
		)
		(pad "1" smd roundrect
			(at -0.5 0 180)
			(size 0.6 0.6)
			(layers "B.Cu" "B.Mask" "B.Paste")
			(roundrect_rratio 0.25)
			(net 1 "GND")
			(pintype "passive")
		)
		(pad "2" smd roundrect
			(at 0.498 0 270)
			(size 0.6 0.6)
			(layers "B.Cu" "B.Mask" "B.Paste")
			(roundrect_rratio 0.25)
			(net 553 "+0V85")
			(pintype "passive")
		)
	)
	(footprint "antmicro-footprints:R_0402_1005Metric"
		(layer "B.Cu")
		(at 238.424499 185.849 180)
		(descr "Resistor SMD 0402")
		(tags "resistor SMD 0402")
		(property "Reference" "R150"
			(at -3.95 -0.5 0)
			(layer "B.SilkS")
			(effects
				(font
					(size 0.7 0.7)
					(thickness 0.15)
				)
				(justify left bottom mirror)
			)
		)
		(property "Value" "R_4k7_0402"
			(at -1.011843 -1.772047 0)
			(layer "B.Fab")
			(effects
				(font
					(size 0.7 0.7)
					(thickness 0.15)
				)
				(justify left bottom mirror)
			)
		)
		(property "Datasheet" "https://www.bourns.com/docs/product-datasheets/cr.pdf"
			(at 0 0 180)
			(layer "F.Fab")
			(hide yes)
			(effects
				(font
					(size 1.27 1.27)
					(thickness 0.15)
				)
			)
		)
		(property "Manufacturer" "Bourns"
			(at 0 0 180)
			(unlocked yes)
			(layer "B.Fab")
			(hide yes)
			(effects
				(font
					(size 1 1)
					(thickness 0.15)
				)
				(justify mirror)
			)
		)
		(property "MPN" "CR0402-FX-4701GLF"
			(at 0 0 180)
			(unlocked yes)
			(layer "B.Fab")
			(hide yes)
			(effects
				(font
					(size 1 1)
					(thickness 0.15)
				)
				(justify mirror)
			)
		)
		(property "Val" "4k7"
			(at 0 0 180)
			(unlocked yes)
			(layer "B.Fab")
			(hide yes)
			(effects
				(font
					(size 1 1)
					(thickness 0.15)
				)
				(justify mirror)
			)
		)
		(property "License" "Apache-2.0"
			(at 0 0 180)
			(unlocked yes)
			(layer "B.Fab")
			(hide yes)
			(effects
				(font
					(size 1 1)
					(thickness 0.15)
				)
				(justify mirror)
			)
		)
		(property "Author" "Antmicro"
			(at 0 0 180)
			(unlocked yes)
			(layer "B.Fab")
			(hide yes)
			(effects
				(font
					(size 1 1)
					(thickness 0.15)
				)
				(justify mirror)
			)
		)
		(property "Tolerance" "1%"
			(at 0 0 180)
			(unlocked yes)
			(layer "B.Fab")
			(hide yes)
			(effects
				(font
					(size 1 1)
					(thickness 0.15)
				)
				(justify mirror)
			)
		)
		(sheetname "/I^{2}C + I3C/")
		(sheetfile "i2c.kicad_sch")
		(attr smd)
		(fp_rect
			(start -0.925 0.47)
			(end 0.925 -0.47)
			(stroke
				(width 0.05)
				(type default)
			)
			(fill no)
			(layer "B.CrtYd")
		)
		(fp_rect
			(start -0.5 0.25)
			(end 0.5 -0.25)
			(stroke
				(width 0.15)
				(type solid)
			)
			(fill no)
			(layer "B.Fab")
		)
		(fp_text user "Author: Antmicro"
			(at -0.95 -4.169 0)
			(layer "B.Fab")
			(effects
				(font
					(size 0.7 0.7)
					(thickness 0.15)
				)
				(justify left bottom mirror)
			)
		)
		(fp_text user "License: Apache-2.0"
			(at -0.95 -5.169 0)
			(layer "B.Fab")
			(effects
				(font
					(size 0.7 0.7)
					(thickness 0.15)
				)
				(justify left bottom mirror)
			)
		)
		(fp_text user "${REFERENCE}"
			(at -0.95 -3.168 0)
			(layer "B.Fab")
			(effects
				(font
					(size 0.7 0.7)
					(thickness 0.15)
				)
				(justify left bottom mirror)
			)
		)
		(pad "1" smd roundrect
			(at -0.48 0 180)
			(size 0.59 0.64)
			(layers "B.Cu" "B.Mask" "B.Paste")
			(roundrect_rratio 0.25)
			(net 151 "+3V3")
			(pintype "passive")
		)
		(pad "2" smd roundrect
			(at 0.48 0 180)
			(size 0.59 0.64)
			(layers "B.Cu" "B.Mask" "B.Paste")
			(roundrect_rratio 0.25)
			(net 746 "/FPGA Config/FPGA_PWR.SDA")
			(pintype "passive")
		)
	)
	(footprint "antmicro-footprints:C_0402_1005Metric_EIA"
		(layer "B.Cu")
		(at 186 156.498 90)
		(descr "Capacitor SMD 0402 (1005 Metric), square (rectangular) end terminal, IPC_7351 nominal, (Body size source: IPC-SM-782 page 76, https://www.pcb-3d.com/wordpress/wp-content/uploads/ipc-sm-782a_amendment_1_and_2.pdf)")
		(tags "capacitor 0402")
		(property "Reference" "C47"
			(at 9.773 -30.65 90)
			(layer "B.SilkS")
			(effects
				(font
					(size 0.7 0.7)
					(thickness 0.15)
				)
				(justify right bottom mirror)
			)
		)
		(property "Value" "C_1u_25V_0402"
			(at 0 -1.169 90)
			(layer "B.Fab")
			(effects
				(font
					(size 0.7 0.7)
					(thickness 0.15)
				)
				(justify right bottom mirror)
			)
		)
		(property "Datasheet" "https://www.murata.com/products/productdetail?partno=GRM155R61E105KE11%23"
			(at 0 0 90)
			(layer "F.Fab")
			(hide yes)
			(effects
				(font
					(size 1.27 1.27)
					(thickness 0.15)
				)
			)
		)
		(property "MPN" "GRM155R61E105KE11J"
			(at 0 0 90)
			(unlocked yes)
			(layer "B.Fab")
			(hide yes)
			(effects
				(font
					(size 1 1)
					(thickness 0.15)
				)
				(justify mirror)
			)
		)
		(property "Manufacturer" "Murata"
			(at 0 0 90)
			(unlocked yes)
			(layer "B.Fab")
			(hide yes)
			(effects
				(font
					(size 1 1)
					(thickness 0.15)
				)
				(justify mirror)
			)
		)
		(property "License" "Apache-2.0"
			(at 0 0 90)
			(unlocked yes)
			(layer "B.Fab")
			(hide yes)
			(effects
				(font
					(size 1 1)
					(thickness 0.15)
				)
				(justify mirror)
			)
		)
		(property "Author" "Antmicro"
			(at 0 0 90)
			(unlocked yes)
			(layer "B.Fab")
			(hide yes)
			(effects
				(font
					(size 1 1)
					(thickness 0.15)
				)
				(justify mirror)
			)
		)
		(property "Val" "1u"
			(at 0 0 90)
			(unlocked yes)
			(layer "B.Fab")
			(hide yes)
			(effects
				(font
					(size 1 1)
					(thickness 0.15)
				)
				(justify mirror)
			)
		)
		(property "Voltage" "25V"
			(at 0 0 90)
			(unlocked yes)
			(layer "B.Fab")
			(hide yes)
			(effects
				(font
					(size 1 1)
					(thickness 0.15)
				)
				(justify mirror)
			)
		)
		(property "Dielectric" "X5R"
			(at 0 0 90)
			(unlocked yes)
			(layer "B.Fab")
			(hide yes)
			(effects
				(font
					(size 1 1)
					(thickness 0.15)
				)
				(justify mirror)
			)
		)
		(sheetname "/FPGA power/")
		(sheetfile "fpga-power.kicad_sch")
		(attr smd)
		(fp_rect
			(start -0.95 0.45)
			(end 0.95 -0.45)
			(stroke
				(width 0.05)
				(type default)
			)
			(fill no)
			(layer "B.CrtYd")
		)
		(fp_line
			(start 0.498 -0.248)
			(end -0.5 -0.248)
			(stroke
				(width 0.15)
				(type solid)
			)
			(layer "B.Fab")
		)
		(fp_line
			(start -0.5 -0.248)
			(end -0.5 0.25)
			(stroke
				(width 0.15)
				(type solid)
			)
			(layer "B.Fab")
		)
		(fp_line
			(start 0.498 0.25)
			(end 0.498 -0.248)
			(stroke
				(width 0.15)
				(type solid)
			)
			(layer "B.Fab")
		)
		(fp_line
			(start -0.5 0.25)
			(end 0.498 0.25)
			(stroke
				(width 0.15)
				(type solid)
			)
			(layer "B.Fab")
		)
		(fp_text user "License: Apache-2.0"
			(at -0.9656 -4.369 270)
			(layer "B.Fab")
			(effects
				(font
					(size 0.7 0.7)
					(thickness 0.15)
				)
				(justify left bottom mirror)
			)
		)
		(fp_text user "Author: Antmicro"
			(at -0.9656 -5.569 270)
			(layer "B.Fab")
			(effects
				(font
					(size 0.7 0.7)
					(thickness 0.15)
				)
				(justify left bottom mirror)
			)
		)
		(fp_text user "${REFERENCE}"
			(at -0.9656 -3.169 270)
			(layer "B.Fab")
			(effects
				(font
					(size 0.7 0.7)
					(thickness 0.15)
				)
				(justify left bottom mirror)
			)
		)
		(pad "1" smd roundrect
			(at -0.5 0)
			(size 0.6 0.6)
			(layers "B.Cu" "B.Mask" "B.Paste")
			(roundrect_rratio 0.25)
			(net 1 "GND")
			(pintype "passive")
		)
		(pad "2" smd roundrect
			(at 0.498 0 90)
			(size 0.6 0.6)
			(layers "B.Cu" "B.Mask" "B.Paste")
			(roundrect_rratio 0.25)
			(net 553 "+0V85")
			(pintype "passive")
		)
	)
	(footprint "antmicro-footprints:R_0402_1005Metric"
		(layer "B.Cu")
		(at 247.475 185.299)
		(descr "Resistor SMD 0402")
		(tags "resistor SMD 0402")
		(property "Reference" "R231"
			(at 0.825 0.5 0)
			(layer "B.SilkS")
			(effects
				(font
					(size 0.7 0.7)
					(thickness 0.15)
				)
				(justify right bottom mirror)
			)
		)
		(property "Value" "R_4k7_0402"
			(at -1.011843 -1.772047 0)
			(layer "B.Fab")
			(effects
				(font
					(size 0.7 0.7)
					(thickness 0.15)
				)
				(justify right bottom mirror)
			)
		)
		(property "Datasheet" "https://www.bourns.com/docs/product-datasheets/cr.pdf"
			(at 0 0 0)
			(layer "F.Fab")
			(hide yes)
			(effects
				(font
					(size 1.27 1.27)
					(thickness 0.15)
				)
			)
		)
		(property "MPN" "CR0402-FX-4701GLF"
			(at 0 0 0)
			(unlocked yes)
			(layer "B.Fab")
			(hide yes)
			(effects
				(font
					(size 1 1)
					(thickness 0.15)
				)
				(justify mirror)
			)
		)
		(property "Manufacturer" "Bourns"
			(at 0 0 0)
			(unlocked yes)
			(layer "B.Fab")
			(hide yes)
			(effects
				(font
					(size 1 1)
					(thickness 0.15)
				)
				(justify mirror)
			)
		)
		(property "License" "Apache-2.0"
			(at 0 0 0)
			(unlocked yes)
			(layer "B.Fab")
			(hide yes)
			(effects
				(font
					(size 1 1)
					(thickness 0.15)
				)
				(justify mirror)
			)
		)
		(property "Author" "Antmicro"
			(at 0 0 0)
			(unlocked yes)
			(layer "B.Fab")
			(hide yes)
			(effects
				(font
					(size 1 1)
					(thickness 0.15)
				)
				(justify mirror)
			)
		)
		(property "Val" "4k7"
			(at 0 0 0)
			(unlocked yes)
			(layer "B.Fab")
			(hide yes)
			(effects
				(font
					(size 1 1)
					(thickness 0.15)
				)
				(justify mirror)
			)
		)
		(property "Tolerance" "1%"
			(at 0 0 0)
			(unlocked yes)
			(layer "B.Fab")
			(hide yes)
			(effects
				(font
					(size 1 1)
					(thickness 0.15)
				)
				(justify mirror)
			)
		)
		(sheetname "/I^{2}C + I3C/")
		(sheetfile "i2c.kicad_sch")
		(attr smd)
		(fp_rect
			(start -0.925 0.47)
			(end 0.925 -0.47)
			(stroke
				(width 0.05)
				(type default)
			)
			(fill no)
			(layer "B.CrtYd")
		)
		(fp_rect
			(start -0.5 0.25)
			(end 0.5 -0.25)
			(stroke
				(width 0.15)
				(type solid)
			)
			(fill no)
			(layer "B.Fab")
		)
		(fp_text user "Author: Antmicro"
			(at -0.95 -4.169 180)
			(layer "B.Fab")
			(effects
				(font
					(size 0.7 0.7)
					(thickness 0.15)
				)
				(justify left bottom mirror)
			)
		)
		(fp_text user "License: Apache-2.0"
			(at -0.95 -5.169 180)
			(layer "B.Fab")
			(effects
				(font
					(size 0.7 0.7)
					(thickness 0.15)
				)
				(justify left bottom mirror)
			)
		)
		(fp_text user "${REFERENCE}"
			(at -0.95 -3.168 180)
			(layer "B.Fab")
			(effects
				(font
					(size 0.7 0.7)
					(thickness 0.15)
				)
				(justify left bottom mirror)
			)
		)
		(pad "1" smd roundrect
			(at -0.48 0)
			(size 0.59 0.64)
			(layers "B.Cu" "B.Mask" "B.Paste")
			(roundrect_rratio 0.25)
			(net 528 "/FPGA banks HD/FPGA_I3C.SDA")
			(pintype "passive")
		)
		(pad "2" smd roundrect
			(at 0.48 0)
			(size 0.59 0.64)
			(layers "B.Cu" "B.Mask" "B.Paste")
			(roundrect_rratio 0.25)
			(net 662 "Net-(Q22-D)")
			(pintype "passive")
		)
	)
	(footprint "antmicro-footprints:R_0402_1005Metric"
		(layer "B.Cu")
		(at 115.34 168.82)
		(descr "Resistor SMD 0402")
		(tags "resistor SMD 0402")
		(property "Reference" "R83"
			(at -1.09 1.53 0)
			(layer "B.SilkS")
			(effects
				(font
					(size 0.7 0.7)
					(thickness 0.15)
				)
				(justify right bottom mirror)
			)
		)
		(property "Value" "R_100k_0402"
			(at -1.011843 -1.772047 0)
			(layer "B.Fab")
			(effects
				(font
					(size 0.7 0.7)
					(thickness 0.15)
				)
				(justify right bottom mirror)
			)
		)
		(property "Datasheet" "https://www.bourns.com/docs/product-datasheets/cr.pdf"
			(at 0 0 0)
			(layer "F.Fab")
			(hide yes)
			(effects
				(font
					(size 1.27 1.27)
					(thickness 0.15)
				)
			)
		)
		(property "MPN" "CR0402-FX-1003GLF"
			(at 0 0 0)
			(unlocked yes)
			(layer "B.Fab")
			(hide yes)
			(effects
				(font
					(size 1 1)
					(thickness 0.15)
				)
				(justify mirror)
			)
		)
		(property "Manufacturer" "Bourns"
			(at 0 0 0)
			(unlocked yes)
			(layer "B.Fab")
			(hide yes)
			(effects
				(font
					(size 1 1)
					(thickness 0.15)
				)
				(justify mirror)
			)
		)
		(property "License" "Apache-2.0"
			(at 0 0 0)
			(unlocked yes)
			(layer "B.Fab")
			(hide yes)
			(effects
				(font
					(size 1 1)
					(thickness 0.15)
				)
				(justify mirror)
			)
		)
		(property "Author" "Antmicro"
			(at 0 0 0)
			(unlocked yes)
			(layer "B.Fab")
			(hide yes)
			(effects
				(font
					(size 1 1)
					(thickness 0.15)
				)
				(justify mirror)
			)
		)
		(property "Val" "100k"
			(at 0 0 0)
			(unlocked yes)
			(layer "B.Fab")
			(hide yes)
			(effects
				(font
					(size 1 1)
					(thickness 0.15)
				)
				(justify mirror)
			)
		)
		(property "Tolerance" "1%"
			(at 0 0 0)
			(unlocked yes)
			(layer "B.Fab")
			(hide yes)
			(effects
				(font
					(size 1 1)
					(thickness 0.15)
				)
				(justify mirror)
			)
		)
		(sheetname "/HDMI + SD Card/")
		(sheetfile "hdmi-sd-card.kicad_sch")
		(attr smd)
		(fp_rect
			(start -0.925 0.47)
			(end 0.925 -0.47)
			(stroke
				(width 0.05)
				(type default)
			)
			(fill no)
			(layer "B.CrtYd")
		)
		(fp_rect
			(start -0.5 0.25)
			(end 0.5 -0.25)
			(stroke
				(width 0.15)
				(type solid)
			)
			(fill no)
			(layer "B.Fab")
		)
		(fp_text user "${REFERENCE}"
			(at -0.95 -3.168 180)
			(layer "B.Fab")
			(effects
				(font
					(size 0.7 0.7)
					(thickness 0.15)
				)
				(justify left bottom mirror)
			)
		)
		(fp_text user "License: Apache-2.0"
			(at -0.95 -5.169 180)
			(layer "B.Fab")
			(effects
				(font
					(size 0.7 0.7)
					(thickness 0.15)
				)
				(justify left bottom mirror)
			)
		)
		(fp_text user "Author: Antmicro"
			(at -0.95 -4.169 180)
			(layer "B.Fab")
			(effects
				(font
					(size 0.7 0.7)
					(thickness 0.15)
				)
				(justify left bottom mirror)
			)
		)
		(pad "1" smd roundrect
			(at -0.48 0)
			(size 0.59 0.64)
			(layers "B.Cu" "B.Mask" "B.Paste")
			(roundrect_rratio 0.25)
			(net 1 "GND")
			(pintype "passive")
		)
		(pad "2" smd roundrect
			(at 0.48 0)
			(size 0.59 0.64)
			(layers "B.Cu" "B.Mask" "B.Paste")
			(roundrect_rratio 0.25)
			(net 500 "HDMI_IN_HPD")
			(pintype "passive")
		)
	)
	(footprint "antmicro-footprints:R_0402_1005Metric"
		(layer "B.Cu")
		(at 240.12 175.975 180)
		(descr "Resistor SMD 0402")
		(tags "resistor SMD 0402")
		(property "Reference" "R143"
			(at -4.505 -0.4 0)
			(layer "B.SilkS")
			(effects
				(font
					(size 0.7 0.7)
					(thickness 0.15)
				)
				(justify left bottom mirror)
			)
		)
		(property "Value" "R_47k_0402"
			(at -1.011843 -1.772047 0)
			(layer "B.Fab")
			(effects
				(font
					(size 0.7 0.7)
					(thickness 0.15)
				)
				(justify left bottom mirror)
			)
		)
		(property "Datasheet" "https://www.bourns.com/docs/product-datasheets/cr.pdf"
			(at 0 0 180)
			(layer "F.Fab")
			(hide yes)
			(effects
				(font
					(size 1.27 1.27)
					(thickness 0.15)
				)
			)
		)
		(property "Manufacturer" "Bourns"
			(at 0 0 180)
			(unlocked yes)
			(layer "B.Fab")
			(hide yes)
			(effects
				(font
					(size 1 1)
					(thickness 0.15)
				)
				(justify mirror)
			)
		)
		(property "MPN" "CR0402-FX-4702GLF"
			(at 0 0 180)
			(unlocked yes)
			(layer "B.Fab")
			(hide yes)
			(effects
				(font
					(size 1 1)
					(thickness 0.15)
				)
				(justify mirror)
			)
		)
		(property "Val" "47k"
			(at 0 0 180)
			(unlocked yes)
			(layer "B.Fab")
			(hide yes)
			(effects
				(font
					(size 1 1)
					(thickness 0.15)
				)
				(justify mirror)
			)
		)
		(property "License" "Apache-2.0"
			(at 0 0 180)
			(unlocked yes)
			(layer "B.Fab")
			(hide yes)
			(effects
				(font
					(size 1 1)
					(thickness 0.15)
				)
				(justify mirror)
			)
		)
		(property "Author" "Antmicro"
			(at 0 0 180)
			(unlocked yes)
			(layer "B.Fab")
			(hide yes)
			(effects
				(font
					(size 1 1)
					(thickness 0.15)
				)
				(justify mirror)
			)
		)
		(property "Tolerance" "1%"
			(at 0 0 180)
			(unlocked yes)
			(layer "B.Fab")
			(hide yes)
			(effects
				(font
					(size 1 1)
					(thickness 0.15)
				)
				(justify mirror)
			)
		)
		(sheetname "/Supply/DC-DC AUX, MGT/")
		(sheetfile "dc-dc-aux-mgt.kicad_sch")
		(attr smd)
		(fp_rect
			(start -0.925 0.47)
			(end 0.925 -0.47)
			(stroke
				(width 0.05)
				(type default)
			)
			(fill no)
			(layer "B.CrtYd")
		)
		(fp_rect
			(start -0.5 0.25)
			(end 0.5 -0.25)
			(stroke
				(width 0.15)
				(type solid)
			)
			(fill no)
			(layer "B.Fab")
		)
		(fp_text user "${REFERENCE}"
			(at -0.95 -3.168 0)
			(layer "B.Fab")
			(effects
				(font
					(size 0.7 0.7)
					(thickness 0.15)
				)
				(justify left bottom mirror)
			)
		)
		(fp_text user "License: Apache-2.0"
			(at -0.95 -5.169 0)
			(layer "B.Fab")
			(effects
				(font
					(size 0.7 0.7)
					(thickness 0.15)
				)
				(justify left bottom mirror)
			)
		)
		(fp_text user "Author: Antmicro"
			(at -0.95 -4.169 0)
			(layer "B.Fab")
			(effects
				(font
					(size 0.7 0.7)
					(thickness 0.15)
				)
				(justify left bottom mirror)
			)
		)
		(pad "1" smd roundrect
			(at -0.48 0 180)
			(size 0.59 0.64)
			(layers "B.Cu" "B.Mask" "B.Paste")
			(roundrect_rratio 0.25)
			(net 711 "Net-(U3-~{ALERT})")
			(pintype "passive")
		)
		(pad "2" smd roundrect
			(at 0.48 0 180)
			(size 0.59 0.64)
			(layers "B.Cu" "B.Mask" "B.Paste")
			(roundrect_rratio 0.25)
			(net 38 "+3V3_AON")
			(pintype "passive")
		)
	)
	(footprint "antmicro-footprints:C_0402_1005Metric_EIA"
		(layer "B.Cu")
		(at 190 152.5 90)
		(descr "Capacitor SMD 0402 (1005 Metric), square (rectangular) end terminal, IPC_7351 nominal, (Body size source: IPC-SM-782 page 76, https://www.pcb-3d.com/wordpress/wp-content/uploads/ipc-sm-782a_amendment_1_and_2.pdf)")
		(tags "capacitor 0402")
		(property "Reference" "C69"
			(at 11.925 -30.625 270)
			(layer "B.SilkS")
			(effects
				(font
					(size 0.7 0.7)
					(thickness 0.15)
				)
				(justify left bottom mirror)
			)
		)
		(property "Value" "C_100n_0402"
			(at 0 -1.169 270)
			(layer "B.Fab")
			(effects
				(font
					(size 0.7 0.7)
					(thickness 0.15)
				)
				(justify left bottom mirror)
			)
		)
		(property "Datasheet" "https://www.murata.com/products/productdetail?partno=GRM155R61H104KE14%23"
			(at 0 0 90)
			(layer "F.Fab")
			(hide yes)
			(effects
				(font
					(size 1.27 1.27)
					(thickness 0.15)
				)
			)
		)
		(property "Manufacturer" "Murata"
			(at 0 0 90)
			(unlocked yes)
			(layer "B.Fab")
			(hide yes)
			(effects
				(font
					(size 1 1)
					(thickness 0.15)
				)
				(justify mirror)
			)
		)
		(property "MPN" "GRM155R61H104KE14D"
			(at 0 0 90)
			(unlocked yes)
			(layer "B.Fab")
			(hide yes)
			(effects
				(font
					(size 1 1)
					(thickness 0.15)
				)
				(justify mirror)
			)
		)
		(property "Val" "100n"
			(at 0 0 90)
			(unlocked yes)
			(layer "B.Fab")
			(hide yes)
			(effects
				(font
					(size 1 1)
					(thickness 0.15)
				)
				(justify mirror)
			)
		)
		(property "License" "Apache-2.0"
			(at 0 0 90)
			(unlocked yes)
			(layer "B.Fab")
			(hide yes)
			(effects
				(font
					(size 1 1)
					(thickness 0.15)
				)
				(justify mirror)
			)
		)
		(property "Author" "Antmicro"
			(at 0 0 90)
			(unlocked yes)
			(layer "B.Fab")
			(hide yes)
			(effects
				(font
					(size 1 1)
					(thickness 0.15)
				)
				(justify mirror)
			)
		)
		(property "Voltage" "50V"
			(at 0 0 90)
			(unlocked yes)
			(layer "B.Fab")
			(hide yes)
			(effects
				(font
					(size 1 1)
					(thickness 0.15)
				)
				(justify mirror)
			)
		)
		(property "Dielectric" "X5R"
			(at 0 0 90)
			(unlocked yes)
			(layer "B.Fab")
			(hide yes)
			(effects
				(font
					(size 1 1)
					(thickness 0.15)
				)
				(justify mirror)
			)
		)
		(sheetname "/FPGA Config/")
		(sheetfile "fpga-config.kicad_sch")
		(attr smd)
		(fp_rect
			(start -0.95 0.45)
			(end 0.95 -0.45)
			(stroke
				(width 0.05)
				(type default)
			)
			(fill no)
			(layer "B.CrtYd")
		)
		(fp_line
			(start 0.498 -0.248)
			(end -0.5 -0.248)
			(stroke
				(width 0.15)
				(type solid)
			)
			(layer "B.Fab")
		)
		(fp_line
			(start -0.5 -0.248)
			(end -0.5 0.25)
			(stroke
				(width 0.15)
				(type solid)
			)
			(layer "B.Fab")
		)
		(fp_line
			(start 0.498 0.25)
			(end 0.498 -0.248)
			(stroke
				(width 0.15)
				(type solid)
			)
			(layer "B.Fab")
		)
		(fp_line
			(start -0.5 0.25)
			(end 0.498 0.25)
			(stroke
				(width 0.15)
				(type solid)
			)
			(layer "B.Fab")
		)
		(fp_text user "${REFERENCE}"
			(at -0.9656 -3.169 270)
			(layer "B.Fab")
			(effects
				(font
					(size 0.7 0.7)
					(thickness 0.15)
				)
				(justify left bottom mirror)
			)
		)
		(fp_text user "License: Apache-2.0"
			(at -0.9656 -4.369 270)
			(layer "B.Fab")
			(effects
				(font
					(size 0.7 0.7)
					(thickness 0.15)
				)
				(justify left bottom mirror)
			)
		)
		(fp_text user "Author: Antmicro"
			(at -0.9656 -5.569 270)
			(layer "B.Fab")
			(effects
				(font
					(size 0.7 0.7)
					(thickness 0.15)
				)
				(justify left bottom mirror)
			)
		)
		(pad "1" smd roundrect
			(at -0.5 0)
			(size 0.6 0.6)
			(layers "B.Cu" "B.Mask" "B.Paste")
			(roundrect_rratio 0.25)
			(net 598 "/FPGA Config/VREFN")
			(pintype "passive")
		)
		(pad "2" smd roundrect
			(at 0.498 0 90)
			(size 0.6 0.6)
			(layers "B.Cu" "B.Mask" "B.Paste")
			(roundrect_rratio 0.25)
			(net 599 "/FPGA Config/VREFP")
			(pintype "passive")
		)
	)
	(footprint "antmicro-footprints:SC70-3"
		(layer "B.Cu")
		(at 114.755 104.85 180)
		(property "Reference" "Q4"
			(at -3.355 -0.334 0)
			(layer "B.SilkS")
			(effects
				(font
					(size 0.7 0.7)
					(thickness 0.15)
				)
				(justify left bottom mirror)
			)
		)
		(property "Value" "BSS138PW"
			(at 0 -2.3 0)
			(layer "B.Fab")
			(effects
				(font
					(size 0.7 0.7)
					(thickness 0.15)
				)
				(justify left bottom mirror)
			)
		)
		(property "Datasheet" "https://assets.nexperia.com/documents/data-sheet/BSS138PW.pdf"
			(at 0 0 180)
			(layer "F.Fab")
			(hide yes)
			(effects
				(font
					(size 1.27 1.27)
					(thickness 0.15)
				)
			)
		)
		(property "MPN" "BSS138PW"
			(at 0 0 180)
			(unlocked yes)
			(layer "B.Fab")
			(hide yes)
			(effects
				(font
					(size 1 1)
					(thickness 0.15)
				)
				(justify mirror)
			)
		)
		(property "Manufacturer" "Nexperia"
			(at 0 0 180)
			(unlocked yes)
			(layer "B.Fab")
			(hide yes)
			(effects
				(font
					(size 1 1)
					(thickness 0.15)
				)
				(justify mirror)
			)
		)
		(property "Author" "Antmicro"
			(at 0 0 180)
			(unlocked yes)
			(layer "B.Fab")
			(hide yes)
			(effects
				(font
					(size 1 1)
					(thickness 0.15)
				)
				(justify mirror)
			)
		)
		(property "License" "Apache-2.0"
			(at 0 0 180)
			(unlocked yes)
			(layer "B.Fab")
			(hide yes)
			(effects
				(font
					(size 1 1)
					(thickness 0.15)
				)
				(justify mirror)
			)
		)
		(sheetname "/FPGA banks HD/")
		(sheetfile "fpga-hd-banks.kicad_sch")
		(attr smd)
		(fp_line
			(start 0.627 0.6)
			(end 0.627 0.999)
			(stroke
				(width 0.15)
				(type solid)
			)
			(layer "B.SilkS")
		)
		(fp_line
			(start 0.627 -0.6)
			(end 0.627 -1.001)
			(stroke
				(width 0.15)
				(type solid)
			)
			(layer "B.SilkS")
		)
		(fp_line
			(start -0.3 1)
			(end 0.627 0.999)
			(stroke
				(width 0.15)
				(type solid)
			)
			(layer "B.SilkS")
		)
		(fp_line
			(start -0.3 -1)
			(end 0.627 -1.001)
			(stroke
				(width 0.15)
				(type solid)
			)
			(layer "B.SilkS")
		)
		(fp_line
			(start 1.4 0.4)
			(end 1.4 -0.4)
			(stroke
				(width 0.05)
				(type solid)
			)
			(layer "B.CrtYd")
		)
		(fp_line
			(start 1.4 -0.4)
			(end 0.9 -0.4)
			(stroke
				(width 0.05)
				(type solid)
			)
			(layer "B.CrtYd")
		)
		(fp_line
			(start 0.9 1.3)
			(end 0.9 0.4)
			(stroke
				(width 0.05)
				(type solid)
			)
			(layer "B.CrtYd")
		)
		(fp_line
			(start 0.9 0.4)
			(end 1.4 0.4)
			(stroke
				(width 0.05)
				(type solid)
			)
			(layer "B.CrtYd")
		)
		(fp_line
			(start 0.9 -0.4)
			(end 0.9 -1.3)
			(stroke
				(width 0.05)
				(type solid)
			)
			(layer "B.CrtYd")
		)
		(fp_line
			(start 0.9 -1.3)
			(end -0.9 -1.3)
			(stroke
				(width 0.05)
				(type solid)
			)
			(layer "B.CrtYd")
		)
		(fp_line
			(start -0.9 1.3)
			(end 0.9 1.3)
			(stroke
				(width 0.05)
				(type solid)
			)
			(layer "B.CrtYd")
		)
		(fp_line
			(start -0.9 1.3)
			(end -0.9 1)
			(stroke
				(width 0.05)
				(type solid)
			)
			(layer "B.CrtYd")
		)
		(fp_line
			(start -0.9 1)
			(end -1.4 1)
			(stroke
				(width 0.05)
				(type solid)
			)
			(layer "B.CrtYd")
		)
		(fp_line
			(start -0.9 -1)
			(end -1.4 -1)
			(stroke
				(width 0.05)
				(type solid)
			)
			(layer "B.CrtYd")
		)
		(fp_line
			(start -0.9 -1.3)
			(end -0.9 -1)
			(stroke
				(width 0.05)
				(type solid)
			)
			(layer "B.CrtYd")
		)
		(fp_line
			(start -1.4 -1)
			(end -1.4 1)
			(stroke
				(width 0.05)
				(type solid)
			)
			(layer "B.CrtYd")
		)
		(fp_rect
			(start -0.623 0.999)
			(end 0.627 -1.001)
			(stroke
				(width 0.15)
				(type solid)
			)
			(fill no)
			(layer "B.Fab")
		)
		(fp_text user "${REFERENCE}"
			(at -1.45 -4.783 0)
			(layer "B.Fab")
			(effects
				(font
					(size 0.7 0.7)
					(thickness 0.15)
				)
				(justify left bottom mirror)
			)
		)
		(fp_text user "Author: Antmicro"
			(at -1.45 -5.782 0)
			(layer "B.Fab")
			(effects
				(font
					(size 0.7 0.7)
					(thickness 0.15)
				)
				(justify left bottom mirror)
			)
		)
		(fp_text user "License: Apache-2.0"
			(at -1.45 -6.782 0)
			(layer "B.Fab")
			(effects
				(font
					(size 0.7 0.7)
					(thickness 0.15)
				)
				(justify left bottom mirror)
			)
		)
		(pad "1" smd rect
			(at -1.051 0.65 90)
			(size 0.6 0.6)
			(layers "B.Cu" "B.Mask" "B.Paste")
			(net 701 "/FPGA banks HD/USR_LED5")
			(pinfunction "G")
			(pintype "passive")
		)
		(pad "2" smd rect
			(at -1.051 -0.65 90)
			(size 0.6 0.6)
			(layers "B.Cu" "B.Mask" "B.Paste")
			(net 1 "GND")
			(pinfunction "S")
			(pintype "passive")
		)
		(pad "3" smd rect
			(at 1.05 0 90)
			(size 0.6 0.6)
			(layers "B.Cu" "B.Mask" "B.Paste")
			(net 272 "Net-(Q4-D)")
			(pinfunction "D")
			(pintype "passive")
		)
	)
	(footprint "antmicro-footprints:R_0402_1005Metric"
		(layer "B.Cu")
		(at 238.424499 182.499 180)
		(descr "Resistor SMD 0402")
		(tags "resistor SMD 0402")
		(property "Reference" "R159"
			(at -3.95 -0.5 0)
			(layer "B.SilkS")
			(effects
				(font
					(size 0.7 0.7)
					(thickness 0.15)
				)
				(justify left bottom mirror)
			)
		)
		(property "Value" "R_4k7_0402"
			(at -1.011843 -1.772047 0)
			(layer "B.Fab")
			(effects
				(font
					(size 0.7 0.7)
					(thickness 0.15)
				)
				(justify left bottom mirror)
			)
		)
		(property "Datasheet" "https://www.bourns.com/docs/product-datasheets/cr.pdf"
			(at 0 0 180)
			(layer "F.Fab")
			(hide yes)
			(effects
				(font
					(size 1.27 1.27)
					(thickness 0.15)
				)
			)
		)
		(property "Manufacturer" "Bourns"
			(at 0 0 180)
			(unlocked yes)
			(layer "B.Fab")
			(hide yes)
			(effects
				(font
					(size 1 1)
					(thickness 0.15)
				)
				(justify mirror)
			)
		)
		(property "MPN" "CR0402-FX-4701GLF"
			(at 0 0 180)
			(unlocked yes)
			(layer "B.Fab")
			(hide yes)
			(effects
				(font
					(size 1 1)
					(thickness 0.15)
				)
				(justify mirror)
			)
		)
		(property "Val" "4k7"
			(at 0 0 180)
			(unlocked yes)
			(layer "B.Fab")
			(hide yes)
			(effects
				(font
					(size 1 1)
					(thickness 0.15)
				)
				(justify mirror)
			)
		)
		(property "License" "Apache-2.0"
			(at 0 0 180)
			(unlocked yes)
			(layer "B.Fab")
			(hide yes)
			(effects
				(font
					(size 1 1)
					(thickness 0.15)
				)
				(justify mirror)
			)
		)
		(property "Author" "Antmicro"
			(at 0 0 180)
			(unlocked yes)
			(layer "B.Fab")
			(hide yes)
			(effects
				(font
					(size 1 1)
					(thickness 0.15)
				)
				(justify mirror)
			)
		)
		(property "Tolerance" "1%"
			(at 0 0 180)
			(unlocked yes)
			(layer "B.Fab")
			(hide yes)
			(effects
				(font
					(size 1 1)
					(thickness 0.15)
				)
				(justify mirror)
			)
		)
		(sheetname "/I^{2}C + I3C/")
		(sheetfile "i2c.kicad_sch")
		(attr smd)
		(fp_rect
			(start -0.925 0.47)
			(end 0.925 -0.47)
			(stroke
				(width 0.05)
				(type default)
			)
			(fill no)
			(layer "B.CrtYd")
		)
		(fp_rect
			(start -0.5 0.25)
			(end 0.5 -0.25)
			(stroke
				(width 0.15)
				(type solid)
			)
			(fill no)
			(layer "B.Fab")
		)
		(fp_text user "${REFERENCE}"
			(at -0.95 -3.168 0)
			(layer "B.Fab")
			(effects
				(font
					(size 0.7 0.7)
					(thickness 0.15)
				)
				(justify left bottom mirror)
			)
		)
		(fp_text user "Author: Antmicro"
			(at -0.95 -4.169 0)
			(layer "B.Fab")
			(effects
				(font
					(size 0.7 0.7)
					(thickness 0.15)
				)
				(justify left bottom mirror)
			)
		)
		(fp_text user "License: Apache-2.0"
			(at -0.95 -5.169 0)
			(layer "B.Fab")
			(effects
				(font
					(size 0.7 0.7)
					(thickness 0.15)
				)
				(justify left bottom mirror)
			)
		)
		(pad "1" smd roundrect
			(at -0.48 0 180)
			(size 0.59 0.64)
			(layers "B.Cu" "B.Mask" "B.Paste")
			(roundrect_rratio 0.25)
			(net 151 "+3V3")
			(pintype "passive")
		)
		(pad "2" smd roundrect
			(at 0.48 0 180)
			(size 0.59 0.64)
			(layers "B.Cu" "B.Mask" "B.Paste")
			(roundrect_rratio 0.25)
			(net 747 "/FPGA Config/FPGA_PWR.SCL")
			(pintype "passive")
		)
	)
	(footprint "antmicro-footprints:R_0402_1005Metric"
		(layer "B.Cu")
		(at 238.774501 140.0975 180)
		(descr "Resistor SMD 0402")
		(tags "resistor SMD 0402")
		(property "Reference" "R139"
			(at -4.365499 -0.4225 0)
			(layer "B.SilkS")
			(effects
				(font
					(size 0.7 0.7)
					(thickness 0.15)
				)
				(justify left bottom mirror)
			)
		)
		(property "Value" "R_47k_0402"
			(at -1.011843 -1.772047 0)
			(layer "B.Fab")
			(effects
				(font
					(size 0.7 0.7)
					(thickness 0.15)
				)
				(justify left bottom mirror)
			)
		)
		(property "Datasheet" "https://www.bourns.com/docs/product-datasheets/cr.pdf"
			(at 0 0 180)
			(layer "F.Fab")
			(hide yes)
			(effects
				(font
					(size 1.27 1.27)
					(thickness 0.15)
				)
			)
		)
		(property "Manufacturer" "Bourns"
			(at 0 0 180)
			(unlocked yes)
			(layer "B.Fab")
			(hide yes)
			(effects
				(font
					(size 1 1)
					(thickness 0.15)
				)
				(justify mirror)
			)
		)
		(property "MPN" "CR0402-FX-4702GLF"
			(at 0 0 180)
			(unlocked yes)
			(layer "B.Fab")
			(hide yes)
			(effects
				(font
					(size 1 1)
					(thickness 0.15)
				)
				(justify mirror)
			)
		)
		(property "Val" "47k"
			(at 0 0 180)
			(unlocked yes)
			(layer "B.Fab")
			(hide yes)
			(effects
				(font
					(size 1 1)
					(thickness 0.15)
				)
				(justify mirror)
			)
		)
		(property "License" "Apache-2.0"
			(at 0 0 180)
			(unlocked yes)
			(layer "B.Fab")
			(hide yes)
			(effects
				(font
					(size 1 1)
					(thickness 0.15)
				)
				(justify mirror)
			)
		)
		(property "Author" "Antmicro"
			(at 0 0 180)
			(unlocked yes)
			(layer "B.Fab")
			(hide yes)
			(effects
				(font
					(size 1 1)
					(thickness 0.15)
				)
				(justify mirror)
			)
		)
		(property "Tolerance" "1%"
			(at 0 0 180)
			(unlocked yes)
			(layer "B.Fab")
			(hide yes)
			(effects
				(font
					(size 1 1)
					(thickness 0.15)
				)
				(justify mirror)
			)
		)
		(sheetname "/Supply/")
		(sheetfile "supply.kicad_sch")
		(attr smd)
		(fp_rect
			(start -0.925 0.47)
			(end 0.925 -0.47)
			(stroke
				(width 0.05)
				(type default)
			)
			(fill no)
			(layer "B.CrtYd")
		)
		(fp_rect
			(start -0.5 0.25)
			(end 0.5 -0.25)
			(stroke
				(width 0.15)
				(type solid)
			)
			(fill no)
			(layer "B.Fab")
		)
		(fp_text user "${REFERENCE}"
			(at -0.95 -3.168 0)
			(layer "B.Fab")
			(effects
				(font
					(size 0.7 0.7)
					(thickness 0.15)
				)
				(justify left bottom mirror)
			)
		)
		(fp_text user "Author: Antmicro"
			(at -0.95 -4.169 0)
			(layer "B.Fab")
			(effects
				(font
					(size 0.7 0.7)
					(thickness 0.15)
				)
				(justify left bottom mirror)
			)
		)
		(fp_text user "License: Apache-2.0"
			(at -0.95 -5.169 0)
			(layer "B.Fab")
			(effects
				(font
					(size 0.7 0.7)
					(thickness 0.15)
				)
				(justify left bottom mirror)
			)
		)
		(pad "1" smd roundrect
			(at -0.48 0 180)
			(size 0.59 0.64)
			(layers "B.Cu" "B.Mask" "B.Paste")
			(roundrect_rratio 0.25)
			(net 404 "IN1")
			(pintype "passive")
		)
		(pad "2" smd roundrect
			(at 0.48 0 180)
			(size 0.59 0.64)
			(layers "B.Cu" "B.Mask" "B.Paste")
			(roundrect_rratio 0.25)
			(net 38 "+3V3_AON")
			(pintype "passive")
		)
	)
	(footprint "antmicro-footprints:R_0402_1005Metric"
		(layer "B.Cu")
		(at 221.03 182.995)
		(descr "Resistor SMD 0402")
		(tags "resistor SMD 0402")
		(property "Reference" "R189"
			(at -3.83 0.505 0)
			(layer "B.SilkS")
			(effects
				(font
					(size 0.7 0.7)
					(thickness 0.15)
				)
				(justify right bottom mirror)
			)
		)
		(property "Value" "R_60k4_0402"
			(at -1.011843 -1.772047 0)
			(layer "B.Fab")
			(effects
				(font
					(size 0.7 0.7)
					(thickness 0.15)
				)
				(justify right bottom mirror)
			)
		)
		(property "Datasheet" "https://www.bourns.com/docs/product-datasheets/cr.pdf"
			(at 0 0 0)
			(layer "F.Fab")
			(hide yes)
			(effects
				(font
					(size 1.27 1.27)
					(thickness 0.15)
				)
			)
		)
		(property "MPN" "CR0402-FX-6042GLF"
			(at 0 0 0)
			(unlocked yes)
			(layer "B.Fab")
			(hide yes)
			(effects
				(font
					(size 1 1)
					(thickness 0.15)
				)
				(justify mirror)
			)
		)
		(property "Manufacturer" "Bourns"
			(at 0 0 0)
			(unlocked yes)
			(layer "B.Fab")
			(hide yes)
			(effects
				(font
					(size 1 1)
					(thickness 0.15)
				)
				(justify mirror)
			)
		)
		(property "License" "Apache-2.0"
			(at 0 0 0)
			(unlocked yes)
			(layer "B.Fab")
			(hide yes)
			(effects
				(font
					(size 1 1)
					(thickness 0.15)
				)
				(justify mirror)
			)
		)
		(property "Author" "Antmicro"
			(at 0 0 0)
			(unlocked yes)
			(layer "B.Fab")
			(hide yes)
			(effects
				(font
					(size 1 1)
					(thickness 0.15)
				)
				(justify mirror)
			)
		)
		(property "Val" "60k4"
			(at 0 0 0)
			(unlocked yes)
			(layer "B.Fab")
			(hide yes)
			(effects
				(font
					(size 1 1)
					(thickness 0.15)
				)
				(justify mirror)
			)
		)
		(property "Tolerance" "1%"
			(at 0 0 0)
			(unlocked yes)
			(layer "B.Fab")
			(hide yes)
			(effects
				(font
					(size 1 1)
					(thickness 0.15)
				)
				(justify mirror)
			)
		)
		(sheetname "/Supply/DC-DC VCCINT/")
		(sheetfile "dc-dc-vccint.kicad_sch")
		(attr smd)
		(fp_rect
			(start -0.925 0.47)
			(end 0.925 -0.47)
			(stroke
				(width 0.05)
				(type default)
			)
			(fill no)
			(layer "B.CrtYd")
		)
		(fp_rect
			(start -0.5 0.25)
			(end 0.5 -0.25)
			(stroke
				(width 0.15)
				(type solid)
			)
			(fill no)
			(layer "B.Fab")
		)
		(fp_text user "License: Apache-2.0"
			(at -0.95 -5.169 180)
			(layer "B.Fab")
			(effects
				(font
					(size 0.7 0.7)
					(thickness 0.15)
				)
				(justify left bottom mirror)
			)
		)
		(fp_text user "Author: Antmicro"
			(at -0.95 -4.169 180)
			(layer "B.Fab")
			(effects
				(font
					(size 0.7 0.7)
					(thickness 0.15)
				)
				(justify left bottom mirror)
			)
		)
		(fp_text user "${REFERENCE}"
			(at -0.95 -3.168 180)
			(layer "B.Fab")
			(effects
				(font
					(size 0.7 0.7)
					(thickness 0.15)
				)
				(justify left bottom mirror)
			)
		)
		(pad "1" smd roundrect
			(at -0.48 0)
			(size 0.59 0.64)
			(layers "B.Cu" "B.Mask" "B.Paste")
			(roundrect_rratio 0.25)
			(net 1 "GND")
			(pintype "passive")
		)
		(pad "2" smd roundrect
			(at 0.48 0)
			(size 0.59 0.64)
			(layers "B.Cu" "B.Mask" "B.Paste")
			(roundrect_rratio 0.25)
			(net 725 "Net-(U4-I_{REF})")
			(pintype "passive")
		)
	)
	(footprint "antmicro-footprints:C_0402_1005Metric_EIA"
		(layer "B.Cu")
		(at 192 150.502 -90)
		(descr "Capacitor SMD 0402 (1005 Metric), square (rectangular) end terminal, IPC_7351 nominal, (Body size source: IPC-SM-782 page 76, https://www.pcb-3d.com/wordpress/wp-content/uploads/ipc-sm-782a_amendment_1_and_2.pdf)")
		(tags "capacitor 0402")
		(property "Reference" "C243"
			(at -12.227 30.65 90)
			(layer "B.SilkS")
			(effects
				(font
					(size 0.7 0.7)
					(thickness 0.15)
				)
				(justify left bottom mirror)
			)
		)
		(property "Value" "C_10u_10V_0402"
			(at 0 -1.169 90)
			(layer "B.Fab")
			(effects
				(font
					(size 0.7 0.7)
					(thickness 0.15)
				)
				(justify left bottom mirror)
			)
		)
		(property "Datasheet" "https://www.murata.com/products/productdetail?partno=GRM155R61A106ME11%23"
			(at 0 0 270)
			(layer "F.Fab")
			(hide yes)
			(effects
				(font
					(size 1.27 1.27)
					(thickness 0.15)
				)
			)
		)
		(property "MPN" "GRM155R61A106ME11D"
			(at 0 0 270)
			(unlocked yes)
			(layer "B.Fab")
			(hide yes)
			(effects
				(font
					(size 1 1)
					(thickness 0.15)
				)
				(justify mirror)
			)
		)
		(property "Manufacturer" "Murata"
			(at 0 0 270)
			(unlocked yes)
			(layer "B.Fab")
			(hide yes)
			(effects
				(font
					(size 1 1)
					(thickness 0.15)
				)
				(justify mirror)
			)
		)
		(property "License" "Apache-2.0"
			(at 0 0 270)
			(unlocked yes)
			(layer "B.Fab")
			(hide yes)
			(effects
				(font
					(size 1 1)
					(thickness 0.15)
				)
				(justify mirror)
			)
		)
		(property "Author" "Antmicro"
			(at 0 0 270)
			(unlocked yes)
			(layer "B.Fab")
			(hide yes)
			(effects
				(font
					(size 1 1)
					(thickness 0.15)
				)
				(justify mirror)
			)
		)
		(property "Val" "10u"
			(at 0 0 270)
			(unlocked yes)
			(layer "B.Fab")
			(hide yes)
			(effects
				(font
					(size 1 1)
					(thickness 0.15)
				)
				(justify mirror)
			)
		)
		(property "Voltage" "10V"
			(at 0 0 270)
			(unlocked yes)
			(layer "B.Fab")
			(hide yes)
			(effects
				(font
					(size 1 1)
					(thickness 0.15)
				)
				(justify mirror)
			)
		)
		(property "Dielectric" "X5R"
			(at 0 0 270)
			(unlocked yes)
			(layer "B.Fab")
			(hide yes)
			(effects
				(font
					(size 1 1)
					(thickness 0.15)
				)
				(justify mirror)
			)
		)
		(sheetname "/FPGA power/")
		(sheetfile "fpga-power.kicad_sch")
		(attr smd)
		(fp_rect
			(start -0.95 0.45)
			(end 0.95 -0.45)
			(stroke
				(width 0.05)
				(type default)
			)
			(fill no)
			(layer "B.CrtYd")
		)
		(fp_line
			(start -0.5 0.25)
			(end 0.498 0.25)
			(stroke
				(width 0.15)
				(type solid)
			)
			(layer "B.Fab")
		)
		(fp_line
			(start 0.498 0.25)
			(end 0.498 -0.248)
			(stroke
				(width 0.15)
				(type solid)
			)
			(layer "B.Fab")
		)
		(fp_line
			(start -0.5 -0.248)
			(end -0.5 0.25)
			(stroke
				(width 0.15)
				(type solid)
			)
			(layer "B.Fab")
		)
		(fp_line
			(start 0.498 -0.248)
			(end -0.5 -0.248)
			(stroke
				(width 0.15)
				(type solid)
			)
			(layer "B.Fab")
		)
		(fp_text user "License: Apache-2.0"
			(at -0.9656 -4.369 90)
			(layer "B.Fab")
			(effects
				(font
					(size 0.7 0.7)
					(thickness 0.15)
				)
				(justify left bottom mirror)
			)
		)
		(fp_text user "${REFERENCE}"
			(at -0.9656 -3.169 90)
			(layer "B.Fab")
			(effects
				(font
					(size 0.7 0.7)
					(thickness 0.15)
				)
				(justify left bottom mirror)
			)
		)
		(fp_text user "Author: Antmicro"
			(at -0.9656 -5.569 90)
			(layer "B.Fab")
			(effects
				(font
					(size 0.7 0.7)
					(thickness 0.15)
				)
				(justify left bottom mirror)
			)
		)
		(pad "1" smd roundrect
			(at -0.5 0 180)
			(size 0.6 0.6)
			(layers "B.Cu" "B.Mask" "B.Paste")
			(roundrect_rratio 0.25)
			(net 1 "GND")
			(pintype "passive")
		)
		(pad "2" smd roundrect
			(at 0.498 0 270)
			(size 0.6 0.6)
			(layers "B.Cu" "B.Mask" "B.Paste")
			(roundrect_rratio 0.25)
			(net 553 "+0V85")
			(pintype "passive")
		)
	)
	(footprint "antmicro-footprints:C_0402_1005Metric"
		(layer "B.Cu")
		(at 167.65 193.299501 90)
		(descr "Capacitor SMD 0402")
		(tags "capacitor SMD 0402")
		(property "Reference" "C228"
			(at 0.994 0.403501 90)
			(layer "B.SilkS")
			(effects
				(font
					(size 0.7 0.7)
					(thickness 0.15)
				)
				(justify right bottom mirror)
			)
		)
		(property "Value" "C_100n_0402"
			(at -1.022927 -2.155213 90)
			(layer "B.Fab")
			(effects
				(font
					(size 0.7 0.7)
					(thickness 0.15)
				)
				(justify right bottom mirror)
			)
		)
		(property "Datasheet" "https://www.murata.com/products/productdetail?partno=GRM155R61H104KE14%23"
			(at 0 0 90)
			(layer "F.Fab")
			(hide yes)
			(effects
				(font
					(size 1.27 1.27)
					(thickness 0.15)
				)
			)
		)
		(property "Manufacturer" "Murata"
			(at 0 0 90)
			(unlocked yes)
			(layer "B.Fab")
			(hide yes)
			(effects
				(font
					(size 1 1)
					(thickness 0.15)
				)
				(justify mirror)
			)
		)
		(property "MPN" "GRM155R61H104KE14D"
			(at 0 0 90)
			(unlocked yes)
			(layer "B.Fab")
			(hide yes)
			(effects
				(font
					(size 1 1)
					(thickness 0.15)
				)
				(justify mirror)
			)
		)
		(property "Val" "100n"
			(at 0 0 90)
			(unlocked yes)
			(layer "B.Fab")
			(hide yes)
			(effects
				(font
					(size 1 1)
					(thickness 0.15)
				)
				(justify mirror)
			)
		)
		(property "License" "Apache-2.0"
			(at 0 0 90)
			(unlocked yes)
			(layer "B.Fab")
			(hide yes)
			(effects
				(font
					(size 1 1)
					(thickness 0.15)
				)
				(justify mirror)
			)
		)
		(property "Author" "Antmicro"
			(at 0 0 90)
			(unlocked yes)
			(layer "B.Fab")
			(hide yes)
			(effects
				(font
					(size 1 1)
					(thickness 0.15)
				)
				(justify mirror)
			)
		)
		(property "Voltage" "50V"
			(at 0 0 90)
			(unlocked yes)
			(layer "B.Fab")
			(hide yes)
			(effects
				(font
					(size 1 1)
					(thickness 0.15)
				)
				(justify mirror)
			)
		)
		(property "Dielectric" "X5R"
			(at 0 0 90)
			(unlocked yes)
			(layer "B.Fab")
			(hide yes)
			(effects
				(font
					(size 1 1)
					(thickness 0.15)
				)
				(justify mirror)
			)
		)
		(sheetname "/FPGA MGT Interface/")
		(sheetfile "fpga-mgt.kicad_sch")
		(attr smd)
		(fp_rect
			(start -0.925 0.47)
			(end 0.925 -0.47)
			(stroke
				(width 0.05)
				(type default)
			)
			(fill no)
			(layer "B.CrtYd")
		)
		(fp_line
			(start 0.504 -0.248)
			(end -0.494 -0.248)
			(stroke
				(width 0.15)
				(type solid)
			)
			(layer "B.Fab")
		)
		(fp_line
			(start -0.494 -0.248)
			(end -0.494 0.25)
			(stroke
				(width 0.15)
				(type solid)
			)
			(layer "B.Fab")
		)
		(fp_line
			(start 0.504 0.25)
			(end 0.504 -0.248)
			(stroke
				(width 0.15)
				(type solid)
			)
			(layer "B.Fab")
		)
		(fp_line
			(start -0.494 0.25)
			(end 0.504 0.25)
			(stroke
				(width 0.15)
				(type solid)
			)
			(layer "B.Fab")
		)
		(fp_text user "Author: Antmicro"
			(at -0.939 -3.399 270)
			(layer "B.Fab")
			(effects
				(font
					(size 0.7 0.7)
					(thickness 0.15)
				)
				(justify left bottom mirror)
			)
		)
		(fp_text user "${REFERENCE}"
			(at -0.939 -4.599 270)
			(layer "B.Fab")
			(effects
				(font
					(size 0.7 0.7)
					(thickness 0.15)
				)
				(justify left bottom mirror)
			)
		)
		(fp_text user "License: Apache-2.0"
			(at -0.939 -5.799 270)
			(layer "B.Fab")
			(effects
				(font
					(size 0.7 0.7)
					(thickness 0.15)
				)
				(justify left bottom mirror)
			)
		)
		(pad "1" smd roundrect
			(at -0.48 0 90)
			(size 0.59 0.64)
			(layers "B.Cu" "B.Mask" "B.Paste")
			(roundrect_rratio 0.25)
			(net 19 "/FPGA MGT Interface/PCIE.TXD1_P")
			(pintype "passive")
		)
		(pad "2" smd roundrect
			(at 0.48 0 90)
			(size 0.59 0.64)
			(layers "B.Cu" "B.Mask" "B.Paste")
			(roundrect_rratio 0.25)
			(net 20 "/FPGA MGT Interface/GTY_225_TX2_P")
			(pintype "passive")
		)
	)
	(footprint "antmicro-footprints:C_0402_1005Metric_EIA"
		(layer "B.Cu")
		(at 197 162.5 90)
		(descr "Capacitor SMD 0402 (1005 Metric), square (rectangular) end terminal, IPC_7351 nominal, (Body size source: IPC-SM-782 page 76, https://www.pcb-3d.com/wordpress/wp-content/uploads/ipc-sm-782a_amendment_1_and_2.pdf)")
		(tags "capacitor 0402")
		(property "Reference" "C106"
			(at -3.95 0.2 90)
			(layer "B.SilkS")
			(effects
				(font
					(size 0.7 0.7)
					(thickness 0.15)
				)
				(justify right bottom mirror)
			)
		)
		(property "Value" "C_100n_0402"
			(at 0 -1.169 90)
			(layer "B.Fab")
			(effects
				(font
					(size 0.7 0.7)
					(thickness 0.15)
				)
				(justify right bottom mirror)
			)
		)
		(property "Datasheet" "https://www.murata.com/products/productdetail?partno=GRM155R61H104KE14%23"
			(at 0 0 90)
			(layer "F.Fab")
			(hide yes)
			(effects
				(font
					(size 1.27 1.27)
					(thickness 0.15)
				)
			)
		)
		(property "MPN" "GRM155R61H104KE14D"
			(at 0 0 90)
			(unlocked yes)
			(layer "B.Fab")
			(hide yes)
			(effects
				(font
					(size 1 1)
					(thickness 0.15)
				)
				(justify mirror)
			)
		)
		(property "Manufacturer" "Murata"
			(at 0 0 90)
			(unlocked yes)
			(layer "B.Fab")
			(hide yes)
			(effects
				(font
					(size 1 1)
					(thickness 0.15)
				)
				(justify mirror)
			)
		)
		(property "License" "Apache-2.0"
			(at 0 0 90)
			(unlocked yes)
			(layer "B.Fab")
			(hide yes)
			(effects
				(font
					(size 1 1)
					(thickness 0.15)
				)
				(justify mirror)
			)
		)
		(property "Author" "Antmicro"
			(at 0 0 90)
			(unlocked yes)
			(layer "B.Fab")
			(hide yes)
			(effects
				(font
					(size 1 1)
					(thickness 0.15)
				)
				(justify mirror)
			)
		)
		(property "Val" "100n"
			(at 0 0 90)
			(unlocked yes)
			(layer "B.Fab")
			(hide yes)
			(effects
				(font
					(size 1 1)
					(thickness 0.15)
				)
				(justify mirror)
			)
		)
		(property "Voltage" "50V"
			(at 0 0 90)
			(unlocked yes)
			(layer "B.Fab")
			(hide yes)
			(effects
				(font
					(size 1 1)
					(thickness 0.15)
				)
				(justify mirror)
			)
		)
		(property "Dielectric" "X5R"
			(at 0 0 90)
			(unlocked yes)
			(layer "B.Fab")
			(hide yes)
			(effects
				(font
					(size 1 1)
					(thickness 0.15)
				)
				(justify mirror)
			)
		)
		(sheetname "/FPGA power/")
		(sheetfile "fpga-power.kicad_sch")
		(attr smd)
		(fp_rect
			(start -0.95 0.45)
			(end 0.95 -0.45)
			(stroke
				(width 0.05)
				(type default)
			)
			(fill no)
			(layer "B.CrtYd")
		)
		(fp_line
			(start 0.498 -0.248)
			(end -0.5 -0.248)
			(stroke
				(width 0.15)
				(type solid)
			)
			(layer "B.Fab")
		)
		(fp_line
			(start -0.5 -0.248)
			(end -0.5 0.25)
			(stroke
				(width 0.15)
				(type solid)
			)
			(layer "B.Fab")
		)
		(fp_line
			(start 0.498 0.25)
			(end 0.498 -0.248)
			(stroke
				(width 0.15)
				(type solid)
			)
			(layer "B.Fab")
		)
		(fp_line
			(start -0.5 0.25)
			(end 0.498 0.25)
			(stroke
				(width 0.15)
				(type solid)
			)
			(layer "B.Fab")
		)
		(fp_text user "License: Apache-2.0"
			(at -0.9656 -4.369 270)
			(layer "B.Fab")
			(effects
				(font
					(size 0.7 0.7)
					(thickness 0.15)
				)
				(justify left bottom mirror)
			)
		)
		(fp_text user "Author: Antmicro"
			(at -0.9656 -5.569 270)
			(layer "B.Fab")
			(effects
				(font
					(size 0.7 0.7)
					(thickness 0.15)
				)
				(justify left bottom mirror)
			)
		)
		(fp_text user "${REFERENCE}"
			(at -0.9656 -3.169 270)
			(layer "B.Fab")
			(effects
				(font
					(size 0.7 0.7)
					(thickness 0.15)
				)
				(justify left bottom mirror)
			)
		)
		(pad "1" smd roundrect
			(at -0.5 0)
			(size 0.6 0.6)
			(layers "B.Cu" "B.Mask" "B.Paste")
			(roundrect_rratio 0.25)
			(net 1 "GND")
			(pintype "passive")
		)
		(pad "2" smd roundrect
			(at 0.498 0 90)
			(size 0.6 0.6)
			(layers "B.Cu" "B.Mask" "B.Paste")
			(roundrect_rratio 0.25)
			(net 172 "+1V2_MGTAVTT")
			(pintype "passive")
		)
	)
	(footprint "antmicro-footprints:C_0402_1005Metric_EIA"
		(layer "B.Cu")
		(at 186 158.499999 90)
		(descr "Capacitor SMD 0402 (1005 Metric), square (rectangular) end terminal, IPC_7351 nominal, (Body size source: IPC-SM-782 page 76, https://www.pcb-3d.com/wordpress/wp-content/uploads/ipc-sm-782a_amendment_1_and_2.pdf)")
		(tags "capacitor 0402")
		(property "Reference" "C51"
			(at 9.524999 -30.625 90)
			(layer "B.SilkS")
			(effects
				(font
					(size 0.7 0.7)
					(thickness 0.15)
				)
				(justify right bottom mirror)
			)
		)
		(property "Value" "C_1u_25V_0402"
			(at 0 -1.169 90)
			(layer "B.Fab")
			(effects
				(font
					(size 0.7 0.7)
					(thickness 0.15)
				)
				(justify right bottom mirror)
			)
		)
		(property "Datasheet" "https://www.murata.com/products/productdetail?partno=GRM155R61E105KE11%23"
			(at 0 0 90)
			(layer "F.Fab")
			(hide yes)
			(effects
				(font
					(size 1.27 1.27)
					(thickness 0.15)
				)
			)
		)
		(property "MPN" "GRM155R61E105KE11J"
			(at 0 0 90)
			(unlocked yes)
			(layer "B.Fab")
			(hide yes)
			(effects
				(font
					(size 1 1)
					(thickness 0.15)
				)
				(justify mirror)
			)
		)
		(property "Manufacturer" "Murata"
			(at 0 0 90)
			(unlocked yes)
			(layer "B.Fab")
			(hide yes)
			(effects
				(font
					(size 1 1)
					(thickness 0.15)
				)
				(justify mirror)
			)
		)
		(property "License" "Apache-2.0"
			(at 0 0 90)
			(unlocked yes)
			(layer "B.Fab")
			(hide yes)
			(effects
				(font
					(size 1 1)
					(thickness 0.15)
				)
				(justify mirror)
			)
		)
		(property "Author" "Antmicro"
			(at 0 0 90)
			(unlocked yes)
			(layer "B.Fab")
			(hide yes)
			(effects
				(font
					(size 1 1)
					(thickness 0.15)
				)
				(justify mirror)
			)
		)
		(property "Val" "1u"
			(at 0 0 90)
			(unlocked yes)
			(layer "B.Fab")
			(hide yes)
			(effects
				(font
					(size 1 1)
					(thickness 0.15)
				)
				(justify mirror)
			)
		)
		(property "Voltage" "25V"
			(at 0 0 90)
			(unlocked yes)
			(layer "B.Fab")
			(hide yes)
			(effects
				(font
					(size 1 1)
					(thickness 0.15)
				)
				(justify mirror)
			)
		)
		(property "Dielectric" "X5R"
			(at 0 0 90)
			(unlocked yes)
			(layer "B.Fab")
			(hide yes)
			(effects
				(font
					(size 1 1)
					(thickness 0.15)
				)
				(justify mirror)
			)
		)
		(sheetname "/FPGA power/")
		(sheetfile "fpga-power.kicad_sch")
		(attr smd)
		(fp_rect
			(start -0.95 0.45)
			(end 0.95 -0.45)
			(stroke
				(width 0.05)
				(type default)
			)
			(fill no)
			(layer "B.CrtYd")
		)
		(fp_line
			(start 0.498 -0.248)
			(end -0.5 -0.248)
			(stroke
				(width 0.15)
				(type solid)
			)
			(layer "B.Fab")
		)
		(fp_line
			(start -0.5 -0.248)
			(end -0.5 0.25)
			(stroke
				(width 0.15)
				(type solid)
			)
			(layer "B.Fab")
		)
		(fp_line
			(start 0.498 0.25)
			(end 0.498 -0.248)
			(stroke
				(width 0.15)
				(type solid)
			)
			(layer "B.Fab")
		)
		(fp_line
			(start -0.5 0.25)
			(end 0.498 0.25)
			(stroke
				(width 0.15)
				(type solid)
			)
			(layer "B.Fab")
		)
		(fp_text user "Author: Antmicro"
			(at -0.9656 -5.569 270)
			(layer "B.Fab")
			(effects
				(font
					(size 0.7 0.7)
					(thickness 0.15)
				)
				(justify left bottom mirror)
			)
		)
		(fp_text user "License: Apache-2.0"
			(at -0.9656 -4.369 270)
			(layer "B.Fab")
			(effects
				(font
					(size 0.7 0.7)
					(thickness 0.15)
				)
				(justify left bottom mirror)
			)
		)
		(fp_text user "${REFERENCE}"
			(at -0.9656 -3.169 270)
			(layer "B.Fab")
			(effects
				(font
					(size 0.7 0.7)
					(thickness 0.15)
				)
				(justify left bottom mirror)
			)
		)
		(pad "1" smd roundrect
			(at -0.5 0)
			(size 0.6 0.6)
			(layers "B.Cu" "B.Mask" "B.Paste")
			(roundrect_rratio 0.25)
			(net 1 "GND")
			(pintype "passive")
		)
		(pad "2" smd roundrect
			(at 0.498 0 90)
			(size 0.6 0.6)
			(layers "B.Cu" "B.Mask" "B.Paste")
			(roundrect_rratio 0.25)
			(net 553 "+0V85")
			(pintype "passive")
		)
	)
	(footprint "antmicro-footprints:R_0402_1005Metric"
		(layer "B.Cu")
		(at 208.275 154.19 -90)
		(descr "Resistor SMD 0402")
		(tags "resistor SMD 0402")
		(property "Reference" "R20"
			(at 1.36 -0.475 90)
			(layer "B.SilkS")
			(effects
				(font
					(size 0.7 0.7)
					(thickness 0.15)
				)
				(justify left bottom mirror)
			)
		)
		(property "Value" "R_4k7_0402"
			(at -1.011843 -1.772047 90)
			(layer "B.Fab")
			(effects
				(font
					(size 0.7 0.7)
					(thickness 0.15)
				)
				(justify left bottom mirror)
			)
		)
		(property "Datasheet" "https://www.bourns.com/docs/product-datasheets/cr.pdf"
			(at 0 0 270)
			(layer "F.Fab")
			(hide yes)
			(effects
				(font
					(size 1.27 1.27)
					(thickness 0.15)
				)
			)
		)
		(property "MPN" "CR0402-FX-4701GLF"
			(at 0 0 270)
			(unlocked yes)
			(layer "B.Fab")
			(hide yes)
			(effects
				(font
					(size 1 1)
					(thickness 0.15)
				)
				(justify mirror)
			)
		)
		(property "Manufacturer" "Bourns"
			(at 0 0 270)
			(unlocked yes)
			(layer "B.Fab")
			(hide yes)
			(effects
				(font
					(size 1 1)
					(thickness 0.15)
				)
				(justify mirror)
			)
		)
		(property "License" "Apache-2.0"
			(at 0 0 270)
			(unlocked yes)
			(layer "B.Fab")
			(hide yes)
			(effects
				(font
					(size 1 1)
					(thickness 0.15)
				)
				(justify mirror)
			)
		)
		(property "Author" "Antmicro"
			(at 0 0 270)
			(unlocked yes)
			(layer "B.Fab")
			(hide yes)
			(effects
				(font
					(size 1 1)
					(thickness 0.15)
				)
				(justify mirror)
			)
		)
		(property "Val" "4k7"
			(at 0 0 270)
			(unlocked yes)
			(layer "B.Fab")
			(hide yes)
			(effects
				(font
					(size 1 1)
					(thickness 0.15)
				)
				(justify mirror)
			)
		)
		(property "Tolerance" "1%"
			(at 0 0 270)
			(unlocked yes)
			(layer "B.Fab")
			(hide yes)
			(effects
				(font
					(size 1 1)
					(thickness 0.15)
				)
				(justify mirror)
			)
		)
		(sheetname "/FPGA Config/")
		(sheetfile "fpga-config.kicad_sch")
		(attr smd)
		(fp_rect
			(start -0.925 0.47)
			(end 0.925 -0.47)
			(stroke
				(width 0.05)
				(type default)
			)
			(fill no)
			(layer "B.CrtYd")
		)
		(fp_rect
			(start -0.5 0.25)
			(end 0.5 -0.25)
			(stroke
				(width 0.15)
				(type solid)
			)
			(fill no)
			(layer "B.Fab")
		)
		(fp_text user "License: Apache-2.0"
			(at -0.95 -5.169 90)
			(layer "B.Fab")
			(effects
				(font
					(size 0.7 0.7)
					(thickness 0.15)
				)
				(justify left bottom mirror)
			)
		)
		(fp_text user "Author: Antmicro"
			(at -0.95 -4.169 90)
			(layer "B.Fab")
			(effects
				(font
					(size 0.7 0.7)
					(thickness 0.15)
				)
				(justify left bottom mirror)
			)
		)
		(fp_text user "${REFERENCE}"
			(at -0.95 -3.168 90)
			(layer "B.Fab")
			(effects
				(font
					(size 0.7 0.7)
					(thickness 0.15)
				)
				(justify left bottom mirror)
			)
		)
		(pad "1" smd roundrect
			(at -0.48 0 270)
			(size 0.59 0.64)
			(layers "B.Cu" "B.Mask" "B.Paste")
			(roundrect_rratio 0.25)
			(net 151 "+3V3")
			(pintype "passive")
		)
		(pad "2" smd roundrect
			(at 0.48 0 270)
			(size 0.59 0.64)
			(layers "B.Cu" "B.Mask" "B.Paste")
			(roundrect_rratio 0.25)
			(net 477 "/FPGA Config/~{ALARM}")
			(pintype "passive")
		)
	)
	(footprint "antmicro-footprints:C_0603_1608Metric"
		(layer "B.Cu")
		(at 230.154999 172.080002 90)
		(descr "Capacitor SMD 0603")
		(tags "capacitor 0603")
		(property "Reference" "C272"
			(at -4.069998 0.320001 90)
			(layer "B.SilkS")
			(effects
				(font
					(size 0.7 0.7)
					(thickness 0.15)
				)
				(justify right bottom mirror)
			)
		)
		(property "Value" "C_22u_0603"
			(at -1.42757 -1.770288 90)
			(layer "B.Fab")
			(effects
				(font
					(size 0.7 0.7)
					(thickness 0.15)
				)
				(justify right bottom mirror)
			)
		)
		(property "Datasheet" "https://www.murata.com/products/productdetail?partno=GRM188R60J226MEA0%23"
			(at 0 0 90)
			(layer "F.Fab")
			(hide yes)
			(effects
				(font
					(size 1.27 1.27)
					(thickness 0.15)
				)
			)
		)
		(property "Manufacturer" "Murata"
			(at 0 0 90)
			(unlocked yes)
			(layer "B.Fab")
			(hide yes)
			(effects
				(font
					(size 1 1)
					(thickness 0.15)
				)
				(justify mirror)
			)
		)
		(property "MPN" "GRM188R60J226MEA0D"
			(at 0 0 90)
			(unlocked yes)
			(layer "B.Fab")
			(hide yes)
			(effects
				(font
					(size 1 1)
					(thickness 0.15)
				)
				(justify mirror)
			)
		)
		(property "Val" "22u"
			(at 0 0 90)
			(unlocked yes)
			(layer "B.Fab")
			(hide yes)
			(effects
				(font
					(size 1 1)
					(thickness 0.15)
				)
				(justify mirror)
			)
		)
		(property "License" "Apache-2.0"
			(at 0 0 90)
			(unlocked yes)
			(layer "B.Fab")
			(hide yes)
			(effects
				(font
					(size 1 1)
					(thickness 0.15)
				)
				(justify mirror)
			)
		)
		(property "Author" "Antmicro"
			(at 0 0 90)
			(unlocked yes)
			(layer "B.Fab")
			(hide yes)
			(effects
				(font
					(size 1 1)
					(thickness 0.15)
				)
				(justify mirror)
			)
		)
		(property "Voltage" ""
			(at 0 0 90)
			(unlocked yes)
			(layer "B.Fab")
			(hide yes)
			(effects
				(font
					(size 1 1)
					(thickness 0.15)
				)
				(justify mirror)
			)
		)
		(property "Dielectric" ""
			(at 0 0 90)
			(unlocked yes)
			(layer "B.Fab")
			(hide yes)
			(effects
				(font
					(size 1 1)
					(thickness 0.15)
				)
				(justify mirror)
			)
		)
		(sheetname "/Supply/DC-DC VCCINT/")
		(sheetfile "dc-dc-vccint.kicad_sch")
		(attr smd)
		(fp_line
			(start -0.15 -0.4)
			(end 0.15 -0.4)
			(stroke
				(width 0.15)
				(type solid)
			)
			(layer "B.SilkS")
		)
		(fp_line
			(start -0.15 0.4)
			(end 0.15 0.4)
			(stroke
				(width 0.15)
				(type solid)
			)
			(layer "B.SilkS")
		)
		(fp_rect
			(start -1.25 0.65)
			(end 1.25 -0.65)
			(stroke
				(width 0.05)
				(type solid)
			)
			(fill no)
			(layer "B.CrtYd")
		)
		(fp_rect
			(start -0.8 0.4)
			(end 0.8 -0.4)
			(stroke
				(width 0.15)
				(type solid)
			)
			(fill no)
			(layer "B.Fab")
		)
		(fp_text user "License: Apache-2.0"
			(at -1.682 -5.895 270)
			(layer "B.Fab")
			(effects
				(font
					(size 0.7 0.7)
					(thickness 0.15)
				)
				(justify left bottom mirror)
			)
		)
		(fp_text user "Author: Antmicro"
			(at -1.682 -4.894 270)
			(layer "B.Fab")
			(effects
				(font
					(size 0.7 0.7)
					(thickness 0.15)
				)
				(justify left bottom mirror)
			)
		)
		(fp_text user "${REFERENCE}"
			(at -1.682 -3.895 270)
			(layer "B.Fab")
			(effects
				(font
					(size 0.7 0.7)
					(thickness 0.15)
				)
				(justify left bottom mirror)
			)
		)
		(pad "1" smd roundrect
			(at -0.7 0 90)
			(size 0.8 1)
			(layers "B.Cu" "B.Mask" "B.Paste")
			(roundrect_rratio 0.2)
			(net 1 "GND")
			(pintype "passive")
		)
		(pad "2" smd roundrect
			(at 0.7 0 90)
			(size 0.8 1)
			(layers "B.Cu" "B.Mask" "B.Paste")
			(roundrect_rratio 0.2)
			(net 224 "/Supply/DC-DC VCCINT/0V85_REG1")
			(pintype "passive")
		)
	)
	(footprint "antmicro-footprints:R_0402_1005Metric"
		(layer "B.Cu")
		(at 203.25 137.0645 180)
		(descr "Resistor SMD 0402")
		(tags "resistor SMD 0402")
		(property "Reference" "R256"
			(at 2.35 0 0)
			(layer "B.SilkS")
			(effects
				(font
					(size 0.7 0.7)
					(thickness 0.15)
				)
				(justify mirror)
			)
		)
		(property "Value" "R_0R_0402"
			(at -1.011843 -1.772047 0)
			(layer "B.Fab")
			(effects
				(font
					(size 0.7 0.7)
					(thickness 0.15)
				)
				(justify left bottom mirror)
			)
		)
		(property "Datasheet" "https://industrial.panasonic.com/cdbs/www-data/pdf/RDA0000/AOA0000C301.pdf"
			(at 0 0 0)
			(layer "B.Fab")
			(hide yes)
			(effects
				(font
					(size 1.27 1.27)
					(thickness 0.15)
				)
				(justify mirror)
			)
		)
		(property "MPN" "ERJ2GE0R00X"
			(at 0 0 0)
			(unlocked yes)
			(layer "B.Fab")
			(hide yes)
			(effects
				(font
					(size 1 1)
					(thickness 0.15)
				)
				(justify mirror)
			)
		)
		(property "Manufacturer" "Panasonic"
			(at 0 0 0)
			(unlocked yes)
			(layer "B.Fab")
			(hide yes)
			(effects
				(font
					(size 1 1)
					(thickness 0.15)
				)
				(justify mirror)
			)
		)
		(property "License" "Apache-2.0"
			(at 0 0 0)
			(unlocked yes)
			(layer "B.Fab")
			(hide yes)
			(effects
				(font
					(size 1 1)
					(thickness 0.15)
				)
				(justify mirror)
			)
		)
		(property "Author" "Antmicro"
			(at 0 0 0)
			(unlocked yes)
			(layer "B.Fab")
			(hide yes)
			(effects
				(font
					(size 1 1)
					(thickness 0.15)
				)
				(justify mirror)
			)
		)
		(property "Val" "0R"
			(at 0 0 0)
			(unlocked yes)
			(layer "B.Fab")
			(hide yes)
			(effects
				(font
					(size 1 1)
					(thickness 0.15)
				)
				(justify mirror)
			)
		)
		(property "Tolerance" "~"
			(at 0 0 0)
			(unlocked yes)
			(layer "B.Fab")
			(hide yes)
			(effects
				(font
					(size 1 1)
					(thickness 0.15)
				)
				(justify mirror)
			)
		)
		(property "Current" "1A"
			(at 0 0 0)
			(unlocked yes)
			(layer "B.Fab")
			(hide yes)
			(effects
				(font
					(size 1 1)
					(thickness 0.15)
				)
				(justify mirror)
			)
		)
		(sheetname "/FPGA banks HP/")
		(sheetfile "fpga-hp-banks.kicad_sch")
		(attr smd exclude_from_bom dnp)
		(fp_rect
			(start -0.925 0.47)
			(end 0.925 -0.47)
			(stroke
				(width 0.05)
				(type default)
			)
			(fill no)
			(layer "B.CrtYd")
		)
		(fp_rect
			(start -0.5 0.25)
			(end 0.5 -0.25)
			(stroke
				(width 0.15)
				(type solid)
			)
			(fill no)
			(layer "B.Fab")
		)
		(fp_text user "Author: Antmicro"
			(at -0.95 -4.169 0)
			(layer "B.Fab")
			(effects
				(font
					(size 0.7 0.7)
					(thickness 0.15)
				)
				(justify left bottom mirror)
			)
		)
		(fp_text user "License: Apache-2.0"
			(at -0.95 -5.169 0)
			(layer "B.Fab")
			(effects
				(font
					(size 0.7 0.7)
					(thickness 0.15)
				)
				(justify left bottom mirror)
			)
		)
		(fp_text user "${REFERENCE}"
			(at -0.95 -3.168 0)
			(layer "B.Fab")
			(effects
				(font
					(size 0.7 0.7)
					(thickness 0.15)
				)
				(justify left bottom mirror)
			)
		)
		(pad "1" smd roundrect
			(at -0.48 0 180)
			(size 0.59 0.64)
			(layers "B.Cu" "B.Mask" "B.Paste")
			(roundrect_rratio 0.25)
			(net 827 "Net-(R253-Pad1)")
			(pintype "passive")
		)
		(pad "2" smd roundrect
			(at 0.48 0 180)
			(size 0.59 0.64)
			(layers "B.Cu" "B.Mask" "B.Paste")
			(roundrect_rratio 0.25)
			(net 826 "/FPGA banks HP/VREF")
			(pintype "passive")
		)
	)
	(footprint "antmicro-footprints:R_0402_1005Metric"
		(layer "B.Cu")
		(at 110.38 166.95 -90)
		(descr "Resistor SMD 0402")
		(tags "resistor SMD 0402")
		(property "Reference" "R81"
			(at -1.122484 0.772697 90)
			(layer "B.SilkS")
			(effects
				(font
					(size 0.7 0.7)
					(thickness 0.15)
				)
				(justify left bottom mirror)
			)
		)
		(property "Value" "R_1k_0402"
			(at -1.011843 -1.772047 90)
			(layer "B.Fab")
			(effects
				(font
					(size 0.7 0.7)
					(thickness 0.15)
				)
				(justify left bottom mirror)
			)
		)
		(property "Datasheet" "https://www.bourns.com/docs/product-datasheets/cr.pdf"
			(at 0 0 270)
			(layer "F.Fab")
			(hide yes)
			(effects
				(font
					(size 1.27 1.27)
					(thickness 0.15)
				)
			)
		)
		(property "MPN" "CR0402-FX-1001GLF"
			(at 0 0 270)
			(unlocked yes)
			(layer "B.Fab")
			(hide yes)
			(effects
				(font
					(size 1 1)
					(thickness 0.15)
				)
				(justify mirror)
			)
		)
		(property "Manufacturer" "Bourns"
			(at 0 0 270)
			(unlocked yes)
			(layer "B.Fab")
			(hide yes)
			(effects
				(font
					(size 1 1)
					(thickness 0.15)
				)
				(justify mirror)
			)
		)
		(property "License" "Apache-2.0"
			(at 0 0 270)
			(unlocked yes)
			(layer "B.Fab")
			(hide yes)
			(effects
				(font
					(size 1 1)
					(thickness 0.15)
				)
				(justify mirror)
			)
		)
		(property "Author" "Antmicro"
			(at 0 0 270)
			(unlocked yes)
			(layer "B.Fab")
			(hide yes)
			(effects
				(font
					(size 1 1)
					(thickness 0.15)
				)
				(justify mirror)
			)
		)
		(property "Val" "1k"
			(at 0 0 270)
			(unlocked yes)
			(layer "B.Fab")
			(hide yes)
			(effects
				(font
					(size 1 1)
					(thickness 0.15)
				)
				(justify mirror)
			)
		)
		(property "Tolerance" "1%"
			(at 0 0 270)
			(unlocked yes)
			(layer "B.Fab")
			(hide yes)
			(effects
				(font
					(size 1 1)
					(thickness 0.15)
				)
				(justify mirror)
			)
		)
		(sheetname "/HDMI + SD Card/")
		(sheetfile "hdmi-sd-card.kicad_sch")
		(attr smd)
		(fp_rect
			(start -0.925 0.47)
			(end 0.925 -0.47)
			(stroke
				(width 0.05)
				(type default)
			)
			(fill no)
			(layer "B.CrtYd")
		)
		(fp_rect
			(start -0.5 0.25)
			(end 0.5 -0.25)
			(stroke
				(width 0.15)
				(type solid)
			)
			(fill no)
			(layer "B.Fab")
		)
		(fp_text user "${REFERENCE}"
			(at -0.95 -3.168 90)
			(layer "B.Fab")
			(effects
				(font
					(size 0.7 0.7)
					(thickness 0.15)
				)
				(justify left bottom mirror)
			)
		)
		(fp_text user "Author: Antmicro"
			(at -0.95 -4.169 90)
			(layer "B.Fab")
			(effects
				(font
					(size 0.7 0.7)
					(thickness 0.15)
				)
				(justify left bottom mirror)
			)
		)
		(fp_text user "License: Apache-2.0"
			(at -0.95 -5.169 90)
			(layer "B.Fab")
			(effects
				(font
					(size 0.7 0.7)
					(thickness 0.15)
				)
				(justify left bottom mirror)
			)
		)
		(pad "1" smd roundrect
			(at -0.48 0 270)
			(size 0.59 0.64)
			(layers "B.Cu" "B.Mask" "B.Paste")
			(roundrect_rratio 0.25)
			(net 604 "/HDMI + SD Card/HDMI_IN_HPD_CONN")
			(pintype "passive")
		)
		(pad "2" smd roundrect
			(at 0.48 0 270)
			(size 0.59 0.64)
			(layers "B.Cu" "B.Mask" "B.Paste")
			(roundrect_rratio 0.25)
			(net 297 "/HDMI + SD Card/HDMI_IN_5V")
			(pintype "passive")
		)
	)
	(footprint "antmicro-footprints:R_0402_1005Metric"
		(layer "B.Cu")
		(at 111.98 168.37 180)
		(descr "Resistor SMD 0402")
		(tags "resistor SMD 0402")
		(property "Reference" "R82"
			(at -1.122484 -1.48 0)
			(layer "B.SilkS")
			(effects
				(font
					(size 0.7 0.7)
					(thickness 0.15)
				)
				(justify left bottom mirror)
			)
		)
		(property "Value" "R_1k_0402"
			(at -1.011843 -1.772047 0)
			(layer "B.Fab")
			(effects
				(font
					(size 0.7 0.7)
					(thickness 0.15)
				)
				(justify left bottom mirror)
			)
		)
		(property "Datasheet" "https://www.bourns.com/docs/product-datasheets/cr.pdf"
			(at 0 0 180)
			(layer "F.Fab")
			(hide yes)
			(effects
				(font
					(size 1.27 1.27)
					(thickness 0.15)
				)
			)
		)
		(property "MPN" "CR0402-FX-1001GLF"
			(at 0 0 180)
			(unlocked yes)
			(layer "B.Fab")
			(hide yes)
			(effects
				(font
					(size 1 1)
					(thickness 0.15)
				)
				(justify mirror)
			)
		)
		(property "Manufacturer" "Bourns"
			(at 0 0 180)
			(unlocked yes)
			(layer "B.Fab")
			(hide yes)
			(effects
				(font
					(size 1 1)
					(thickness 0.15)
				)
				(justify mirror)
			)
		)
		(property "License" "Apache-2.0"
			(at 0 0 180)
			(unlocked yes)
			(layer "B.Fab")
			(hide yes)
			(effects
				(font
					(size 1 1)
					(thickness 0.15)
				)
				(justify mirror)
			)
		)
		(property "Author" "Antmicro"
			(at 0 0 180)
			(unlocked yes)
			(layer "B.Fab")
			(hide yes)
			(effects
				(font
					(size 1 1)
					(thickness 0.15)
				)
				(justify mirror)
			)
		)
		(property "Val" "1k"
			(at 0 0 180)
			(unlocked yes)
			(layer "B.Fab")
			(hide yes)
			(effects
				(font
					(size 1 1)
					(thickness 0.15)
				)
				(justify mirror)
			)
		)
		(property "Tolerance" "1%"
			(at 0 0 180)
			(unlocked yes)
			(layer "B.Fab")
			(hide yes)
			(effects
				(font
					(size 1 1)
					(thickness 0.15)
				)
				(justify mirror)
			)
		)
		(sheetname "/HDMI + SD Card/")
		(sheetfile "hdmi-sd-card.kicad_sch")
		(attr smd)
		(fp_rect
			(start -0.925 0.47)
			(end 0.925 -0.47)
			(stroke
				(width 0.05)
				(type default)
			)
			(fill no)
			(layer "B.CrtYd")
		)
		(fp_rect
			(start -0.5 0.25)
			(end 0.5 -0.25)
			(stroke
				(width 0.15)
				(type solid)
			)
			(fill no)
			(layer "B.Fab")
		)
		(fp_text user "${REFERENCE}"
			(at -0.95 -3.168 0)
			(layer "B.Fab")
			(effects
				(font
					(size 0.7 0.7)
					(thickness 0.15)
				)
				(justify left bottom mirror)
			)
		)
		(fp_text user "Author: Antmicro"
			(at -0.95 -4.169 0)
			(layer "B.Fab")
			(effects
				(font
					(size 0.7 0.7)
					(thickness 0.15)
				)
				(justify left bottom mirror)
			)
		)
		(fp_text user "License: Apache-2.0"
			(at -0.95 -5.169 0)
			(layer "B.Fab")
			(effects
				(font
					(size 0.7 0.7)
					(thickness 0.15)
				)
				(justify left bottom mirror)
			)
		)
		(pad "1" smd roundrect
			(at -0.48 0 180)
			(size 0.59 0.64)
			(layers "B.Cu" "B.Mask" "B.Paste")
			(roundrect_rratio 0.25)
			(net 506 "Net-(Q18-G)")
			(pintype "passive")
		)
		(pad "2" smd roundrect
			(at 0.48 0 180)
			(size 0.59 0.64)
			(layers "B.Cu" "B.Mask" "B.Paste")
			(roundrect_rratio 0.25)
			(net 297 "/HDMI + SD Card/HDMI_IN_5V")
			(pintype "passive")
		)
	)
	(footprint "antmicro-footprints:C_0402_1005Metric_EIA"
		(layer "B.Cu")
		(at 199 149.5 -90)
		(descr "Capacitor SMD 0402 (1005 Metric), square (rectangular) end terminal, IPC_7351 nominal, (Body size source: IPC-SM-782 page 76, https://www.pcb-3d.com/wordpress/wp-content/uploads/ipc-sm-782a_amendment_1_and_2.pdf)")
		(tags "capacitor 0402")
		(property "Reference" "C95"
			(at 0.95 -0.425 90)
			(layer "B.SilkS")
			(effects
				(font
					(size 0.7 0.7)
					(thickness 0.15)
				)
				(justify left bottom mirror)
			)
		)
		(property "Value" "C_10u_10V_0402"
			(at 0 -1.169 90)
			(layer "B.Fab")
			(effects
				(font
					(size 0.7 0.7)
					(thickness 0.15)
				)
				(justify left bottom mirror)
			)
		)
		(property "Datasheet" "https://www.murata.com/products/productdetail?partno=GRM155R61A106ME11%23"
			(at 0 0 270)
			(layer "F.Fab")
			(hide yes)
			(effects
				(font
					(size 1.27 1.27)
					(thickness 0.15)
				)
			)
		)
		(property "MPN" "GRM155R61A106ME11D"
			(at 0 0 270)
			(unlocked yes)
			(layer "B.Fab")
			(hide yes)
			(effects
				(font
					(size 1 1)
					(thickness 0.15)
				)
				(justify mirror)
			)
		)
		(property "Manufacturer" "Murata"
			(at 0 0 270)
			(unlocked yes)
			(layer "B.Fab")
			(hide yes)
			(effects
				(font
					(size 1 1)
					(thickness 0.15)
				)
				(justify mirror)
			)
		)
		(property "License" "Apache-2.0"
			(at 0 0 270)
			(unlocked yes)
			(layer "B.Fab")
			(hide yes)
			(effects
				(font
					(size 1 1)
					(thickness 0.15)
				)
				(justify mirror)
			)
		)
		(property "Author" "Antmicro"
			(at 0 0 270)
			(unlocked yes)
			(layer "B.Fab")
			(hide yes)
			(effects
				(font
					(size 1 1)
					(thickness 0.15)
				)
				(justify mirror)
			)
		)
		(property "Val" "10u"
			(at 0 0 270)
			(unlocked yes)
			(layer "B.Fab")
			(hide yes)
			(effects
				(font
					(size 1 1)
					(thickness 0.15)
				)
				(justify mirror)
			)
		)
		(property "Voltage" "10V"
			(at 0 0 270)
			(unlocked yes)
			(layer "B.Fab")
			(hide yes)
			(effects
				(font
					(size 1 1)
					(thickness 0.15)
				)
				(justify mirror)
			)
		)
		(property "Dielectric" "X5R"
			(at 0 0 270)
			(unlocked yes)
			(layer "B.Fab")
			(hide yes)
			(effects
				(font
					(size 1 1)
					(thickness 0.15)
				)
				(justify mirror)
			)
		)
		(sheetname "/FPGA power/")
		(sheetfile "fpga-power.kicad_sch")
		(attr smd)
		(fp_rect
			(start -0.95 0.45)
			(end 0.95 -0.45)
			(stroke
				(width 0.05)
				(type default)
			)
			(fill no)
			(layer "B.CrtYd")
		)
		(fp_line
			(start -0.5 0.25)
			(end 0.498 0.25)
			(stroke
				(width 0.15)
				(type solid)
			)
			(layer "B.Fab")
		)
		(fp_line
			(start 0.498 0.25)
			(end 0.498 -0.248)
			(stroke
				(width 0.15)
				(type solid)
			)
			(layer "B.Fab")
		)
		(fp_line
			(start -0.5 -0.248)
			(end -0.5 0.25)
			(stroke
				(width 0.15)
				(type solid)
			)
			(layer "B.Fab")
		)
		(fp_line
			(start 0.498 -0.248)
			(end -0.5 -0.248)
			(stroke
				(width 0.15)
				(type solid)
			)
			(layer "B.Fab")
		)
		(fp_text user "${REFERENCE}"
			(at -0.9656 -3.169 90)
			(layer "B.Fab")
			(effects
				(font
					(size 0.7 0.7)
					(thickness 0.15)
				)
				(justify left bottom mirror)
			)
		)
		(fp_text user "Author: Antmicro"
			(at -0.9656 -5.569 90)
			(layer "B.Fab")
			(effects
				(font
					(size 0.7 0.7)
					(thickness 0.15)
				)
				(justify left bottom mirror)
			)
		)
		(fp_text user "License: Apache-2.0"
			(at -0.9656 -4.369 90)
			(layer "B.Fab")
			(effects
				(font
					(size 0.7 0.7)
					(thickness 0.15)
				)
				(justify left bottom mirror)
			)
		)
		(pad "1" smd roundrect
			(at -0.5 0 180)
			(size 0.6 0.6)
			(layers "B.Cu" "B.Mask" "B.Paste")
			(roundrect_rratio 0.25)
			(net 1 "GND")
			(pintype "passive")
		)
		(pad "2" smd roundrect
			(at 0.498 0 270)
			(size 0.6 0.6)
			(layers "B.Cu" "B.Mask" "B.Paste")
			(roundrect_rratio 0.25)
			(net 151 "+3V3")
			(pintype "passive")
		)
	)
	(footprint "antmicro-footprints:R_0402_1005Metric"
		(layer "B.Cu")
		(at 156.124499 190.274 180)
		(descr "Resistor SMD 0402")
		(tags "resistor SMD 0402")
		(property "Reference" "R192"
			(at 1.004499 -0.376 0)
			(layer "B.SilkS")
			(effects
				(font
					(size 0.7 0.7)
					(thickness 0.15)
				)
				(justify left bottom mirror)
			)
		)
		(property "Value" "R_10k_0402"
			(at -1.011843 -1.772047 0)
			(layer "B.Fab")
			(effects
				(font
					(size 0.7 0.7)
					(thickness 0.15)
				)
				(justify left bottom mirror)
			)
		)
		(property "Datasheet" "https://www.bourns.com/docs/product-datasheets/cr.pdf"
			(at 0 0 180)
			(layer "F.Fab")
			(hide yes)
			(effects
				(font
					(size 1.27 1.27)
					(thickness 0.15)
				)
			)
		)
		(property "MPN" "CR0402-FX-1002GLF"
			(at 0 0 180)
			(unlocked yes)
			(layer "B.Fab")
			(hide yes)
			(effects
				(font
					(size 1 1)
					(thickness 0.15)
				)
				(justify mirror)
			)
		)
		(property "Manufacturer" "Bourns"
			(at 0 0 180)
			(unlocked yes)
			(layer "B.Fab")
			(hide yes)
			(effects
				(font
					(size 1 1)
					(thickness 0.15)
				)
				(justify mirror)
			)
		)
		(property "License" "Apache-2.0"
			(at 0 0 180)
			(unlocked yes)
			(layer "B.Fab")
			(hide yes)
			(effects
				(font
					(size 1 1)
					(thickness 0.15)
				)
				(justify mirror)
			)
		)
		(property "Author" "Antmicro"
			(at 0 0 180)
			(unlocked yes)
			(layer "B.Fab")
			(hide yes)
			(effects
				(font
					(size 1 1)
					(thickness 0.15)
				)
				(justify mirror)
			)
		)
		(property "Val" "10k"
			(at 0 0 180)
			(unlocked yes)
			(layer "B.Fab")
			(hide yes)
			(effects
				(font
					(size 1 1)
					(thickness 0.15)
				)
				(justify mirror)
			)
		)
		(property "Tolerance" "1%"
			(at 0 0 180)
			(unlocked yes)
			(layer "B.Fab")
			(hide yes)
			(effects
				(font
					(size 1 1)
					(thickness 0.15)
				)
				(justify mirror)
			)
		)
		(sheetname "/PCIe connector/")
		(sheetfile "pcie-connector.kicad_sch")
		(attr smd exclude_from_bom dnp)
		(fp_rect
			(start -0.925 0.47)
			(end 0.925 -0.47)
			(stroke
				(width 0.05)
				(type default)
			)
			(fill no)
			(layer "B.CrtYd")
		)
		(fp_rect
			(start -0.5 0.25)
			(end 0.5 -0.25)
			(stroke
				(width 0.15)
				(type solid)
			)
			(fill no)
			(layer "B.Fab")
		)
		(fp_text user "${REFERENCE}"
			(at -0.95 -3.168 0)
			(layer "B.Fab")
			(effects
				(font
					(size 0.7 0.7)
					(thickness 0.15)
				)
				(justify left bottom mirror)
			)
		)
		(fp_text user "Author: Antmicro"
			(at -0.95 -4.169 0)
			(layer "B.Fab")
			(effects
				(font
					(size 0.7 0.7)
					(thickness 0.15)
				)
				(justify left bottom mirror)
			)
		)
		(fp_text user "License: Apache-2.0"
			(at -0.95 -5.169 0)
			(layer "B.Fab")
			(effects
				(font
					(size 0.7 0.7)
					(thickness 0.15)
				)
				(justify left bottom mirror)
			)
		)
		(pad "1" smd roundrect
			(at -0.48 0 180)
			(size 0.59 0.64)
			(layers "B.Cu" "B.Mask" "B.Paste")
			(roundrect_rratio 0.25)
			(net 1 "GND")
			(pintype "passive")
		)
		(pad "2" smd roundrect
			(at 0.48 0 180)
			(size 0.59 0.64)
			(layers "B.Cu" "B.Mask" "B.Paste")
			(roundrect_rratio 0.25)
			(net 98 "PCIE.PWRGD")
			(pintype "passive")
		)
	)
	(footprint "antmicro-footprints:C_0603_1608Metric"
		(layer "B.Cu")
		(at 231.534998 172.080002 90)
		(descr "Capacitor SMD 0603")
		(tags "capacitor 0603")
		(property "Reference" "C268"
			(at -4.069998 0.320001 90)
			(layer "B.SilkS")
			(effects
				(font
					(size 0.7 0.7)
					(thickness 0.15)
				)
				(justify right bottom mirror)
			)
		)
		(property "Value" "C_22u_0603"
			(at -1.42757 -1.770288 90)
			(layer "B.Fab")
			(effects
				(font
					(size 0.7 0.7)
					(thickness 0.15)
				)
				(justify right bottom mirror)
			)
		)
		(property "Datasheet" "https://www.murata.com/products/productdetail?partno=GRM188R60J226MEA0%23"
			(at 0 0 90)
			(layer "F.Fab")
			(hide yes)
			(effects
				(font
					(size 1.27 1.27)
					(thickness 0.15)
				)
			)
		)
		(property "Manufacturer" "Murata"
			(at 0 0 90)
			(unlocked yes)
			(layer "B.Fab")
			(hide yes)
			(effects
				(font
					(size 1 1)
					(thickness 0.15)
				)
				(justify mirror)
			)
		)
		(property "MPN" "GRM188R60J226MEA0D"
			(at 0 0 90)
			(unlocked yes)
			(layer "B.Fab")
			(hide yes)
			(effects
				(font
					(size 1 1)
					(thickness 0.15)
				)
				(justify mirror)
			)
		)
		(property "Val" "22u"
			(at 0 0 90)
			(unlocked yes)
			(layer "B.Fab")
			(hide yes)
			(effects
				(font
					(size 1 1)
					(thickness 0.15)
				)
				(justify mirror)
			)
		)
		(property "License" "Apache-2.0"
			(at 0 0 90)
			(unlocked yes)
			(layer "B.Fab")
			(hide yes)
			(effects
				(font
					(size 1 1)
					(thickness 0.15)
				)
				(justify mirror)
			)
		)
		(property "Author" "Antmicro"
			(at 0 0 90)
			(unlocked yes)
			(layer "B.Fab")
			(hide yes)
			(effects
				(font
					(size 1 1)
					(thickness 0.15)
				)
				(justify mirror)
			)
		)
		(property "Voltage" ""
			(at 0 0 90)
			(unlocked yes)
			(layer "B.Fab")
			(hide yes)
			(effects
				(font
					(size 1 1)
					(thickness 0.15)
				)
				(justify mirror)
			)
		)
		(property "Dielectric" ""
			(at 0 0 90)
			(unlocked yes)
			(layer "B.Fab")
			(hide yes)
			(effects
				(font
					(size 1 1)
					(thickness 0.15)
				)
				(justify mirror)
			)
		)
		(sheetname "/Supply/DC-DC VCCINT/")
		(sheetfile "dc-dc-vccint.kicad_sch")
		(attr smd)
		(fp_line
			(start -0.15 -0.4)
			(end 0.15 -0.4)
			(stroke
				(width 0.15)
				(type solid)
			)
			(layer "B.SilkS")
		)
		(fp_line
			(start -0.15 0.4)
			(end 0.15 0.4)
			(stroke
				(width 0.15)
				(type solid)
			)
			(layer "B.SilkS")
		)
		(fp_rect
			(start -1.25 0.65)
			(end 1.25 -0.65)
			(stroke
				(width 0.05)
				(type solid)
			)
			(fill no)
			(layer "B.CrtYd")
		)
		(fp_rect
			(start -0.8 0.4)
			(end 0.8 -0.4)
			(stroke
				(width 0.15)
				(type solid)
			)
			(fill no)
			(layer "B.Fab")
		)
		(fp_text user "License: Apache-2.0"
			(at -1.682 -5.895 270)
			(layer "B.Fab")
			(effects
				(font
					(size 0.7 0.7)
					(thickness 0.15)
				)
				(justify left bottom mirror)
			)
		)
		(fp_text user "Author: Antmicro"
			(at -1.682 -4.894 270)
			(layer "B.Fab")
			(effects
				(font
					(size 0.7 0.7)
					(thickness 0.15)
				)
				(justify left bottom mirror)
			)
		)
		(fp_text user "${REFERENCE}"
			(at -1.682 -3.895 270)
			(layer "B.Fab")
			(effects
				(font
					(size 0.7 0.7)
					(thickness 0.15)
				)
				(justify left bottom mirror)
			)
		)
		(pad "1" smd roundrect
			(at -0.7 0 90)
			(size 0.8 1)
			(layers "B.Cu" "B.Mask" "B.Paste")
			(roundrect_rratio 0.2)
			(net 1 "GND")
			(pintype "passive")
		)
		(pad "2" smd roundrect
			(at 0.7 0 90)
			(size 0.8 1)
			(layers "B.Cu" "B.Mask" "B.Paste")
			(roundrect_rratio 0.2)
			(net 224 "/Supply/DC-DC VCCINT/0V85_REG1")
			(pintype "passive")
		)
	)
	(footprint "antmicro-footprints:R_0402_1005Metric"
		(layer "B.Cu")
		(at 254.324499 160.174)
		(descr "Resistor SMD 0402")
		(tags "resistor SMD 0402")
		(property "Reference" "R156"
			(at 0.925501 0.525 0)
			(layer "B.SilkS")
			(effects
				(font
					(size 0.7 0.7)
					(thickness 0.15)
				)
				(justify right bottom mirror)
			)
		)
		(property "Value" "R_0R_0402"
			(at -1.011843 -1.772047 0)
			(layer "B.Fab")
			(effects
				(font
					(size 0.7 0.7)
					(thickness 0.15)
				)
				(justify right bottom mirror)
			)
		)
		(property "Datasheet" "https://industrial.panasonic.com/cdbs/www-data/pdf/RDA0000/AOA0000C301.pdf"
			(at 0 0 0)
			(layer "F.Fab")
			(hide yes)
			(effects
				(font
					(size 1.27 1.27)
					(thickness 0.15)
				)
			)
		)
		(property "Manufacturer" "Panasonic"
			(at 0 0 0)
			(unlocked yes)
			(layer "B.Fab")
			(hide yes)
			(effects
				(font
					(size 1 1)
					(thickness 0.15)
				)
				(justify mirror)
			)
		)
		(property "MPN" "ERJ2GE0R00X"
			(at 0 0 0)
			(unlocked yes)
			(layer "B.Fab")
			(hide yes)
			(effects
				(font
					(size 1 1)
					(thickness 0.15)
				)
				(justify mirror)
			)
		)
		(property "Val" "0R"
			(at 0 0 0)
			(unlocked yes)
			(layer "B.Fab")
			(hide yes)
			(effects
				(font
					(size 1 1)
					(thickness 0.15)
				)
				(justify mirror)
			)
		)
		(property "License" "Apache-2.0"
			(at 0 0 0)
			(unlocked yes)
			(layer "B.Fab")
			(hide yes)
			(effects
				(font
					(size 1 1)
					(thickness 0.15)
				)
				(justify mirror)
			)
		)
		(property "Author" "Antmicro"
			(at 0 0 0)
			(unlocked yes)
			(layer "B.Fab")
			(hide yes)
			(effects
				(font
					(size 1 1)
					(thickness 0.15)
				)
				(justify mirror)
			)
		)
		(property "Tolerance" "~"
			(at 0 0 0)
			(unlocked yes)
			(layer "B.Fab")
			(hide yes)
			(effects
				(font
					(size 1 1)
					(thickness 0.15)
				)
				(justify mirror)
			)
		)
		(property "Current" "1A"
			(at 0 0 0)
			(unlocked yes)
			(layer "B.Fab")
			(hide yes)
			(effects
				(font
					(size 1 1)
					(thickness 0.15)
				)
				(justify mirror)
			)
		)
		(sheetname "/Supply/DC-DC IO/")
		(sheetfile "dc-dc-io.kicad_sch")
		(attr smd exclude_from_bom dnp)
		(fp_rect
			(start -0.925 0.47)
			(end 0.925 -0.47)
			(stroke
				(width 0.05)
				(type default)
			)
			(fill no)
			(layer "B.CrtYd")
		)
		(fp_rect
			(start -0.5 0.25)
			(end 0.5 -0.25)
			(stroke
				(width 0.15)
				(type solid)
			)
			(fill no)
			(layer "B.Fab")
		)
		(fp_text user "Author: Antmicro"
			(at -0.95 -4.169 180)
			(layer "B.Fab")
			(effects
				(font
					(size 0.7 0.7)
					(thickness 0.15)
				)
				(justify left bottom mirror)
			)
		)
		(fp_text user "License: Apache-2.0"
			(at -0.95 -5.169 180)
			(layer "B.Fab")
			(effects
				(font
					(size 0.7 0.7)
					(thickness 0.15)
				)
				(justify left bottom mirror)
			)
		)
		(fp_text user "${REFERENCE}"
			(at -0.95 -3.168 180)
			(layer "B.Fab")
			(effects
				(font
					(size 0.7 0.7)
					(thickness 0.15)
				)
				(justify left bottom mirror)
			)
		)
		(pad "1" smd roundrect
			(at -0.48 0)
			(size 0.59 0.64)
			(layers "B.Cu" "B.Mask" "B.Paste")
			(roundrect_rratio 0.25)
			(net 1 "GND")
			(pintype "passive")
		)
		(pad "2" smd roundrect
			(at 0.48 0)
			(size 0.59 0.64)
			(layers "B.Cu" "B.Mask" "B.Paste")
			(roundrect_rratio 0.25)
			(net 714 "/Supply/DC-DC IO/FB5")
			(pintype "passive")
		)
	)
	(footprint "antmicro-footprints:C_0402_1005Metric"
		(layer "B.Cu")
		(at 189.622499 193.2285 90)
		(descr "Capacitor SMD 0402")
		(tags "capacitor SMD 0402")
		(property "Reference" "C253"
			(at 0.994 0.403501 90)
			(layer "B.SilkS")
			(effects
				(font
					(size 0.7 0.7)
					(thickness 0.15)
				)
				(justify right bottom mirror)
			)
		)
		(property "Value" "C_100n_0402"
			(at -1.022927 -2.155213 90)
			(layer "B.Fab")
			(effects
				(font
					(size 0.7 0.7)
					(thickness 0.15)
				)
				(justify right bottom mirror)
			)
		)
		(property "Datasheet" "https://www.murata.com/products/productdetail?partno=GRM155R61H104KE14%23"
			(at 0 0 90)
			(layer "F.Fab")
			(hide yes)
			(effects
				(font
					(size 1.27 1.27)
					(thickness 0.15)
				)
			)
		)
		(property "Manufacturer" "Murata"
			(at 0 0 90)
			(unlocked yes)
			(layer "B.Fab")
			(hide yes)
			(effects
				(font
					(size 1 1)
					(thickness 0.15)
				)
				(justify mirror)
			)
		)
		(property "MPN" "GRM155R61H104KE14D"
			(at 0 0 90)
			(unlocked yes)
			(layer "B.Fab")
			(hide yes)
			(effects
				(font
					(size 1 1)
					(thickness 0.15)
				)
				(justify mirror)
			)
		)
		(property "Val" "100n"
			(at 0 0 90)
			(unlocked yes)
			(layer "B.Fab")
			(hide yes)
			(effects
				(font
					(size 1 1)
					(thickness 0.15)
				)
				(justify mirror)
			)
		)
		(property "License" "Apache-2.0"
			(at 0 0 90)
			(unlocked yes)
			(layer "B.Fab")
			(hide yes)
			(effects
				(font
					(size 1 1)
					(thickness 0.15)
				)
				(justify mirror)
			)
		)
		(property "Author" "Antmicro"
			(at 0 0 90)
			(unlocked yes)
			(layer "B.Fab")
			(hide yes)
			(effects
				(font
					(size 1 1)
					(thickness 0.15)
				)
				(justify mirror)
			)
		)
		(property "Voltage" "50V"
			(at 0 0 90)
			(unlocked yes)
			(layer "B.Fab")
			(hide yes)
			(effects
				(font
					(size 1 1)
					(thickness 0.15)
				)
				(justify mirror)
			)
		)
		(property "Dielectric" "X5R"
			(at 0 0 90)
			(unlocked yes)
			(layer "B.Fab")
			(hide yes)
			(effects
				(font
					(size 1 1)
					(thickness 0.15)
				)
				(justify mirror)
			)
		)
		(sheetname "/FPGA MGT Interface/")
		(sheetfile "fpga-mgt.kicad_sch")
		(attr smd)
		(fp_rect
			(start -0.925 0.47)
			(end 0.925 -0.47)
			(stroke
				(width 0.05)
				(type default)
			)
			(fill no)
			(layer "B.CrtYd")
		)
		(fp_line
			(start 0.504 -0.248)
			(end -0.494 -0.248)
			(stroke
				(width 0.15)
				(type solid)
			)
			(layer "B.Fab")
		)
		(fp_line
			(start -0.494 -0.248)
			(end -0.494 0.25)
			(stroke
				(width 0.15)
				(type solid)
			)
			(layer "B.Fab")
		)
		(fp_line
			(start 0.504 0.25)
			(end 0.504 -0.248)
			(stroke
				(width 0.15)
				(type solid)
			)
			(layer "B.Fab")
		)
		(fp_line
			(start -0.494 0.25)
			(end 0.504 0.25)
			(stroke
				(width 0.15)
				(type solid)
			)
			(layer "B.Fab")
		)
		(fp_text user "Author: Antmicro"
			(at -0.939 -3.399 270)
			(layer "B.Fab")
			(effects
				(font
					(size 0.7 0.7)
					(thickness 0.15)
				)
				(justify left bottom mirror)
			)
		)
		(fp_text user "${REFERENCE}"
			(at -0.939 -4.599 270)
			(layer "B.Fab")
			(effects
				(font
					(size 0.7 0.7)
					(thickness 0.15)
				)
				(justify left bottom mirror)
			)
		)
		(fp_text user "License: Apache-2.0"
			(at -0.939 -5.799 270)
			(layer "B.Fab")
			(effects
				(font
					(size 0.7 0.7)
					(thickness 0.15)
				)
				(justify left bottom mirror)
			)
		)
		(pad "1" smd roundrect
			(at -0.48 0 90)
			(size 0.59 0.64)
			(layers "B.Cu" "B.Mask" "B.Paste")
			(roundrect_rratio 0.25)
			(net 255 "/FPGA MGT Interface/PCIE.TXD6_P")
			(pintype "passive")
		)
		(pad "2" smd roundrect
			(at 0.48 0 90)
			(size 0.59 0.64)
			(layers "B.Cu" "B.Mask" "B.Paste")
			(roundrect_rratio 0.25)
			(net 559 "/FPGA MGT Interface/GTY_224_TX1_P")
			(pintype "passive")
		)
	)
	(footprint "antmicro-footprints:C_0402_1005Metric_EIA"
		(layer "B.Cu")
		(at 194 148.5 90)
		(descr "Capacitor SMD 0402 (1005 Metric), square (rectangular) end terminal, IPC_7351 nominal, (Body size source: IPC-SM-782 page 76, https://www.pcb-3d.com/wordpress/wp-content/uploads/ipc-sm-782a_amendment_1_and_2.pdf)")
		(tags "capacitor 0402")
		(property "Reference" "C58"
			(at 9.475 -30.675 90)
			(layer "B.SilkS")
			(effects
				(font
					(size 0.7 0.7)
					(thickness 0.15)
				)
				(justify right bottom mirror)
			)
		)
		(property "Value" "C_1u_25V_0402"
			(at 0 -1.169 90)
			(layer "B.Fab")
			(effects
				(font
					(size 0.7 0.7)
					(thickness 0.15)
				)
				(justify right bottom mirror)
			)
		)
		(property "Datasheet" "https://www.murata.com/products/productdetail?partno=GRM155R61E105KE11%23"
			(at 0 0 90)
			(layer "F.Fab")
			(hide yes)
			(effects
				(font
					(size 1.27 1.27)
					(thickness 0.15)
				)
			)
		)
		(property "MPN" "GRM155R61E105KE11J"
			(at 0 0 90)
			(unlocked yes)
			(layer "B.Fab")
			(hide yes)
			(effects
				(font
					(size 1 1)
					(thickness 0.15)
				)
				(justify mirror)
			)
		)
		(property "Manufacturer" "Murata"
			(at 0 0 90)
			(unlocked yes)
			(layer "B.Fab")
			(hide yes)
			(effects
				(font
					(size 1 1)
					(thickness 0.15)
				)
				(justify mirror)
			)
		)
		(property "License" "Apache-2.0"
			(at 0 0 90)
			(unlocked yes)
			(layer "B.Fab")
			(hide yes)
			(effects
				(font
					(size 1 1)
					(thickness 0.15)
				)
				(justify mirror)
			)
		)
		(property "Author" "Antmicro"
			(at 0 0 90)
			(unlocked yes)
			(layer "B.Fab")
			(hide yes)
			(effects
				(font
					(size 1 1)
					(thickness 0.15)
				)
				(justify mirror)
			)
		)
		(property "Val" "1u"
			(at 0 0 90)
			(unlocked yes)
			(layer "B.Fab")
			(hide yes)
			(effects
				(font
					(size 1 1)
					(thickness 0.15)
				)
				(justify mirror)
			)
		)
		(property "Voltage" "25V"
			(at 0 0 90)
			(unlocked yes)
			(layer "B.Fab")
			(hide yes)
			(effects
				(font
					(size 1 1)
					(thickness 0.15)
				)
				(justify mirror)
			)
		)
		(property "Dielectric" "X5R"
			(at 0 0 90)
			(unlocked yes)
			(layer "B.Fab")
			(hide yes)
			(effects
				(font
					(size 1 1)
					(thickness 0.15)
				)
				(justify mirror)
			)
		)
		(sheetname "/FPGA power/")
		(sheetfile "fpga-power.kicad_sch")
		(attr smd)
		(fp_rect
			(start -0.95 0.45)
			(end 0.95 -0.45)
			(stroke
				(width 0.05)
				(type default)
			)
			(fill no)
			(layer "B.CrtYd")
		)
		(fp_line
			(start 0.498 -0.248)
			(end -0.5 -0.248)
			(stroke
				(width 0.15)
				(type solid)
			)
			(layer "B.Fab")
		)
		(fp_line
			(start -0.5 -0.248)
			(end -0.5 0.25)
			(stroke
				(width 0.15)
				(type solid)
			)
			(layer "B.Fab")
		)
		(fp_line
			(start 0.498 0.25)
			(end 0.498 -0.248)
			(stroke
				(width 0.15)
				(type solid)
			)
			(layer "B.Fab")
		)
		(fp_line
			(start -0.5 0.25)
			(end 0.498 0.25)
			(stroke
				(width 0.15)
				(type solid)
			)
			(layer "B.Fab")
		)
		(fp_text user "${REFERENCE}"
			(at -0.9656 -3.169 270)
			(layer "B.Fab")
			(effects
				(font
					(size 0.7 0.7)
					(thickness 0.15)
				)
				(justify left bottom mirror)
			)
		)
		(fp_text user "License: Apache-2.0"
			(at -0.9656 -4.369 270)
			(layer "B.Fab")
			(effects
				(font
					(size 0.7 0.7)
					(thickness 0.15)
				)
				(justify left bottom mirror)
			)
		)
		(fp_text user "Author: Antmicro"
			(at -0.9656 -5.569 270)
			(layer "B.Fab")
			(effects
				(font
					(size 0.7 0.7)
					(thickness 0.15)
				)
				(justify left bottom mirror)
			)
		)
		(pad "1" smd roundrect
			(at -0.5 0)
			(size 0.6 0.6)
			(layers "B.Cu" "B.Mask" "B.Paste")
			(roundrect_rratio 0.25)
			(net 1 "GND")
			(pintype "passive")
		)
		(pad "2" smd roundrect
			(at 0.498 0 90)
			(size 0.6 0.6)
			(layers "B.Cu" "B.Mask" "B.Paste")
			(roundrect_rratio 0.25)
			(net 553 "+0V85")
			(pintype "passive")
		)
	)
	(footprint "antmicro-footprints:C_0402_1005Metric_EIA"
		(layer "B.Cu")
		(at 198.5 159)
		(descr "Capacitor SMD 0402 (1005 Metric), square (rectangular) end terminal, IPC_7351 nominal, (Body size source: IPC-SM-782 page 76, https://www.pcb-3d.com/wordpress/wp-content/uploads/ipc-sm-782a_amendment_1_and_2.pdf)")
		(tags "capacitor 0402")
		(property "Reference" "C168"
			(at -31.7 -10.3 0)
			(layer "B.SilkS")
			(effects
				(font
					(size 0.7 0.7)
					(thickness 0.15)
				)
				(justify right bottom mirror)
			)
		)
		(property "Value" "C_10u_10V_0402"
			(at 0 -1.169 0)
			(layer "B.Fab")
			(effects
				(font
					(size 0.7 0.7)
					(thickness 0.15)
				)
				(justify right bottom mirror)
			)
		)
		(property "Datasheet" "https://www.murata.com/products/productdetail?partno=GRM155R61A106ME11%23"
			(at 0 0 0)
			(layer "F.Fab")
			(hide yes)
			(effects
				(font
					(size 1.27 1.27)
					(thickness 0.15)
				)
			)
		)
		(property "MPN" "GRM155R61A106ME11D"
			(at 0 0 0)
			(unlocked yes)
			(layer "B.Fab")
			(hide yes)
			(effects
				(font
					(size 1 1)
					(thickness 0.15)
				)
				(justify mirror)
			)
		)
		(property "Manufacturer" "Murata"
			(at 0 0 0)
			(unlocked yes)
			(layer "B.Fab")
			(hide yes)
			(effects
				(font
					(size 1 1)
					(thickness 0.15)
				)
				(justify mirror)
			)
		)
		(property "License" "Apache-2.0"
			(at 0 0 0)
			(unlocked yes)
			(layer "B.Fab")
			(hide yes)
			(effects
				(font
					(size 1 1)
					(thickness 0.15)
				)
				(justify mirror)
			)
		)
		(property "Author" "Antmicro"
			(at 0 0 0)
			(unlocked yes)
			(layer "B.Fab")
			(hide yes)
			(effects
				(font
					(size 1 1)
					(thickness 0.15)
				)
				(justify mirror)
			)
		)
		(property "Val" "10u"
			(at 0 0 0)
			(unlocked yes)
			(layer "B.Fab")
			(hide yes)
			(effects
				(font
					(size 1 1)
					(thickness 0.15)
				)
				(justify mirror)
			)
		)
		(property "Voltage" "10V"
			(at 0 0 0)
			(unlocked yes)
			(layer "B.Fab")
			(hide yes)
			(effects
				(font
					(size 1 1)
					(thickness 0.15)
				)
				(justify mirror)
			)
		)
		(property "Dielectric" "X5R"
			(at 0 0 0)
			(unlocked yes)
			(layer "B.Fab")
			(hide yes)
			(effects
				(font
					(size 1 1)
					(thickness 0.15)
				)
				(justify mirror)
			)
		)
		(sheetname "/FPGA power/")
		(sheetfile "fpga-power.kicad_sch")
		(attr smd)
		(fp_rect
			(start -0.95 0.45)
			(end 0.95 -0.45)
			(stroke
				(width 0.05)
				(type default)
			)
			(fill no)
			(layer "B.CrtYd")
		)
		(fp_line
			(start -0.5 -0.248)
			(end -0.5 0.25)
			(stroke
				(width 0.15)
				(type solid)
			)
			(layer "B.Fab")
		)
		(fp_line
			(start -0.5 0.25)
			(end 0.498 0.25)
			(stroke
				(width 0.15)
				(type solid)
			)
			(layer "B.Fab")
		)
		(fp_line
			(start 0.498 -0.248)
			(end -0.5 -0.248)
			(stroke
				(width 0.15)
				(type solid)
			)
			(layer "B.Fab")
		)
		(fp_line
			(start 0.498 0.25)
			(end 0.498 -0.248)
			(stroke
				(width 0.15)
				(type solid)
			)
			(layer "B.Fab")
		)
		(fp_text user "${REFERENCE}"
			(at -0.9656 -3.169 180)
			(layer "B.Fab")
			(effects
				(font
					(size 0.7 0.7)
					(thickness 0.15)
				)
				(justify left bottom mirror)
			)
		)
		(fp_text user "Author: Antmicro"
			(at -0.9656 -5.569 180)
			(layer "B.Fab")
			(effects
				(font
					(size 0.7 0.7)
					(thickness 0.15)
				)
				(justify left bottom mirror)
			)
		)
		(fp_text user "License: Apache-2.0"
			(at -0.9656 -4.369 180)
			(layer "B.Fab")
			(effects
				(font
					(size 0.7 0.7)
					(thickness 0.15)
				)
				(justify left bottom mirror)
			)
		)
		(pad "1" smd roundrect
			(at -0.5 0 270)
			(size 0.6 0.6)
			(layers "B.Cu" "B.Mask" "B.Paste")
			(roundrect_rratio 0.25)
			(net 1 "GND")
			(pintype "passive")
		)
		(pad "2" smd roundrect
			(at 0.498 0)
			(size 0.6 0.6)
			(layers "B.Cu" "B.Mask" "B.Paste")
			(roundrect_rratio 0.25)
			(net 820 "+0V9_MGTAVCC")
			(pintype "passive")
		)
	)
	(footprint "antmicro-footprints:R_0402_1005Metric_EIA"
		(layer "B.Cu")
		(at 201 141.5 90)
		(descr "Resistor SMD 0402 (1005 Metric), square (rectangular) end terminal, IPC_7351 nominal, (Body size source: IPC-SM-782 page 76, https://www.pcb-3d.com/wordpress/wp-content/uploads/ipc-sm-782a_amendment_1_and_2.pdf)")
		(tags "resistor 0402")
		(property "Reference" "R133"
			(at 1.425 1.625 270)
			(layer "B.SilkS")
			(effects
				(font
					(size 0.7 0.7)
					(thickness 0.15)
				)
				(justify left bottom mirror)
			)
		)
		(property "Value" "R_240R_0402"
			(at 0 -1.169 270)
			(layer "B.Fab")
			(effects
				(font
					(size 0.7 0.7)
					(thickness 0.15)
				)
				(justify left bottom mirror)
			)
		)
		(property "Datasheet" "https://www.bourns.com/docs/product-datasheets/cr.pdf"
			(at 0 0 90)
			(layer "F.Fab")
			(hide yes)
			(effects
				(font
					(size 1.27 1.27)
					(thickness 0.15)
				)
			)
		)
		(property "MPN" "CR0402-FX-2400GLF"
			(at 0 0 90)
			(unlocked yes)
			(layer "B.Fab")
			(hide yes)
			(effects
				(font
					(size 1 1)
					(thickness 0.15)
				)
				(justify mirror)
			)
		)
		(property "Manufacturer" "Bourns"
			(at 0 0 90)
			(unlocked yes)
			(layer "B.Fab")
			(hide yes)
			(effects
				(font
					(size 1 1)
					(thickness 0.15)
				)
				(justify mirror)
			)
		)
		(property "License" "Apache-2.0"
			(at 0 0 90)
			(unlocked yes)
			(layer "B.Fab")
			(hide yes)
			(effects
				(font
					(size 1 1)
					(thickness 0.15)
				)
				(justify mirror)
			)
		)
		(property "Author" "Antmicro"
			(at 0 0 90)
			(unlocked yes)
			(layer "B.Fab")
			(hide yes)
			(effects
				(font
					(size 1 1)
					(thickness 0.15)
				)
				(justify mirror)
			)
		)
		(property "Val" "240R"
			(at 0 0 90)
			(unlocked yes)
			(layer "B.Fab")
			(hide yes)
			(effects
				(font
					(size 1 1)
					(thickness 0.15)
				)
				(justify mirror)
			)
		)
		(property "Tolerance" "1%"
			(at 0 0 90)
			(unlocked yes)
			(layer "B.Fab")
			(hide yes)
			(effects
				(font
					(size 1 1)
					(thickness 0.15)
				)
				(justify mirror)
			)
		)
		(sheetname "/FPGA banks HP/")
		(sheetfile "fpga-hp-banks.kicad_sch")
		(attr smd)
		(fp_rect
			(start -0.95 0.45)
			(end 0.95 -0.45)
			(stroke
				(width 0.05)
				(type default)
			)
			(fill no)
			(layer "B.CrtYd")
		)
		(fp_line
			(start 0.499 -0.249)
			(end -0.5 -0.249)
			(stroke
				(width 0.15)
				(type solid)
			)
			(layer "B.Fab")
		)
		(fp_line
			(start -0.5 -0.249)
			(end -0.5 0.25)
			(stroke
				(width 0.15)
				(type solid)
			)
			(layer "B.Fab")
		)
		(fp_line
			(start 0.499 0.25)
			(end 0.499 -0.249)
			(stroke
				(width 0.15)
				(type solid)
			)
			(layer "B.Fab")
		)
		(fp_line
			(start -0.5 0.25)
			(end 0.499 0.25)
			(stroke
				(width 0.15)
				(type solid)
			)
			(layer "B.Fab")
		)
		(fp_text user "Author: Antmicro"
			(at -0.95 -5.569 270)
			(layer "B.Fab")
			(effects
				(font
					(size 0.7 0.7)
					(thickness 0.15)
				)
				(justify left bottom mirror)
			)
		)
		(fp_text user "${REFERENCE}"
			(at -0.95 -3.169 270)
			(layer "B.Fab")
			(effects
				(font
					(size 0.7 0.7)
					(thickness 0.15)
				)
				(justify left bottom mirror)
			)
		)
		(fp_text user "License: Apache-2.0"
			(at -0.95 -4.369 270)
			(layer "B.Fab")
			(effects
				(font
					(size 0.7 0.7)
					(thickness 0.15)
				)
				(justify left bottom mirror)
			)
		)
		(pad "1" smd roundrect
			(at -0.5 0)
			(size 0.6 0.6)
			(layers "B.Cu" "B.Mask" "B.Paste")
			(roundrect_rratio 0.25)
			(net 547 "/FPGA banks HP/VRP_64")
			(pintype "passive")
		)
		(pad "2" smd roundrect
			(at 0.499 0 90)
			(size 0.6 0.6)
			(layers "B.Cu" "B.Mask" "B.Paste")
			(roundrect_rratio 0.25)
			(net 1 "GND")
			(pintype "passive")
		)
	)
	(footprint "antmicro-footprints:C_0402_1005Metric"
		(layer "B.Cu")
		(at 120.125 159.45 -90)
		(descr "Capacitor SMD 0402")
		(tags "capacitor SMD 0402")
		(property "Reference" "C298"
			(at 0.9 -0.525 90)
			(layer "B.SilkS")
			(effects
				(font
					(size 0.7 0.7)
					(thickness 0.15)
				)
				(justify left bottom mirror)
			)
		)
		(property "Value" "C_100n_0402"
			(at -1.022927 -2.155213 90)
			(layer "B.Fab")
			(effects
				(font
					(size 0.7 0.7)
					(thickness 0.15)
				)
				(justify left bottom mirror)
			)
		)
		(property "Datasheet" "https://www.murata.com/products/productdetail?partno=GRM155R61H104KE14%23"
			(at 0 0 270)
			(layer "F.Fab")
			(hide yes)
			(effects
				(font
					(size 1.27 1.27)
					(thickness 0.15)
				)
			)
		)
		(property "MPN" "GRM155R61H104KE14D"
			(at 0 0 270)
			(unlocked yes)
			(layer "B.Fab")
			(hide yes)
			(effects
				(font
					(size 1 1)
					(thickness 0.15)
				)
				(justify mirror)
			)
		)
		(property "Manufacturer" "Murata"
			(at 0 0 270)
			(unlocked yes)
			(layer "B.Fab")
			(hide yes)
			(effects
				(font
					(size 1 1)
					(thickness 0.15)
				)
				(justify mirror)
			)
		)
		(property "License" "Apache-2.0"
			(at 0 0 270)
			(unlocked yes)
			(layer "B.Fab")
			(hide yes)
			(effects
				(font
					(size 1 1)
					(thickness 0.15)
				)
				(justify mirror)
			)
		)
		(property "Author" "Antmicro"
			(at 0 0 270)
			(unlocked yes)
			(layer "B.Fab")
			(hide yes)
			(effects
				(font
					(size 1 1)
					(thickness 0.15)
				)
				(justify mirror)
			)
		)
		(property "Val" "100n"
			(at 0 0 270)
			(unlocked yes)
			(layer "B.Fab")
			(hide yes)
			(effects
				(font
					(size 1 1)
					(thickness 0.15)
				)
				(justify mirror)
			)
		)
		(property "Voltage" "50V"
			(at 0 0 270)
			(unlocked yes)
			(layer "B.Fab")
			(hide yes)
			(effects
				(font
					(size 1 1)
					(thickness 0.15)
				)
				(justify mirror)
			)
		)
		(property "Dielectric" "X5R"
			(at 0 0 270)
			(unlocked yes)
			(layer "B.Fab")
			(hide yes)
			(effects
				(font
					(size 1 1)
					(thickness 0.15)
				)
				(justify mirror)
			)
		)
		(sheetname "/HDMI + SD Card/")
		(sheetfile "hdmi-sd-card.kicad_sch")
		(attr smd)
		(fp_rect
			(start -0.925 0.47)
			(end 0.925 -0.47)
			(stroke
				(width 0.05)
				(type default)
			)
			(fill no)
			(layer "B.CrtYd")
		)
		(fp_line
			(start -0.494 0.25)
			(end 0.504 0.25)
			(stroke
				(width 0.15)
				(type solid)
			)
			(layer "B.Fab")
		)
		(fp_line
			(start 0.504 0.25)
			(end 0.504 -0.248)
			(stroke
				(width 0.15)
				(type solid)
			)
			(layer "B.Fab")
		)
		(fp_line
			(start -0.494 -0.248)
			(end -0.494 0.25)
			(stroke
				(width 0.15)
				(type solid)
			)
			(layer "B.Fab")
		)
		(fp_line
			(start 0.504 -0.248)
			(end -0.494 -0.248)
			(stroke
				(width 0.15)
				(type solid)
			)
			(layer "B.Fab")
		)
		(fp_text user "License: Apache-2.0"
			(at -0.939 -5.799 90)
			(layer "B.Fab")
			(effects
				(font
					(size 0.7 0.7)
					(thickness 0.15)
				)
				(justify left bottom mirror)
			)
		)
		(fp_text user "Author: Antmicro"
			(at -0.939 -3.399 90)
			(layer "B.Fab")
			(effects
				(font
					(size 0.7 0.7)
					(thickness 0.15)
				)
				(justify left bottom mirror)
			)
		)
		(fp_text user "${REFERENCE}"
			(at -0.939 -4.599 90)
			(layer "B.Fab")
			(effects
				(font
					(size 0.7 0.7)
					(thickness 0.15)
				)
				(justify left bottom mirror)
			)
		)
		(pad "1" smd roundrect
			(at -0.48 0 270)
			(size 0.59 0.64)
			(layers "B.Cu" "B.Mask" "B.Paste")
			(roundrect_rratio 0.25)
			(net 1 "GND")
			(pintype "passive")
		)
		(pad "2" smd roundrect
			(at 0.48 0 270)
			(size 0.59 0.64)
			(layers "B.Cu" "B.Mask" "B.Paste")
			(roundrect_rratio 0.25)
			(net 797 "+1V8")
			(pintype "passive")
		)
	)
	(footprint "antmicro-footprints:R_0402_1005Metric"
		(layer "B.Cu")
		(at 188.4 104.2)
		(descr "Resistor SMD 0402")
		(tags "resistor SMD 0402")
		(property "Reference" "R26"
			(at 1.01 1.76 0)
			(layer "B.SilkS")
			(effects
				(font
					(size 0.7 0.7)
					(thickness 0.15)
				)
				(justify right bottom mirror)
			)
		)
		(property "Value" "R_0R_0402"
			(at -1.011843 -1.772047 0)
			(layer "B.Fab")
			(effects
				(font
					(size 0.7 0.7)
					(thickness 0.15)
				)
				(justify right bottom mirror)
			)
		)
		(property "Datasheet" "https://industrial.panasonic.com/cdbs/www-data/pdf/RDA0000/AOA0000C301.pdf"
			(at 0 0 0)
			(layer "F.Fab")
			(hide yes)
			(effects
				(font
					(size 1.27 1.27)
					(thickness 0.15)
				)
			)
		)
		(property "MPN" "ERJ2GE0R00X"
			(at 0 0 0)
			(unlocked yes)
			(layer "B.Fab")
			(hide yes)
			(effects
				(font
					(size 1 1)
					(thickness 0.15)
				)
				(justify mirror)
			)
		)
		(property "Manufacturer" "Panasonic"
			(at 0 0 0)
			(unlocked yes)
			(layer "B.Fab")
			(hide yes)
			(effects
				(font
					(size 1 1)
					(thickness 0.15)
				)
				(justify mirror)
			)
		)
		(property "License" "Apache-2.0"
			(at 0 0 0)
			(unlocked yes)
			(layer "B.Fab")
			(hide yes)
			(effects
				(font
					(size 1 1)
					(thickness 0.15)
				)
				(justify mirror)
			)
		)
		(property "Author" "Antmicro"
			(at 0 0 0)
			(unlocked yes)
			(layer "B.Fab")
			(hide yes)
			(effects
				(font
					(size 1 1)
					(thickness 0.15)
				)
				(justify mirror)
			)
		)
		(property "Val" "0R"
			(at 0 0 0)
			(unlocked yes)
			(layer "B.Fab")
			(hide yes)
			(effects
				(font
					(size 1 1)
					(thickness 0.15)
				)
				(justify mirror)
			)
		)
		(property "Tolerance" "~"
			(at 0 0 0)
			(unlocked yes)
			(layer "B.Fab")
			(hide yes)
			(effects
				(font
					(size 1 1)
					(thickness 0.15)
				)
				(justify mirror)
			)
		)
		(property "Current" "1A"
			(at 0 0 0)
			(unlocked yes)
			(layer "B.Fab")
			(hide yes)
			(effects
				(font
					(size 1 1)
					(thickness 0.15)
				)
				(justify mirror)
			)
		)
		(sheetname "/DDR5 RDIMM/")
		(sheetfile "ddr5-rdimm.kicad_sch")
		(attr smd exclude_from_bom dnp)
		(fp_rect
			(start -0.925 0.47)
			(end 0.925 -0.47)
			(stroke
				(width 0.05)
				(type default)
			)
			(fill no)
			(layer "B.CrtYd")
		)
		(fp_rect
			(start -0.5 0.25)
			(end 0.5 -0.25)
			(stroke
				(width 0.15)
				(type solid)
			)
			(fill no)
			(layer "B.Fab")
		)
		(fp_text user "${REFERENCE}"
			(at -0.95 -3.168 180)
			(layer "B.Fab")
			(effects
				(font
					(size 0.7 0.7)
					(thickness 0.15)
				)
				(justify left bottom mirror)
			)
		)
		(fp_text user "Author: Antmicro"
			(at -0.95 -4.169 180)
			(layer "B.Fab")
			(effects
				(font
					(size 0.7 0.7)
					(thickness 0.15)
				)
				(justify left bottom mirror)
			)
		)
		(fp_text user "License: Apache-2.0"
			(at -0.95 -5.169 180)
			(layer "B.Fab")
			(effects
				(font
					(size 0.7 0.7)
					(thickness 0.15)
				)
				(justify left bottom mirror)
			)
		)
		(pad "1" smd roundrect
			(at -0.48 0)
			(size 0.59 0.64)
			(layers "B.Cu" "B.Mask" "B.Paste")
			(roundrect_rratio 0.25)
			(net 1 "GND")
			(pintype "passive")
		)
		(pad "2" smd roundrect
			(at 0.48 0)
			(size 0.59 0.64)
			(layers "B.Cu" "B.Mask" "B.Paste")
			(roundrect_rratio 0.25)
			(net 703 "/DDR5 RDIMM/VSS_DET1")
			(pintype "passive")
		)
	)
	(footprint "antmicro-footprints:C_0402_1005Metric_EIA"
		(layer "B.Cu")
		(at 192 154.5 -90)
		(descr "Capacitor SMD 0402 (1005 Metric), square (rectangular) end terminal, IPC_7351 nominal, (Body size source: IPC-SM-782 page 76, https://www.pcb-3d.com/wordpress/wp-content/uploads/ipc-sm-782a_amendment_1_and_2.pdf)")
		(tags "capacitor 0402")
		(property "Reference" "C75"
			(at -12.125 30.65 90)
			(layer "B.SilkS")
			(effects
				(font
					(size 0.7 0.7)
					(thickness 0.15)
				)
				(justify left bottom mirror)
			)
		)
		(property "Value" "C_1u_25V_0402"
			(at 0 -1.169 90)
			(layer "B.Fab")
			(effects
				(font
					(size 0.7 0.7)
					(thickness 0.15)
				)
				(justify left bottom mirror)
			)
		)
		(property "Datasheet" "https://www.murata.com/products/productdetail?partno=GRM155R61E105KE11%23"
			(at 0 0 270)
			(layer "F.Fab")
			(hide yes)
			(effects
				(font
					(size 1.27 1.27)
					(thickness 0.15)
				)
			)
		)
		(property "MPN" "GRM155R61E105KE11J"
			(at 0 0 270)
			(unlocked yes)
			(layer "B.Fab")
			(hide yes)
			(effects
				(font
					(size 1 1)
					(thickness 0.15)
				)
				(justify mirror)
			)
		)
		(property "Manufacturer" "Murata"
			(at 0 0 270)
			(unlocked yes)
			(layer "B.Fab")
			(hide yes)
			(effects
				(font
					(size 1 1)
					(thickness 0.15)
				)
				(justify mirror)
			)
		)
		(property "License" "Apache-2.0"
			(at 0 0 270)
			(unlocked yes)
			(layer "B.Fab")
			(hide yes)
			(effects
				(font
					(size 1 1)
					(thickness 0.15)
				)
				(justify mirror)
			)
		)
		(property "Author" "Antmicro"
			(at 0 0 270)
			(unlocked yes)
			(layer "B.Fab")
			(hide yes)
			(effects
				(font
					(size 1 1)
					(thickness 0.15)
				)
				(justify mirror)
			)
		)
		(property "Val" "1u"
			(at 0 0 270)
			(unlocked yes)
			(layer "B.Fab")
			(hide yes)
			(effects
				(font
					(size 1 1)
					(thickness 0.15)
				)
				(justify mirror)
			)
		)
		(property "Voltage" "25V"
			(at 0 0 270)
			(unlocked yes)
			(layer "B.Fab")
			(hide yes)
			(effects
				(font
					(size 1 1)
					(thickness 0.15)
				)
				(justify mirror)
			)
		)
		(property "Dielectric" "X5R"
			(at 0 0 270)
			(unlocked yes)
			(layer "B.Fab")
			(hide yes)
			(effects
				(font
					(size 1 1)
					(thickness 0.15)
				)
				(justify mirror)
			)
		)
		(sheetname "/FPGA power/")
		(sheetfile "fpga-power.kicad_sch")
		(attr smd)
		(fp_rect
			(start -0.95 0.45)
			(end 0.95 -0.45)
			(stroke
				(width 0.05)
				(type default)
			)
			(fill no)
			(layer "B.CrtYd")
		)
		(fp_line
			(start -0.5 0.25)
			(end 0.498 0.25)
			(stroke
				(width 0.15)
				(type solid)
			)
			(layer "B.Fab")
		)
		(fp_line
			(start 0.498 0.25)
			(end 0.498 -0.248)
			(stroke
				(width 0.15)
				(type solid)
			)
			(layer "B.Fab")
		)
		(fp_line
			(start -0.5 -0.248)
			(end -0.5 0.25)
			(stroke
				(width 0.15)
				(type solid)
			)
			(layer "B.Fab")
		)
		(fp_line
			(start 0.498 -0.248)
			(end -0.5 -0.248)
			(stroke
				(width 0.15)
				(type solid)
			)
			(layer "B.Fab")
		)
		(fp_text user "Author: Antmicro"
			(at -0.9656 -5.569 90)
			(layer "B.Fab")
			(effects
				(font
					(size 0.7 0.7)
					(thickness 0.15)
				)
				(justify left bottom mirror)
			)
		)
		(fp_text user "License: Apache-2.0"
			(at -0.9656 -4.369 90)
			(layer "B.Fab")
			(effects
				(font
					(size 0.7 0.7)
					(thickness 0.15)
				)
				(justify left bottom mirror)
			)
		)
		(fp_text user "${REFERENCE}"
			(at -0.9656 -3.169 90)
			(layer "B.Fab")
			(effects
				(font
					(size 0.7 0.7)
					(thickness 0.15)
				)
				(justify left bottom mirror)
			)
		)
		(pad "1" smd roundrect
			(at -0.5 0 180)
			(size 0.6 0.6)
			(layers "B.Cu" "B.Mask" "B.Paste")
			(roundrect_rratio 0.25)
			(net 1 "GND")
			(pintype "passive")
		)
		(pad "2" smd roundrect
			(at 0.498 0 270)
			(size 0.6 0.6)
			(layers "B.Cu" "B.Mask" "B.Paste")
			(roundrect_rratio 0.25)
			(net 553 "+0V85")
			(pintype "passive")
		)
	)
	(footprint "antmicro-footprints:C_0402_1005Metric"
		(layer "B.Cu")
		(at 119.075 159.45 -90)
		(descr "Capacitor SMD 0402")
		(tags "capacitor SMD 0402")
		(property "Reference" "C299"
			(at 0.9 -0.525 90)
			(layer "B.SilkS")
			(effects
				(font
					(size 0.7 0.7)
					(thickness 0.15)
				)
				(justify left bottom mirror)
			)
		)
		(property "Value" "C_100n_0402"
			(at -1.022927 -2.155213 90)
			(layer "B.Fab")
			(effects
				(font
					(size 0.7 0.7)
					(thickness 0.15)
				)
				(justify left bottom mirror)
			)
		)
		(property "Datasheet" "https://www.murata.com/products/productdetail?partno=GRM155R61H104KE14%23"
			(at 0 0 270)
			(layer "F.Fab")
			(hide yes)
			(effects
				(font
					(size 1.27 1.27)
					(thickness 0.15)
				)
			)
		)
		(property "MPN" "GRM155R61H104KE14D"
			(at 0 0 270)
			(unlocked yes)
			(layer "B.Fab")
			(hide yes)
			(effects
				(font
					(size 1 1)
					(thickness 0.15)
				)
				(justify mirror)
			)
		)
		(property "Manufacturer" "Murata"
			(at 0 0 270)
			(unlocked yes)
			(layer "B.Fab")
			(hide yes)
			(effects
				(font
					(size 1 1)
					(thickness 0.15)
				)
				(justify mirror)
			)
		)
		(property "License" "Apache-2.0"
			(at 0 0 270)
			(unlocked yes)
			(layer "B.Fab")
			(hide yes)
			(effects
				(font
					(size 1 1)
					(thickness 0.15)
				)
				(justify mirror)
			)
		)
		(property "Author" "Antmicro"
			(at 0 0 270)
			(unlocked yes)
			(layer "B.Fab")
			(hide yes)
			(effects
				(font
					(size 1 1)
					(thickness 0.15)
				)
				(justify mirror)
			)
		)
		(property "Val" "100n"
			(at 0 0 270)
			(unlocked yes)
			(layer "B.Fab")
			(hide yes)
			(effects
				(font
					(size 1 1)
					(thickness 0.15)
				)
				(justify mirror)
			)
		)
		(property "Voltage" "50V"
			(at 0 0 270)
			(unlocked yes)
			(layer "B.Fab")
			(hide yes)
			(effects
				(font
					(size 1 1)
					(thickness 0.15)
				)
				(justify mirror)
			)
		)
		(property "Dielectric" "X5R"
			(at 0 0 270)
			(unlocked yes)
			(layer "B.Fab")
			(hide yes)
			(effects
				(font
					(size 1 1)
					(thickness 0.15)
				)
				(justify mirror)
			)
		)
		(sheetname "/HDMI + SD Card/")
		(sheetfile "hdmi-sd-card.kicad_sch")
		(attr smd)
		(fp_rect
			(start -0.925 0.47)
			(end 0.925 -0.47)
			(stroke
				(width 0.05)
				(type default)
			)
			(fill no)
			(layer "B.CrtYd")
		)
		(fp_line
			(start -0.494 0.25)
			(end 0.504 0.25)
			(stroke
				(width 0.15)
				(type solid)
			)
			(layer "B.Fab")
		)
		(fp_line
			(start 0.504 0.25)
			(end 0.504 -0.248)
			(stroke
				(width 0.15)
				(type solid)
			)
			(layer "B.Fab")
		)
		(fp_line
			(start -0.494 -0.248)
			(end -0.494 0.25)
			(stroke
				(width 0.15)
				(type solid)
			)
			(layer "B.Fab")
		)
		(fp_line
			(start 0.504 -0.248)
			(end -0.494 -0.248)
			(stroke
				(width 0.15)
				(type solid)
			)
			(layer "B.Fab")
		)
		(fp_text user "License: Apache-2.0"
			(at -0.939 -5.799 90)
			(layer "B.Fab")
			(effects
				(font
					(size 0.7 0.7)
					(thickness 0.15)
				)
				(justify left bottom mirror)
			)
		)
		(fp_text user "Author: Antmicro"
			(at -0.939 -3.399 90)
			(layer "B.Fab")
			(effects
				(font
					(size 0.7 0.7)
					(thickness 0.15)
				)
				(justify left bottom mirror)
			)
		)
		(fp_text user "${REFERENCE}"
			(at -0.939 -4.599 90)
			(layer "B.Fab")
			(effects
				(font
					(size 0.7 0.7)
					(thickness 0.15)
				)
				(justify left bottom mirror)
			)
		)
		(pad "1" smd roundrect
			(at -0.48 0 270)
			(size 0.59 0.64)
			(layers "B.Cu" "B.Mask" "B.Paste")
			(roundrect_rratio 0.25)
			(net 1 "GND")
			(pintype "passive")
		)
		(pad "2" smd roundrect
			(at 0.48 0 270)
			(size 0.59 0.64)
			(layers "B.Cu" "B.Mask" "B.Paste")
			(roundrect_rratio 0.25)
			(net 647 "/HDMI + SD Card/VCCB")
			(pintype "passive")
		)
	)
	(footprint "antmicro-footprints:R_0402_1005Metric"
		(layer "B.Cu")
		(at 240.12 171.425)
		(descr "Resistor SMD 0402")
		(tags "resistor SMD 0402")
		(property "Reference" "R215"
			(at 1.655 0.5 0)
			(layer "B.SilkS")
			(effects
				(font
					(size 0.7 0.7)
					(thickness 0.15)
				)
				(justify right bottom mirror)
			)
		)
		(property "Value" "R_100R_0402"
			(at -1.011843 -1.772047 0)
			(layer "B.Fab")
			(effects
				(font
					(size 0.7 0.7)
					(thickness 0.15)
				)
				(justify right bottom mirror)
			)
		)
		(property "Datasheet" "https://www.bourns.com/docs/product-datasheets/cr.pdf"
			(at 0 0 0)
			(layer "F.Fab")
			(hide yes)
			(effects
				(font
					(size 1.27 1.27)
					(thickness 0.15)
				)
			)
		)
		(property "MPN" "CR0402-FX-1000GLF"
			(at 0 0 0)
			(unlocked yes)
			(layer "B.Fab")
			(hide yes)
			(effects
				(font
					(size 1 1)
					(thickness 0.15)
				)
				(justify mirror)
			)
		)
		(property "Manufacturer" "Bourns"
			(at 0 0 0)
			(unlocked yes)
			(layer "B.Fab")
			(hide yes)
			(effects
				(font
					(size 1 1)
					(thickness 0.15)
				)
				(justify mirror)
			)
		)
		(property "License" "Apache-2.0"
			(at 0 0 0)
			(unlocked yes)
			(layer "B.Fab")
			(hide yes)
			(effects
				(font
					(size 1 1)
					(thickness 0.15)
				)
				(justify mirror)
			)
		)
		(property "Author" "Antmicro"
			(at 0 0 0)
			(unlocked yes)
			(layer "B.Fab")
			(hide yes)
			(effects
				(font
					(size 1 1)
					(thickness 0.15)
				)
				(justify mirror)
			)
		)
		(property "Val" "100R"
			(at 0 0 0)
			(unlocked yes)
			(layer "B.Fab")
			(hide yes)
			(effects
				(font
					(size 1 1)
					(thickness 0.15)
				)
				(justify mirror)
			)
		)
		(property "Tolerance" "1%"
			(at 0 0 0)
			(unlocked yes)
			(layer "B.Fab")
			(hide yes)
			(effects
				(font
					(size 1 1)
					(thickness 0.15)
				)
				(justify mirror)
			)
		)
		(sheetname "/Supply/DC-DC AUX, MGT/")
		(sheetfile "dc-dc-aux-mgt.kicad_sch")
		(attr smd)
		(fp_rect
			(start -0.925 0.47)
			(end 0.925 -0.47)
			(stroke
				(width 0.05)
				(type default)
			)
			(fill no)
			(layer "B.CrtYd")
		)
		(fp_rect
			(start -0.5 0.25)
			(end 0.5 -0.25)
			(stroke
				(width 0.15)
				(type solid)
			)
			(fill no)
			(layer "B.Fab")
		)
		(fp_text user "License: Apache-2.0"
			(at -0.95 -5.169 180)
			(layer "B.Fab")
			(effects
				(font
					(size 0.7 0.7)
					(thickness 0.15)
				)
				(justify left bottom mirror)
			)
		)
		(fp_text user "${REFERENCE}"
			(at -0.95 -3.168 180)
			(layer "B.Fab")
			(effects
				(font
					(size 0.7 0.7)
					(thickness 0.15)
				)
				(justify left bottom mirror)
			)
		)
		(fp_text user "Author: Antmicro"
			(at -0.95 -4.169 180)
			(layer "B.Fab")
			(effects
				(font
					(size 0.7 0.7)
					(thickness 0.15)
				)
				(justify left bottom mirror)
			)
		)
		(pad "1" smd roundrect
			(at -0.48 0)
			(size 0.59 0.64)
			(layers "B.Cu" "B.Mask" "B.Paste")
			(roundrect_rratio 0.25)
			(net 1 "GND")
			(pintype "passive")
		)
		(pad "2" smd roundrect
			(at 0.48 0)
			(size 0.59 0.64)
			(layers "B.Cu" "B.Mask" "B.Paste")
			(roundrect_rratio 0.25)
			(net 735 "Net-(U25-ADDRSEL)")
			(pintype "passive")
		)
	)
	(footprint "antmicro-footprints:SC70-3"
		(layer "B.Cu")
		(at 114.755 115.65 180)
		(property "Reference" "Q8"
			(at -3.355 -0.334 0)
			(layer "B.SilkS")
			(effects
				(font
					(size 0.7 0.7)
					(thickness 0.15)
				)
				(justify left bottom mirror)
			)
		)
		(property "Value" "BSS138PW"
			(at 0 -2.3 0)
			(layer "B.Fab")
			(effects
				(font
					(size 0.7 0.7)
					(thickness 0.15)
				)
				(justify left bottom mirror)
			)
		)
		(property "Datasheet" "https://assets.nexperia.com/documents/data-sheet/BSS138PW.pdf"
			(at 0 0 180)
			(layer "F.Fab")
			(hide yes)
			(effects
				(font
					(size 1.27 1.27)
					(thickness 0.15)
				)
			)
		)
		(property "MPN" "BSS138PW"
			(at 0 0 180)
			(unlocked yes)
			(layer "B.Fab")
			(hide yes)
			(effects
				(font
					(size 1 1)
					(thickness 0.15)
				)
				(justify mirror)
			)
		)
		(property "Manufacturer" "Nexperia"
			(at 0 0 180)
			(unlocked yes)
			(layer "B.Fab")
			(hide yes)
			(effects
				(font
					(size 1 1)
					(thickness 0.15)
				)
				(justify mirror)
			)
		)
		(property "Author" "Antmicro"
			(at 0 0 180)
			(unlocked yes)
			(layer "B.Fab")
			(hide yes)
			(effects
				(font
					(size 1 1)
					(thickness 0.15)
				)
				(justify mirror)
			)
		)
		(property "License" "Apache-2.0"
			(at 0 0 180)
			(unlocked yes)
			(layer "B.Fab")
			(hide yes)
			(effects
				(font
					(size 1 1)
					(thickness 0.15)
				)
				(justify mirror)
			)
		)
		(sheetname "/FPGA banks HD/")
		(sheetfile "fpga-hd-banks.kicad_sch")
		(attr smd)
		(fp_line
			(start 0.627 0.6)
			(end 0.627 0.999)
			(stroke
				(width 0.15)
				(type solid)
			)
			(layer "B.SilkS")
		)
		(fp_line
			(start 0.627 -0.6)
			(end 0.627 -1.001)
			(stroke
				(width 0.15)
				(type solid)
			)
			(layer "B.SilkS")
		)
		(fp_line
			(start -0.3 1)
			(end 0.627 0.999)
			(stroke
				(width 0.15)
				(type solid)
			)
			(layer "B.SilkS")
		)
		(fp_line
			(start -0.3 -1)
			(end 0.627 -1.001)
			(stroke
				(width 0.15)
				(type solid)
			)
			(layer "B.SilkS")
		)
		(fp_line
			(start 1.4 0.4)
			(end 1.4 -0.4)
			(stroke
				(width 0.05)
				(type solid)
			)
			(layer "B.CrtYd")
		)
		(fp_line
			(start 1.4 -0.4)
			(end 0.9 -0.4)
			(stroke
				(width 0.05)
				(type solid)
			)
			(layer "B.CrtYd")
		)
		(fp_line
			(start 0.9 1.3)
			(end 0.9 0.4)
			(stroke
				(width 0.05)
				(type solid)
			)
			(layer "B.CrtYd")
		)
		(fp_line
			(start 0.9 0.4)
			(end 1.4 0.4)
			(stroke
				(width 0.05)
				(type solid)
			)
			(layer "B.CrtYd")
		)
		(fp_line
			(start 0.9 -0.4)
			(end 0.9 -1.3)
			(stroke
				(width 0.05)
				(type solid)
			)
			(layer "B.CrtYd")
		)
		(fp_line
			(start 0.9 -1.3)
			(end -0.9 -1.3)
			(stroke
				(width 0.05)
				(type solid)
			)
			(layer "B.CrtYd")
		)
		(fp_line
			(start -0.9 1.3)
			(end 0.9 1.3)
			(stroke
				(width 0.05)
				(type solid)
			)
			(layer "B.CrtYd")
		)
		(fp_line
			(start -0.9 1.3)
			(end -0.9 1)
			(stroke
				(width 0.05)
				(type solid)
			)
			(layer "B.CrtYd")
		)
		(fp_line
			(start -0.9 1)
			(end -1.4 1)
			(stroke
				(width 0.05)
				(type solid)
			)
			(layer "B.CrtYd")
		)
		(fp_line
			(start -0.9 -1)
			(end -1.4 -1)
			(stroke
				(width 0.05)
				(type solid)
			)
			(layer "B.CrtYd")
		)
		(fp_line
			(start -0.9 -1.3)
			(end -0.9 -1)
			(stroke
				(width 0.05)
				(type solid)
			)
			(layer "B.CrtYd")
		)
		(fp_line
			(start -1.4 -1)
			(end -1.4 1)
			(stroke
				(width 0.05)
				(type solid)
			)
			(layer "B.CrtYd")
		)
		(fp_rect
			(start -0.623 0.999)
			(end 0.627 -1.001)
			(stroke
				(width 0.15)
				(type solid)
			)
			(fill no)
			(layer "B.Fab")
		)
		(fp_text user "License: Apache-2.0"
			(at -1.45 -6.782 0)
			(layer "B.Fab")
			(effects
				(font
					(size 0.7 0.7)
					(thickness 0.15)
				)
				(justify left bottom mirror)
			)
		)
		(fp_text user "${REFERENCE}"
			(at -1.45 -4.783 0)
			(layer "B.Fab")
			(effects
				(font
					(size 0.7 0.7)
					(thickness 0.15)
				)
				(justify left bottom mirror)
			)
		)
		(fp_text user "Author: Antmicro"
			(at -1.45 -5.782 0)
			(layer "B.Fab")
			(effects
				(font
					(size 0.7 0.7)
					(thickness 0.15)
				)
				(justify left bottom mirror)
			)
		)
		(pad "1" smd rect
			(at -1.051 0.65 90)
			(size 0.6 0.6)
			(layers "B.Cu" "B.Mask" "B.Paste")
			(net 697 "/FPGA banks HD/USR_LED1")
			(pinfunction "G")
			(pintype "passive")
		)
		(pad "2" smd rect
			(at -1.051 -0.65 90)
			(size 0.6 0.6)
			(layers "B.Cu" "B.Mask" "B.Paste")
			(net 1 "GND")
			(pinfunction "S")
			(pintype "passive")
		)
		(pad "3" smd rect
			(at 1.05 0 90)
			(size 0.6 0.6)
			(layers "B.Cu" "B.Mask" "B.Paste")
			(net 276 "Net-(Q8-D)")
			(pinfunction "D")
			(pintype "passive")
		)
	)
	(footprint "antmicro-footprints:C_0603_1608Metric"
		(layer "B.Cu")
		(at 148.275 192.625 180)
		(descr "Capacitor SMD 0603")
		(tags "capacitor 0603")
		(property "Reference" "C224"
			(at -4.045 -0.595 0)
			(layer "B.SilkS")
			(effects
				(font
					(size 0.7 0.7)
					(thickness 0.15)
				)
				(justify left bottom mirror)
			)
		)
		(property "Value" "C_10u_25V_0603"
			(at -1.42757 -1.770288 0)
			(layer "B.Fab")
			(effects
				(font
					(size 0.7 0.7)
					(thickness 0.15)
				)
				(justify left bottom mirror)
			)
		)
		(property "Datasheet" "https://product.tdk.com/en/search/capacitor/ceramic/mlcc/info?part_no=C1608X5R1E106M080AC"
			(at 0 0 180)
			(layer "F.Fab")
			(hide yes)
			(effects
				(font
					(size 1.27 1.27)
					(thickness 0.15)
				)
			)
		)
		(property "MPN" "C1608X5R1E106M080AC"
			(at 0 0 180)
			(unlocked yes)
			(layer "B.Fab")
			(hide yes)
			(effects
				(font
					(size 1 1)
					(thickness 0.15)
				)
				(justify mirror)
			)
		)
		(property "Manufacturer" "TDK"
			(at 0 0 180)
			(unlocked yes)
			(layer "B.Fab")
			(hide yes)
			(effects
				(font
					(size 1 1)
					(thickness 0.15)
				)
				(justify mirror)
			)
		)
		(property "License" "Apache-2.0"
			(at 0 0 180)
			(unlocked yes)
			(layer "B.Fab")
			(hide yes)
			(effects
				(font
					(size 1 1)
					(thickness 0.15)
				)
				(justify mirror)
			)
		)
		(property "Author" "Antmicro"
			(at 0 0 180)
			(unlocked yes)
			(layer "B.Fab")
			(hide yes)
			(effects
				(font
					(size 1 1)
					(thickness 0.15)
				)
				(justify mirror)
			)
		)
		(property "Val" "10u"
			(at 0 0 180)
			(unlocked yes)
			(layer "B.Fab")
			(hide yes)
			(effects
				(font
					(size 1 1)
					(thickness 0.15)
				)
				(justify mirror)
			)
		)
		(property "Voltage" "25V"
			(at 0 0 180)
			(unlocked yes)
			(layer "B.Fab")
			(hide yes)
			(effects
				(font
					(size 1 1)
					(thickness 0.15)
				)
				(justify mirror)
			)
		)
		(property "Dielectric" ""
			(at 0 0 180)
			(unlocked yes)
			(layer "B.Fab")
			(hide yes)
			(effects
				(font
					(size 1 1)
					(thickness 0.15)
				)
				(justify mirror)
			)
		)
		(sheetname "/PCIe connector/")
		(sheetfile "pcie-connector.kicad_sch")
		(attr smd)
		(fp_line
			(start -0.15 0.4)
			(end 0.15 0.4)
			(stroke
				(width 0.15)
				(type solid)
			)
			(layer "B.SilkS")
		)
		(fp_line
			(start -0.15 -0.4)
			(end 0.15 -0.4)
			(stroke
				(width 0.15)
				(type solid)
			)
			(layer "B.SilkS")
		)
		(fp_rect
			(start -1.25 0.65)
			(end 1.25 -0.65)
			(stroke
				(width 0.05)
				(type solid)
			)
			(fill no)
			(layer "B.CrtYd")
		)
		(fp_rect
			(start -0.8 0.4)
			(end 0.8 -0.4)
			(stroke
				(width 0.15)
				(type solid)
			)
			(fill no)
			(layer "B.Fab")
		)
		(fp_text user "${REFERENCE}"
			(at -1.682 -3.895 0)
			(layer "B.Fab")
			(effects
				(font
					(size 0.7 0.7)
					(thickness 0.15)
				)
				(justify left bottom mirror)
			)
		)
		(fp_text user "Author: Antmicro"
			(at -1.682 -4.894 0)
			(layer "B.Fab")
			(effects
				(font
					(size 0.7 0.7)
					(thickness 0.15)
				)
				(justify left bottom mirror)
			)
		)
		(fp_text user "License: Apache-2.0"
			(at -1.682 -5.895 0)
			(layer "B.Fab")
			(effects
				(font
					(size 0.7 0.7)
					(thickness 0.15)
				)
				(justify left bottom mirror)
			)
		)
		(pad "1" smd roundrect
			(at -0.7 0 180)
			(size 0.8 1)
			(layers "B.Cu" "B.Mask" "B.Paste")
			(roundrect_rratio 0.2)
			(net 1 "GND")
			(pintype "passive")
		)
		(pad "2" smd roundrect
			(at 0.7 0 180)
			(size 0.8 1)
			(layers "B.Cu" "B.Mask" "B.Paste")
			(roundrect_rratio 0.2)
			(net 10 "+12V")
			(pintype "passive")
		)
	)
	(footprint "antmicro-footprints:R_0402_1005Metric"
		(layer "B.Cu")
		(at 250.375 122.225)
		(descr "Resistor SMD 0402")
		(tags "resistor SMD 0402")
		(property "Reference" "R240"
			(at -1.4 1.625 0)
			(layer "B.SilkS")
			(effects
				(font
					(size 0.7 0.7)
					(thickness 0.15)
				)
				(justify right bottom mirror)
			)
		)
		(property "Value" "R_47k_0402"
			(at -1.011843 -1.772047 0)
			(layer "B.Fab")
			(effects
				(font
					(size 0.7 0.7)
					(thickness 0.15)
				)
				(justify right bottom mirror)
			)
		)
		(property "Datasheet" "https://www.bourns.com/docs/product-datasheets/cr.pdf"
			(at 0 0 0)
			(layer "F.Fab")
			(hide yes)
			(effects
				(font
					(size 1.27 1.27)
					(thickness 0.15)
				)
			)
		)
		(property "MPN" "CR0402-FX-4702GLF"
			(at 0 0 0)
			(unlocked yes)
			(layer "B.Fab")
			(hide yes)
			(effects
				(font
					(size 1 1)
					(thickness 0.15)
				)
				(justify mirror)
			)
		)
		(property "Manufacturer" "Bourns"
			(at 0 0 0)
			(unlocked yes)
			(layer "B.Fab")
			(hide yes)
			(effects
				(font
					(size 1 1)
					(thickness 0.15)
				)
				(justify mirror)
			)
		)
		(property "License" "Apache-2.0"
			(at 0 0 0)
			(unlocked yes)
			(layer "B.Fab")
			(hide yes)
			(effects
				(font
					(size 1 1)
					(thickness 0.15)
				)
				(justify mirror)
			)
		)
		(property "Author" "Antmicro"
			(at 0 0 0)
			(unlocked yes)
			(layer "B.Fab")
			(hide yes)
			(effects
				(font
					(size 1 1)
					(thickness 0.15)
				)
				(justify mirror)
			)
		)
		(property "Val" "47k"
			(at 0 0 0)
			(unlocked yes)
			(layer "B.Fab")
			(hide yes)
			(effects
				(font
					(size 1 1)
					(thickness 0.15)
				)
				(justify mirror)
			)
		)
		(property "Tolerance" "1%"
			(at 0 0 0)
			(unlocked yes)
			(layer "B.Fab")
			(hide yes)
			(effects
				(font
					(size 1 1)
					(thickness 0.15)
				)
				(justify mirror)
			)
		)
		(sheetname "/DDR5 RDIMM/")
		(sheetfile "ddr5-rdimm.kicad_sch")
		(attr smd)
		(fp_rect
			(start -0.925 0.47)
			(end 0.925 -0.47)
			(stroke
				(width 0.05)
				(type default)
			)
			(fill no)
			(layer "B.CrtYd")
		)
		(fp_rect
			(start -0.5 0.25)
			(end 0.5 -0.25)
			(stroke
				(width 0.15)
				(type solid)
			)
			(fill no)
			(layer "B.Fab")
		)
		(fp_text user "${REFERENCE}"
			(at -0.95 -3.168 180)
			(layer "B.Fab")
			(effects
				(font
					(size 0.7 0.7)
					(thickness 0.15)
				)
				(justify left bottom mirror)
			)
		)
		(fp_text user "Author: Antmicro"
			(at -0.95 -4.169 180)
			(layer "B.Fab")
			(effects
				(font
					(size 0.7 0.7)
					(thickness 0.15)
				)
				(justify left bottom mirror)
			)
		)
		(fp_text user "License: Apache-2.0"
			(at -0.95 -5.169 180)
			(layer "B.Fab")
			(effects
				(font
					(size 0.7 0.7)
					(thickness 0.15)
				)
				(justify left bottom mirror)
			)
		)
		(pad "1" smd roundrect
			(at -0.48 0)
			(size 0.59 0.64)
			(layers "B.Cu" "B.Mask" "B.Paste")
			(roundrect_rratio 0.25)
			(net 1 "GND")
			(pintype "passive")
		)
		(pad "2" smd roundrect
			(at 0.48 0)
			(size 0.59 0.64)
			(layers "B.Cu" "B.Mask" "B.Paste")
			(roundrect_rratio 0.25)
			(net 808 "VIN_BULK_EN")
			(pintype "passive")
		)
	)
	(footprint "antmicro-footprints:R_0402_1005Metric"
		(layer "B.Cu")
		(at 254.274499 132.199 90)
		(descr "Resistor SMD 0402")
		(tags "resistor SMD 0402")
		(property "Reference" "R149"
			(at 1.324 -0.599499 90)
			(layer "B.SilkS")
			(effects
				(font
					(size 0.7 0.7)
					(thickness 0.15)
				)
				(justify right bottom mirror)
			)
		)
		(property "Value" "R_47k_0402"
			(at -1.011843 -1.772047 90)
			(layer "B.Fab")
			(effects
				(font
					(size 0.7 0.7)
					(thickness 0.15)
				)
				(justify right bottom mirror)
			)
		)
		(property "Datasheet" "https://www.bourns.com/docs/product-datasheets/cr.pdf"
			(at 0 0 90)
			(layer "F.Fab")
			(hide yes)
			(effects
				(font
					(size 1.27 1.27)
					(thickness 0.15)
				)
			)
		)
		(property "Manufacturer" "Bourns"
			(at 0 0 90)
			(unlocked yes)
			(layer "B.Fab")
			(hide yes)
			(effects
				(font
					(size 1 1)
					(thickness 0.15)
				)
				(justify mirror)
			)
		)
		(property "MPN" "CR0402-FX-4702GLF"
			(at 0 0 90)
			(unlocked yes)
			(layer "B.Fab")
			(hide yes)
			(effects
				(font
					(size 1 1)
					(thickness 0.15)
				)
				(justify mirror)
			)
		)
		(property "Val" "47k"
			(at 0 0 90)
			(unlocked yes)
			(layer "B.Fab")
			(hide yes)
			(effects
				(font
					(size 1 1)
					(thickness 0.15)
				)
				(justify mirror)
			)
		)
		(property "License" "Apache-2.0"
			(at 0 0 90)
			(unlocked yes)
			(layer "B.Fab")
			(hide yes)
			(effects
				(font
					(size 1 1)
					(thickness 0.15)
				)
				(justify mirror)
			)
		)
		(property "Author" "Antmicro"
			(at 0 0 90)
			(unlocked yes)
			(layer "B.Fab")
			(hide yes)
			(effects
				(font
					(size 1 1)
					(thickness 0.15)
				)
				(justify mirror)
			)
		)
		(property "Tolerance" "1%"
			(at 0 0 90)
			(unlocked yes)
			(layer "B.Fab")
			(hide yes)
			(effects
				(font
					(size 1 1)
					(thickness 0.15)
				)
				(justify mirror)
			)
		)
		(sheetname "/Supply/")
		(sheetfile "supply.kicad_sch")
		(attr smd)
		(fp_rect
			(start -0.925 0.47)
			(end 0.925 -0.47)
			(stroke
				(width 0.05)
				(type default)
			)
			(fill no)
			(layer "B.CrtYd")
		)
		(fp_rect
			(start -0.5 0.25)
			(end 0.5 -0.25)
			(stroke
				(width 0.15)
				(type solid)
			)
			(fill no)
			(layer "B.Fab")
		)
		(fp_text user "License: Apache-2.0"
			(at -0.95 -5.169 270)
			(layer "B.Fab")
			(effects
				(font
					(size 0.7 0.7)
					(thickness 0.15)
				)
				(justify left bottom mirror)
			)
		)
		(fp_text user "${REFERENCE}"
			(at -0.95 -3.168 270)
			(layer "B.Fab")
			(effects
				(font
					(size 0.7 0.7)
					(thickness 0.15)
				)
				(justify left bottom mirror)
			)
		)
		(fp_text user "Author: Antmicro"
			(at -0.95 -4.169 270)
			(layer "B.Fab")
			(effects
				(font
					(size 0.7 0.7)
					(thickness 0.15)
				)
				(justify left bottom mirror)
			)
		)
		(pad "1" smd roundrect
			(at -0.48 0 90)
			(size 0.59 0.64)
			(layers "B.Cu" "B.Mask" "B.Paste")
			(roundrect_rratio 0.25)
			(net 137 "/Supply/~{PB_CTRL_CLR}")
			(pintype "passive")
		)
		(pad "2" smd roundrect
			(at 0.48 0 90)
			(size 0.59 0.64)
			(layers "B.Cu" "B.Mask" "B.Paste")
			(roundrect_rratio 0.25)
			(net 138 "/Supply/PB_CTRL_OUT")
			(pintype "passive")
		)
	)
	(footprint "antmicro-footprints:SOT-323"
		(layer "B.Cu")
		(at 247.05 183.399)
		(property "Reference" "Q22"
			(at -1.05 -1.6 0)
			(layer "B.SilkS")
			(effects
				(font
					(size 0.7 0.7)
					(thickness 0.15)
				)
				(justify right bottom mirror)
			)
		)
		(property "Value" "BSS84AKW"
			(at 0 -2.749 0)
			(layer "B.Fab")
			(effects
				(font
					(size 0.7 0.7)
					(thickness 0.15)
				)
				(justify right bottom mirror)
			)
		)
		(property "Datasheet" "https://assets.nexperia.com/documents/data-sheet/BSS84AKW.pdf"
			(at 0 0 0)
			(layer "F.Fab")
			(hide yes)
			(effects
				(font
					(size 1.27 1.27)
					(thickness 0.15)
				)
			)
		)
		(property "MPN" "BSS84AKW,115"
			(at 0 0 0)
			(unlocked yes)
			(layer "B.Fab")
			(hide yes)
			(effects
				(font
					(size 1 1)
					(thickness 0.15)
				)
				(justify mirror)
			)
		)
		(property "Manufacturer" "Nexperia"
			(at 0 0 0)
			(unlocked yes)
			(layer "B.Fab")
			(hide yes)
			(effects
				(font
					(size 1 1)
					(thickness 0.15)
				)
				(justify mirror)
			)
		)
		(property "Author" "Antmicro"
			(at 0 0 0)
			(unlocked yes)
			(layer "B.Fab")
			(hide yes)
			(effects
				(font
					(size 1 1)
					(thickness 0.15)
				)
				(justify mirror)
			)
		)
		(property "License" "Apache-2.0"
			(at 0 0 0)
			(unlocked yes)
			(layer "B.Fab")
			(hide yes)
			(effects
				(font
					(size 1 1)
					(thickness 0.15)
				)
				(justify mirror)
			)
		)
		(sheetname "/I^{2}C + I3C/")
		(sheetfile "i2c.kicad_sch")
		(attr smd)
		(fp_line
			(start -0.802 -1.199)
			(end -0.5 -1.199)
			(stroke
				(width 0.15)
				(type solid)
			)
			(layer "B.SilkS")
		)
		(fp_line
			(start -0.802 -1.05)
			(end -0.802 -1.199)
			(stroke
				(width 0.15)
				(type solid)
			)
			(layer "B.SilkS")
		)
		(fp_line
			(start -0.802 1.2)
			(end -0.802 1.05)
			(stroke
				(width 0.15)
				(type solid)
			)
			(layer "B.SilkS")
		)
		(fp_line
			(start -0.402 1.2)
			(end -0.802 1.2)
			(stroke
				(width 0.15)
				(type solid)
			)
			(layer "B.SilkS")
		)
		(fp_line
			(start 0.498 -1.199)
			(end 0.8 -1.199)
			(stroke
				(width 0.15)
				(type solid)
			)
			(layer "B.SilkS")
		)
		(fp_line
			(start 0.498 1.2)
			(end 0.8 1.2)
			(stroke
				(width 0.15)
				(type solid)
			)
			(layer "B.SilkS")
		)
		(fp_line
			(start 0.8 -1.199)
			(end 0.8 -0.9)
			(stroke
				(width 0.15)
				(type solid)
			)
			(layer "B.SilkS")
		)
		(fp_line
			(start 0.8 1.2)
			(end 0.8 0.902)
			(stroke
				(width 0.15)
				(type solid)
			)
			(layer "B.SilkS")
		)
		(fp_circle
			(center -1.05 1.156824)
			(end -1 1.129824)
			(stroke
				(width 0.15)
				(type solid)
			)
			(fill no)
			(layer "B.SilkS")
		)
		(fp_rect
			(start -1.35 1.35)
			(end 1.35 -1.35)
			(stroke
				(width 0.05)
				(type solid)
			)
			(fill no)
			(layer "B.CrtYd")
		)
		(fp_line
			(start -0.677 -1.1)
			(end 0.675 -1.1)
			(stroke
				(width 0.15)
				(type solid)
			)
			(layer "B.Fab")
		)
		(fp_line
			(start -0.677 1.101)
			(end -0.677 -1.1)
			(stroke
				(width 0.15)
				(type solid)
			)
			(layer "B.Fab")
		)
		(fp_line
			(start -0.677 1.101)
			(end 0.675 1.101)
			(stroke
				(width 0.15)
				(type solid)
			)
			(layer "B.Fab")
		)
		(fp_line
			(start 0.675 1.101)
			(end 0.675 -1.1)
			(stroke
				(width 0.15)
				(type solid)
			)
			(layer "B.Fab")
		)
		(fp_text user "Author: Antmicro"
			(at -1.35 -7.149 180)
			(layer "B.Fab")
			(effects
				(font
					(size 0.7 0.7)
					(thickness 0.15)
				)
				(justify left bottom mirror)
			)
		)
		(fp_text user "${REFERENCE}"
			(at -1.35 -4.749 180)
			(layer "B.Fab")
			(effects
				(font
					(size 0.7 0.7)
					(thickness 0.15)
				)
				(justify left bottom mirror)
			)
		)
		(fp_text user "License: Apache-2.0"
			(at -1.35 -5.949 180)
			(layer "B.Fab")
			(effects
				(font
					(size 0.7 0.7)
					(thickness 0.15)
				)
				(justify left bottom mirror)
			)
		)
		(pad "1" smd rect
			(at -0.927 0.652)
			(size 0.55 0.6)
			(layers "B.Cu" "B.Mask" "B.Paste")
			(net 778 "~{FPGA_I3C_EXT_PU}")
			(pinfunction "G")
			(pintype "bidirectional")
		)
		(pad "2" smd rect
			(at -0.927 -0.65)
			(size 0.55 0.6)
			(layers "B.Cu" "B.Mask" "B.Paste")
			(net 151 "+3V3")
			(pinfunction "S")
			(pintype "bidirectional")
		)
		(pad "3" smd rect
			(at 0.925 0)
			(size 0.55 0.6)
			(layers "B.Cu" "B.Mask" "B.Paste")
			(net 662 "Net-(Q22-D)")
			(pinfunction "D")
			(pintype "bidirectional")
		)
	)
	(footprint "antmicro-footprints:R_0402_1005Metric"
		(layer "B.Cu")
		(at 237.925 153.27 90)
		(descr "Resistor SMD 0402")
		(tags "resistor SMD 0402")
		(property "Reference" "R213"
			(at 0.97 0.475 90)
			(layer "B.SilkS")
			(effects
				(font
					(size 0.7 0.7)
					(thickness 0.15)
				)
				(justify right bottom mirror)
			)
		)
		(property "Value" "R_0R_0402"
			(at -1.011843 -1.772047 90)
			(layer "B.Fab")
			(effects
				(font
					(size 0.7 0.7)
					(thickness 0.15)
				)
				(justify right bottom mirror)
			)
		)
		(property "Datasheet" "https://industrial.panasonic.com/cdbs/www-data/pdf/RDA0000/AOA0000C301.pdf"
			(at 0 0 90)
			(layer "F.Fab")
			(hide yes)
			(effects
				(font
					(size 1.27 1.27)
					(thickness 0.15)
				)
			)
		)
		(property "MPN" "ERJ2GE0R00X"
			(at 0 0 90)
			(unlocked yes)
			(layer "B.Fab")
			(hide yes)
			(effects
				(font
					(size 1 1)
					(thickness 0.15)
				)
				(justify mirror)
			)
		)
		(property "Manufacturer" "Panasonic"
			(at 0 0 90)
			(unlocked yes)
			(layer "B.Fab")
			(hide yes)
			(effects
				(font
					(size 1 1)
					(thickness 0.15)
				)
				(justify mirror)
			)
		)
		(property "License" "Apache-2.0"
			(at 0 0 90)
			(unlocked yes)
			(layer "B.Fab")
			(hide yes)
			(effects
				(font
					(size 1 1)
					(thickness 0.15)
				)
				(justify mirror)
			)
		)
		(property "Author" "Antmicro"
			(at 0 0 90)
			(unlocked yes)
			(layer "B.Fab")
			(hide yes)
			(effects
				(font
					(size 1 1)
					(thickness 0.15)
				)
				(justify mirror)
			)
		)
		(property "Val" "0R"
			(at 0 0 90)
			(unlocked yes)
			(layer "B.Fab")
			(hide yes)
			(effects
				(font
					(size 1 1)
					(thickness 0.15)
				)
				(justify mirror)
			)
		)
		(property "Tolerance" "~"
			(at 0 0 90)
			(unlocked yes)
			(layer "B.Fab")
			(hide yes)
			(effects
				(font
					(size 1 1)
					(thickness 0.15)
				)
				(justify mirror)
			)
		)
		(property "Current" "1A"
			(at 0 0 90)
			(unlocked yes)
			(layer "B.Fab")
			(hide yes)
			(effects
				(font
					(size 1 1)
					(thickness 0.15)
				)
				(justify mirror)
			)
		)
		(sheetname "/Supply/DC-DC IO/")
		(sheetfile "dc-dc-io.kicad_sch")
		(attr smd)
		(fp_rect
			(start -0.925 0.47)
			(end 0.925 -0.47)
			(stroke
				(width 0.05)
				(type default)
			)
			(fill no)
			(layer "B.CrtYd")
		)
		(fp_rect
			(start -0.5 0.25)
			(end 0.5 -0.25)
			(stroke
				(width 0.15)
				(type solid)
			)
			(fill no)
			(layer "B.Fab")
		)
		(fp_text user "${REFERENCE}"
			(at -0.95 -3.168 270)
			(layer "B.Fab")
			(effects
				(font
					(size 0.7 0.7)
					(thickness 0.15)
				)
				(justify left bottom mirror)
			)
		)
		(fp_text user "License: Apache-2.0"
			(at -0.95 -5.169 270)
			(layer "B.Fab")
			(effects
				(font
					(size 0.7 0.7)
					(thickness 0.15)
				)
				(justify left bottom mirror)
			)
		)
		(fp_text user "Author: Antmicro"
			(at -0.95 -4.169 270)
			(layer "B.Fab")
			(effects
				(font
					(size 0.7 0.7)
					(thickness 0.15)
				)
				(justify left bottom mirror)
			)
		)
		(pad "1" smd roundrect
			(at -0.48 0 90)
			(size 0.59 0.64)
			(layers "B.Cu" "B.Mask" "B.Paste")
			(roundrect_rratio 0.25)
			(net 733 "Net-(U28-IN3+)")
			(pintype "passive")
		)
		(pad "2" smd roundrect
			(at 0.48 0 90)
			(size 0.59 0.64)
			(layers "B.Cu" "B.Mask" "B.Paste")
			(roundrect_rratio 0.25)
			(net 695 "/Supply/DC-DC IO/VDDQ_SEN_+")
			(pintype "passive")
		)
	)
	(footprint "antmicro-footprints:C_0402_1005Metric"
		(layer "B.Cu")
		(at 167.6 153 90)
		(descr "Capacitor SMD 0402")
		(tags "capacitor SMD 0402")
		(property "Reference" "C4"
			(at 1.1 0.4 90)
			(layer "B.SilkS")
			(effects
				(font
					(size 0.7 0.7)
					(thickness 0.15)
				)
				(justify right bottom mirror)
			)
		)
		(property "Value" "C_100n_0402"
			(at -1.022927 -2.155213 90)
			(layer "B.Fab")
			(effects
				(font
					(size 0.7 0.7)
					(thickness 0.15)
				)
				(justify right bottom mirror)
			)
		)
		(property "Datasheet" "https://www.murata.com/products/productdetail?partno=GRM155R61H104KE14%23"
			(at 0 0 90)
			(layer "F.Fab")
			(hide yes)
			(effects
				(font
					(size 1.27 1.27)
					(thickness 0.15)
				)
			)
		)
		(property "Manufacturer" "Murata"
			(at 0 0 90)
			(unlocked yes)
			(layer "B.Fab")
			(hide yes)
			(effects
				(font
					(size 1 1)
					(thickness 0.15)
				)
				(justify mirror)
			)
		)
		(property "MPN" "GRM155R61H104KE14D"
			(at 0 0 90)
			(unlocked yes)
			(layer "B.Fab")
			(hide yes)
			(effects
				(font
					(size 1 1)
					(thickness 0.15)
				)
				(justify mirror)
			)
		)
		(property "Val" "100n"
			(at 0 0 90)
			(unlocked yes)
			(layer "B.Fab")
			(hide yes)
			(effects
				(font
					(size 1 1)
					(thickness 0.15)
				)
				(justify mirror)
			)
		)
		(property "License" "Apache-2.0"
			(at 0 0 90)
			(unlocked yes)
			(layer "B.Fab")
			(hide yes)
			(effects
				(font
					(size 1 1)
					(thickness 0.15)
				)
				(justify mirror)
			)
		)
		(property "Author" "Antmicro"
			(at 0 0 90)
			(unlocked yes)
			(layer "B.Fab")
			(hide yes)
			(effects
				(font
					(size 1 1)
					(thickness 0.15)
				)
				(justify mirror)
			)
		)
		(property "Voltage" "50V"
			(at 0 0 90)
			(unlocked yes)
			(layer "B.Fab")
			(hide yes)
			(effects
				(font
					(size 1 1)
					(thickness 0.15)
				)
				(justify mirror)
			)
		)
		(property "Dielectric" "X5R"
			(at 0 0 90)
			(unlocked yes)
			(layer "B.Fab")
			(hide yes)
			(effects
				(font
					(size 1 1)
					(thickness 0.15)
				)
				(justify mirror)
			)
		)
		(sheetname "/HyperRAM + QSPI Flash/")
		(sheetfile "hyperram-flash.kicad_sch")
		(attr smd)
		(fp_rect
			(start -0.925 0.47)
			(end 0.925 -0.47)
			(stroke
				(width 0.05)
				(type default)
			)
			(fill no)
			(layer "B.CrtYd")
		)
		(fp_line
			(start 0.504 -0.248)
			(end -0.494 -0.248)
			(stroke
				(width 0.15)
				(type solid)
			)
			(layer "B.Fab")
		)
		(fp_line
			(start -0.494 -0.248)
			(end -0.494 0.25)
			(stroke
				(width 0.15)
				(type solid)
			)
			(layer "B.Fab")
		)
		(fp_line
			(start 0.504 0.25)
			(end 0.504 -0.248)
			(stroke
				(width 0.15)
				(type solid)
			)
			(layer "B.Fab")
		)
		(fp_line
			(start -0.494 0.25)
			(end 0.504 0.25)
			(stroke
				(width 0.15)
				(type solid)
			)
			(layer "B.Fab")
		)
		(fp_text user "${REFERENCE}"
			(at -0.939 -4.599 270)
			(layer "B.Fab")
			(effects
				(font
					(size 0.7 0.7)
					(thickness 0.15)
				)
				(justify left bottom mirror)
			)
		)
		(fp_text user "License: Apache-2.0"
			(at -0.939 -5.799 270)
			(layer "B.Fab")
			(effects
				(font
					(size 0.7 0.7)
					(thickness 0.15)
				)
				(justify left bottom mirror)
			)
		)
		(fp_text user "Author: Antmicro"
			(at -0.939 -3.399 270)
			(layer "B.Fab")
			(effects
				(font
					(size 0.7 0.7)
					(thickness 0.15)
				)
				(justify left bottom mirror)
			)
		)
		(pad "1" smd roundrect
			(at -0.48 0 90)
			(size 0.59 0.64)
			(layers "B.Cu" "B.Mask" "B.Paste")
			(roundrect_rratio 0.25)
			(net 797 "+1V8")
			(pintype "passive")
		)
		(pad "2" smd roundrect
			(at 0.48 0 90)
			(size 0.59 0.64)
			(layers "B.Cu" "B.Mask" "B.Paste")
			(roundrect_rratio 0.25)
			(net 1 "GND")
			(pintype "passive")
		)
	)
	(footprint "antmicro-footprints:C_0402_1005Metric"
		(layer "B.Cu")
		(at 181.49 167.45 90)
		(descr "Capacitor SMD 0402")
		(tags "capacitor SMD 0402")
		(property "Reference" "C245"
			(at -4 -0.134 90)
			(layer "B.SilkS")
			(effects
				(font
					(size 0.7 0.7)
					(thickness 0.15)
				)
				(justify right bottom mirror)
			)
		)
		(property "Value" "C_100n_0402"
			(at -1.022927 -2.155213 90)
			(layer "B.Fab")
			(effects
				(font
					(size 0.7 0.7)
					(thickness 0.15)
				)
				(justify right bottom mirror)
			)
		)
		(property "Datasheet" "https://www.murata.com/products/productdetail?partno=GRM155R61H104KE14%23"
			(at 0 0 90)
			(layer "F.Fab")
			(hide yes)
			(effects
				(font
					(size 1.27 1.27)
					(thickness 0.15)
				)
			)
		)
		(property "Manufacturer" "Murata"
			(at 0 0 90)
			(unlocked yes)
			(layer "B.Fab")
			(hide yes)
			(effects
				(font
					(size 1 1)
					(thickness 0.15)
				)
				(justify mirror)
			)
		)
		(property "MPN" "GRM155R61H104KE14D"
			(at 0 0 90)
			(unlocked yes)
			(layer "B.Fab")
			(hide yes)
			(effects
				(font
					(size 1 1)
					(thickness 0.15)
				)
				(justify mirror)
			)
		)
		(property "Val" "100n"
			(at 0 0 90)
			(unlocked yes)
			(layer "B.Fab")
			(hide yes)
			(effects
				(font
					(size 1 1)
					(thickness 0.15)
				)
				(justify mirror)
			)
		)
		(property "License" "Apache-2.0"
			(at 0 0 90)
			(unlocked yes)
			(layer "B.Fab")
			(hide yes)
			(effects
				(font
					(size 1 1)
					(thickness 0.15)
				)
				(justify mirror)
			)
		)
		(property "Author" "Antmicro"
			(at 0 0 90)
			(unlocked yes)
			(layer "B.Fab")
			(hide yes)
			(effects
				(font
					(size 1 1)
					(thickness 0.15)
				)
				(justify mirror)
			)
		)
		(property "Voltage" "50V"
			(at 0 0 90)
			(unlocked yes)
			(layer "B.Fab")
			(hide yes)
			(effects
				(font
					(size 1 1)
					(thickness 0.15)
				)
				(justify mirror)
			)
		)
		(property "Dielectric" "X5R"
			(at 0 0 90)
			(unlocked yes)
			(layer "B.Fab")
			(hide yes)
			(effects
				(font
					(size 1 1)
					(thickness 0.15)
				)
				(justify mirror)
			)
		)
		(sheetname "/FPGA MGT Interface/")
		(sheetfile "fpga-mgt.kicad_sch")
		(attr smd)
		(fp_rect
			(start -0.925 0.47)
			(end 0.925 -0.47)
			(stroke
				(width 0.05)
				(type default)
			)
			(fill no)
			(layer "B.CrtYd")
		)
		(fp_line
			(start 0.504 -0.248)
			(end -0.494 -0.248)
			(stroke
				(width 0.15)
				(type solid)
			)
			(layer "B.Fab")
		)
		(fp_line
			(start -0.494 -0.248)
			(end -0.494 0.25)
			(stroke
				(width 0.15)
				(type solid)
			)
			(layer "B.Fab")
		)
		(fp_line
			(start 0.504 0.25)
			(end 0.504 -0.248)
			(stroke
				(width 0.15)
				(type solid)
			)
			(layer "B.Fab")
		)
		(fp_line
			(start -0.494 0.25)
			(end 0.504 0.25)
			(stroke
				(width 0.15)
				(type solid)
			)
			(layer "B.Fab")
		)
		(fp_text user "${REFERENCE}"
			(at -0.939 -4.599 270)
			(layer "B.Fab")
			(effects
				(font
					(size 0.7 0.7)
					(thickness 0.15)
				)
				(justify left bottom mirror)
			)
		)
		(fp_text user "License: Apache-2.0"
			(at -0.939 -5.799 270)
			(layer "B.Fab")
			(effects
				(font
					(size 0.7 0.7)
					(thickness 0.15)
				)
				(justify left bottom mirror)
			)
		)
		(fp_text user "Author: Antmicro"
			(at -0.939 -3.399 270)
			(layer "B.Fab")
			(effects
				(font
					(size 0.7 0.7)
					(thickness 0.15)
				)
				(justify left bottom mirror)
			)
		)
		(pad "1" smd roundrect
			(at -0.48 0 90)
			(size 0.59 0.64)
			(layers "B.Cu" "B.Mask" "B.Paste")
			(roundrect_rratio 0.25)
			(net 383 "/FPGA MGT Interface/HDMI_OUT.CLK_N")
			(pintype "passive")
		)
		(pad "2" smd roundrect
			(at 0.48 0 90)
			(size 0.59 0.64)
			(layers "B.Cu" "B.Mask" "B.Paste")
			(roundrect_rratio 0.25)
			(net 384 "/FPGA MGT Interface/HDMI_FPGA.TX_CLK_N")
			(pintype "passive")
		)
	)
	(footprint "antmicro-footprints:C_0402_1005Metric"
		(layer "B.Cu")
		(at 122.95 151.61)
		(descr "Capacitor SMD 0402")
		(tags "capacitor SMD 0402")
		(property "Reference" "C307"
			(at 2.44 1.504 0)
			(layer "B.SilkS")
			(effects
				(font
					(size 0.7 0.7)
					(thickness 0.15)
				)
				(justify right bottom mirror)
			)
		)
		(property "Value" "C_100n_0402"
			(at -1.022927 -2.155213 0)
			(layer "B.Fab")
			(effects
				(font
					(size 0.7 0.7)
					(thickness 0.15)
				)
				(justify right bottom mirror)
			)
		)
		(property "Datasheet" "https://www.murata.com/products/productdetail?partno=GRM155R61H104KE14%23"
			(at 0 0 0)
			(layer "F.Fab")
			(hide yes)
			(effects
				(font
					(size 1.27 1.27)
					(thickness 0.15)
				)
			)
		)
		(property "Manufacturer" "Murata"
			(at 0 0 0)
			(unlocked yes)
			(layer "B.Fab")
			(hide yes)
			(effects
				(font
					(size 1 1)
					(thickness 0.15)
				)
				(justify mirror)
			)
		)
		(property "MPN" "GRM155R61H104KE14D"
			(at 0 0 0)
			(unlocked yes)
			(layer "B.Fab")
			(hide yes)
			(effects
				(font
					(size 1 1)
					(thickness 0.15)
				)
				(justify mirror)
			)
		)
		(property "Val" "100n"
			(at 0 0 0)
			(unlocked yes)
			(layer "B.Fab")
			(hide yes)
			(effects
				(font
					(size 1 1)
					(thickness 0.15)
				)
				(justify mirror)
			)
		)
		(property "License" "Apache-2.0"
			(at 0 0 0)
			(unlocked yes)
			(layer "B.Fab")
			(hide yes)
			(effects
				(font
					(size 1 1)
					(thickness 0.15)
				)
				(justify mirror)
			)
		)
		(property "Author" "Antmicro"
			(at 0 0 0)
			(unlocked yes)
			(layer "B.Fab")
			(hide yes)
			(effects
				(font
					(size 1 1)
					(thickness 0.15)
				)
				(justify mirror)
			)
		)
		(property "Voltage" "50V"
			(at 0 0 0)
			(unlocked yes)
			(layer "B.Fab")
			(hide yes)
			(effects
				(font
					(size 1 1)
					(thickness 0.15)
				)
				(justify mirror)
			)
		)
		(property "Dielectric" "X5R"
			(at 0 0 0)
			(unlocked yes)
			(layer "B.Fab")
			(hide yes)
			(effects
				(font
					(size 1 1)
					(thickness 0.15)
				)
				(justify mirror)
			)
		)
		(sheetname "/FPGA MGT Interface/")
		(sheetfile "fpga-mgt.kicad_sch")
		(attr smd)
		(fp_rect
			(start -0.925 0.47)
			(end 0.925 -0.47)
			(stroke
				(width 0.05)
				(type default)
			)
			(fill no)
			(layer "B.CrtYd")
		)
		(fp_line
			(start -0.494 -0.248)
			(end -0.494 0.25)
			(stroke
				(width 0.15)
				(type solid)
			)
			(layer "B.Fab")
		)
		(fp_line
			(start -0.494 0.25)
			(end 0.504 0.25)
			(stroke
				(width 0.15)
				(type solid)
			)
			(layer "B.Fab")
		)
		(fp_line
			(start 0.504 -0.248)
			(end -0.494 -0.248)
			(stroke
				(width 0.15)
				(type solid)
			)
			(layer "B.Fab")
		)
		(fp_line
			(start 0.504 0.25)
			(end 0.504 -0.248)
			(stroke
				(width 0.15)
				(type solid)
			)
			(layer "B.Fab")
		)
		(fp_text user "License: Apache-2.0"
			(at -0.939 -5.799 180)
			(layer "B.Fab")
			(effects
				(font
					(size 0.7 0.7)
					(thickness 0.15)
				)
				(justify left bottom mirror)
			)
		)
		(fp_text user "${REFERENCE}"
			(at -0.939 -4.599 180)
			(layer "B.Fab")
			(effects
				(font
					(size 0.7 0.7)
					(thickness 0.15)
				)
				(justify left bottom mirror)
			)
		)
		(fp_text user "Author: Antmicro"
			(at -0.939 -3.399 180)
			(layer "B.Fab")
			(effects
				(font
					(size 0.7 0.7)
					(thickness 0.15)
				)
				(justify left bottom mirror)
			)
		)
		(pad "1" smd roundrect
			(at -0.48 0)
			(size 0.59 0.64)
			(layers "B.Cu" "B.Mask" "B.Paste")
			(roundrect_rratio 0.25)
			(net 380 "/FPGA MGT Interface/HDMI_IN.D0_P")
			(pintype "passive")
		)
		(pad "2" smd roundrect
			(at 0.48 0)
			(size 0.59 0.64)
			(layers "B.Cu" "B.Mask" "B.Paste")
			(roundrect_rratio 0.25)
			(net 653 "/FPGA MGT Interface/HDMI_FPGA.RX0_P")
			(pintype "passive")
		)
	)
	(footprint "antmicro-footprints:C_0402_1005Metric"
		(layer "B.Cu")
		(at 255.724499 132.214 90)
		(descr "Capacitor SMD 0402")
		(tags "capacitor SMD 0402")
		(property "Reference" "C195"
			(at 1.414 0.375501 90)
			(layer "B.SilkS")
			(effects
				(font
					(size 0.7 0.7)
					(thickness 0.15)
				)
				(justify right bottom mirror)
			)
		)
		(property "Value" "C_100n_0402"
			(at -1.022927 -2.155213 90)
			(layer "B.Fab")
			(effects
				(font
					(size 0.7 0.7)
					(thickness 0.15)
				)
				(justify right bottom mirror)
			)
		)
		(property "Datasheet" "https://www.murata.com/products/productdetail?partno=GRM155R61H104KE14%23"
			(at 0 0 90)
			(layer "F.Fab")
			(hide yes)
			(effects
				(font
					(size 1.27 1.27)
					(thickness 0.15)
				)
			)
		)
		(property "Manufacturer" "Murata"
			(at 0 0 90)
			(unlocked yes)
			(layer "B.Fab")
			(hide yes)
			(effects
				(font
					(size 1 1)
					(thickness 0.15)
				)
				(justify mirror)
			)
		)
		(property "MPN" "GRM155R61H104KE14D"
			(at 0 0 90)
			(unlocked yes)
			(layer "B.Fab")
			(hide yes)
			(effects
				(font
					(size 1 1)
					(thickness 0.15)
				)
				(justify mirror)
			)
		)
		(property "Val" "100n"
			(at 0 0 90)
			(unlocked yes)
			(layer "B.Fab")
			(hide yes)
			(effects
				(font
					(size 1 1)
					(thickness 0.15)
				)
				(justify mirror)
			)
		)
		(property "License" "Apache-2.0"
			(at 0 0 90)
			(unlocked yes)
			(layer "B.Fab")
			(hide yes)
			(effects
				(font
					(size 1 1)
					(thickness 0.15)
				)
				(justify mirror)
			)
		)
		(property "Author" "Antmicro"
			(at 0 0 90)
			(unlocked yes)
			(layer "B.Fab")
			(hide yes)
			(effects
				(font
					(size 1 1)
					(thickness 0.15)
				)
				(justify mirror)
			)
		)
		(property "Voltage" "50V"
			(at 0 0 90)
			(unlocked yes)
			(layer "B.Fab")
			(hide yes)
			(effects
				(font
					(size 1 1)
					(thickness 0.15)
				)
				(justify mirror)
			)
		)
		(property "Dielectric" "X5R"
			(at 0 0 90)
			(unlocked yes)
			(layer "B.Fab")
			(hide yes)
			(effects
				(font
					(size 1 1)
					(thickness 0.15)
				)
				(justify mirror)
			)
		)
		(sheetname "/Supply/")
		(sheetfile "supply.kicad_sch")
		(attr smd)
		(fp_rect
			(start -0.925 0.47)
			(end 0.925 -0.47)
			(stroke
				(width 0.05)
				(type default)
			)
			(fill no)
			(layer "B.CrtYd")
		)
		(fp_line
			(start 0.504 -0.248)
			(end -0.494 -0.248)
			(stroke
				(width 0.15)
				(type solid)
			)
			(layer "B.Fab")
		)
		(fp_line
			(start -0.494 -0.248)
			(end -0.494 0.25)
			(stroke
				(width 0.15)
				(type solid)
			)
			(layer "B.Fab")
		)
		(fp_line
			(start 0.504 0.25)
			(end 0.504 -0.248)
			(stroke
				(width 0.15)
				(type solid)
			)
			(layer "B.Fab")
		)
		(fp_line
			(start -0.494 0.25)
			(end 0.504 0.25)
			(stroke
				(width 0.15)
				(type solid)
			)
			(layer "B.Fab")
		)
		(fp_text user "Author: Antmicro"
			(at -0.939 -3.399 270)
			(layer "B.Fab")
			(effects
				(font
					(size 0.7 0.7)
					(thickness 0.15)
				)
				(justify left bottom mirror)
			)
		)
		(fp_text user "${REFERENCE}"
			(at -0.939 -4.599 270)
			(layer "B.Fab")
			(effects
				(font
					(size 0.7 0.7)
					(thickness 0.15)
				)
				(justify left bottom mirror)
			)
		)
		(fp_text user "License: Apache-2.0"
			(at -0.939 -5.799 270)
			(layer "B.Fab")
			(effects
				(font
					(size 0.7 0.7)
					(thickness 0.15)
				)
				(justify left bottom mirror)
			)
		)
		(pad "1" smd roundrect
			(at -0.48 0 90)
			(size 0.59 0.64)
			(layers "B.Cu" "B.Mask" "B.Paste")
			(roundrect_rratio 0.25)
			(net 1 "GND")
			(pintype "passive")
		)
		(pad "2" smd roundrect
			(at 0.48 0 90)
			(size 0.59 0.64)
			(layers "B.Cu" "B.Mask" "B.Paste")
			(roundrect_rratio 0.25)
			(net 38 "+3V3_AON")
			(pintype "passive")
		)
	)
	(footprint "antmicro-footprints:C_0402_1005Metric_EIA"
		(layer "B.Cu")
		(at 185 158.5 90)
		(descr "Capacitor SMD 0402 (1005 Metric), square (rectangular) end terminal, IPC_7351 nominal, (Body size source: IPC-SM-782 page 76, https://www.pcb-3d.com/wordpress/wp-content/uploads/ipc-sm-782a_amendment_1_and_2.pdf)")
		(tags "capacitor 0402")
		(property "Reference" "C52"
			(at 9.8 -30.625 90)
			(layer "B.SilkS")
			(effects
				(font
					(size 0.7 0.7)
					(thickness 0.15)
				)
				(justify right bottom mirror)
			)
		)
		(property "Value" "C_1u_25V_0402"
			(at 0 -1.169 90)
			(layer "B.Fab")
			(effects
				(font
					(size 0.7 0.7)
					(thickness 0.15)
				)
				(justify right bottom mirror)
			)
		)
		(property "Datasheet" "https://www.murata.com/products/productdetail?partno=GRM155R61E105KE11%23"
			(at 0 0 90)
			(layer "F.Fab")
			(hide yes)
			(effects
				(font
					(size 1.27 1.27)
					(thickness 0.15)
				)
			)
		)
		(property "MPN" "GRM155R61E105KE11J"
			(at 0 0 90)
			(unlocked yes)
			(layer "B.Fab")
			(hide yes)
			(effects
				(font
					(size 1 1)
					(thickness 0.15)
				)
				(justify mirror)
			)
		)
		(property "Manufacturer" "Murata"
			(at 0 0 90)
			(unlocked yes)
			(layer "B.Fab")
			(hide yes)
			(effects
				(font
					(size 1 1)
					(thickness 0.15)
				)
				(justify mirror)
			)
		)
		(property "License" "Apache-2.0"
			(at 0 0 90)
			(unlocked yes)
			(layer "B.Fab")
			(hide yes)
			(effects
				(font
					(size 1 1)
					(thickness 0.15)
				)
				(justify mirror)
			)
		)
		(property "Author" "Antmicro"
			(at 0 0 90)
			(unlocked yes)
			(layer "B.Fab")
			(hide yes)
			(effects
				(font
					(size 1 1)
					(thickness 0.15)
				)
				(justify mirror)
			)
		)
		(property "Val" "1u"
			(at 0 0 90)
			(unlocked yes)
			(layer "B.Fab")
			(hide yes)
			(effects
				(font
					(size 1 1)
					(thickness 0.15)
				)
				(justify mirror)
			)
		)
		(property "Voltage" "25V"
			(at 0 0 90)
			(unlocked yes)
			(layer "B.Fab")
			(hide yes)
			(effects
				(font
					(size 1 1)
					(thickness 0.15)
				)
				(justify mirror)
			)
		)
		(property "Dielectric" "X5R"
			(at 0 0 90)
			(unlocked yes)
			(layer "B.Fab")
			(hide yes)
			(effects
				(font
					(size 1 1)
					(thickness 0.15)
				)
				(justify mirror)
			)
		)
		(sheetname "/FPGA power/")
		(sheetfile "fpga-power.kicad_sch")
		(attr smd)
		(fp_rect
			(start -0.95 0.45)
			(end 0.95 -0.45)
			(stroke
				(width 0.05)
				(type default)
			)
			(fill no)
			(layer "B.CrtYd")
		)
		(fp_line
			(start 0.498 -0.248)
			(end -0.5 -0.248)
			(stroke
				(width 0.15)
				(type solid)
			)
			(layer "B.Fab")
		)
		(fp_line
			(start -0.5 -0.248)
			(end -0.5 0.25)
			(stroke
				(width 0.15)
				(type solid)
			)
			(layer "B.Fab")
		)
		(fp_line
			(start 0.498 0.25)
			(end 0.498 -0.248)
			(stroke
				(width 0.15)
				(type solid)
			)
			(layer "B.Fab")
		)
		(fp_line
			(start -0.5 0.25)
			(end 0.498 0.25)
			(stroke
				(width 0.15)
				(type solid)
			)
			(layer "B.Fab")
		)
		(fp_text user "License: Apache-2.0"
			(at -0.9656 -4.369 270)
			(layer "B.Fab")
			(effects
				(font
					(size 0.7 0.7)
					(thickness 0.15)
				)
				(justify left bottom mirror)
			)
		)
		(fp_text user "Author: Antmicro"
			(at -0.9656 -5.569 270)
			(layer "B.Fab")
			(effects
				(font
					(size 0.7 0.7)
					(thickness 0.15)
				)
				(justify left bottom mirror)
			)
		)
		(fp_text user "${REFERENCE}"
			(at -0.9656 -3.169 270)
			(layer "B.Fab")
			(effects
				(font
					(size 0.7 0.7)
					(thickness 0.15)
				)
				(justify left bottom mirror)
			)
		)
		(pad "1" smd roundrect
			(at -0.5 0)
			(size 0.6 0.6)
			(layers "B.Cu" "B.Mask" "B.Paste")
			(roundrect_rratio 0.25)
			(net 1 "GND")
			(pintype "passive")
		)
		(pad "2" smd roundrect
			(at 0.498 0 90)
			(size 0.6 0.6)
			(layers "B.Cu" "B.Mask" "B.Paste")
			(roundrect_rratio 0.25)
			(net 553 "+0V85")
			(pintype "passive")
		)
	)
	(footprint "antmicro-footprints:C_0805_2012Metric"
		(layer "B.Cu")
		(at 219.334999 185.799999)
		(descr "Capacitor SMD 0805")
		(tags "capacitor SMD 0805")
		(property "Reference" "C201"
			(at 2.115001 0.800001 0)
			(layer "B.SilkS")
			(effects
				(font
					(size 0.7 0.7)
					(thickness 0.15)
				)
				(justify right bottom mirror)
			)
		)
		(property "Value" "C_22u_25V_0805"
			(at -2.055717 -1.963152 0)
			(layer "B.Fab")
			(effects
				(font
					(size 0.7 0.7)
					(thickness 0.15)
				)
				(justify right bottom mirror)
			)
		)
		(property "Datasheet" "https://product.samsungsem.com/mlcc/CL21A226MAYNNN.do"
			(at 0 0 0)
			(layer "F.Fab")
			(hide yes)
			(effects
				(font
					(size 1.27 1.27)
					(thickness 0.15)
				)
			)
		)
		(property "MPN" "CL21A226MAYNNNE"
			(at 0 0 0)
			(unlocked yes)
			(layer "B.Fab")
			(hide yes)
			(effects
				(font
					(size 1 1)
					(thickness 0.15)
				)
				(justify mirror)
			)
		)
		(property "Manufacturer" "Samsung Electro-Mechanics"
			(at 0 0 0)
			(unlocked yes)
			(layer "B.Fab")
			(hide yes)
			(effects
				(font
					(size 1 1)
					(thickness 0.15)
				)
				(justify mirror)
			)
		)
		(property "License" "Apache-2.0"
			(at 0 0 0)
			(unlocked yes)
			(layer "B.Fab")
			(hide yes)
			(effects
				(font
					(size 1 1)
					(thickness 0.15)
				)
				(justify mirror)
			)
		)
		(property "Author" "Antmicro"
			(at 0 0 0)
			(unlocked yes)
			(layer "B.Fab")
			(hide yes)
			(effects
				(font
					(size 1 1)
					(thickness 0.15)
				)
				(justify mirror)
			)
		)
		(property "Val" "22u"
			(at 0 0 0)
			(unlocked yes)
			(layer "B.Fab")
			(hide yes)
			(effects
				(font
					(size 1 1)
					(thickness 0.15)
				)
				(justify mirror)
			)
		)
		(property "Voltage" "25V"
			(at 0 0 0)
			(unlocked yes)
			(layer "B.Fab")
			(hide yes)
			(effects
				(font
					(size 1 1)
					(thickness 0.15)
				)
				(justify mirror)
			)
		)
		(property "Dielectric" "X5R"
			(at 0 0 0)
			(unlocked yes)
			(layer "B.Fab")
			(hide yes)
			(effects
				(font
					(size 1 1)
					(thickness 0.15)
				)
				(justify mirror)
			)
		)
		(property "Public" "False"
			(at 0 0 0)
			(unlocked yes)
			(layer "B.Fab")
			(hide yes)
			(effects
				(font
					(size 1 1)
					(thickness 0.15)
				)
				(justify mirror)
			)
		)
		(sheetname "/Supply/DC-DC VCCINT/")
		(sheetfile "dc-dc-vccint.kicad_sch")
		(attr smd)
		(fp_line
			(start -0.3 -0.7)
			(end 0.3 -0.7)
			(stroke
				(width 0.15)
				(type solid)
			)
			(layer "B.SilkS")
		)
		(fp_line
			(start -0.3 0.7)
			(end 0.3 0.7)
			(stroke
				(width 0.15)
				(type solid)
			)
			(layer "B.SilkS")
		)
		(fp_rect
			(start 1.95 0.9)
			(end -1.95 -0.9)
			(stroke
				(width 0.05)
				(type default)
			)
			(fill no)
			(layer "B.CrtYd")
		)
		(fp_rect
			(start -0.95 0.675)
			(end 0.95 -0.675)
			(stroke
				(width 0.15)
				(type solid)
			)
			(fill no)
			(layer "B.Fab")
		)
		(fp_text user "Author: Antmicro"
			(at -1.9 -5.947 180)
			(layer "B.Fab")
			(effects
				(font
					(size 0.7 0.7)
					(thickness 0.15)
				)
				(justify left bottom mirror)
			)
		)
		(fp_text user "${REFERENCE}"
			(at -1.9 -3.947 180)
			(layer "B.Fab")
			(effects
				(font
					(size 0.7 0.7)
					(thickness 0.15)
				)
				(justify left bottom mirror)
			)
		)
		(fp_text user "License: Apache-2.0"
			(at -1.9 -4.947 180)
			(layer "B.Fab")
			(effects
				(font
					(size 0.7 0.7)
					(thickness 0.15)
				)
				(justify left bottom mirror)
			)
		)
		(pad "1" smd roundrect
			(at -1.1 0)
			(size 1.2 1.3)
			(layers "B.Cu" "B.Mask" "B.Paste")
			(roundrect_rratio 0.25)
			(net 1 "GND")
			(pintype "passive")
		)
		(pad "2" smd roundrect
			(at 1.1 0)
			(size 1.2 1.3)
			(layers "B.Cu" "B.Mask" "B.Paste")
			(roundrect_rratio 0.25)
			(net 35 "VDC")
			(pintype "passive")
		)
	)
	(footprint "antmicro-footprints:R_0402_1005Metric"
		(layer "B.Cu")
		(at 240.12 176.975)
		(descr "Resistor SMD 0402")
		(tags "resistor SMD 0402")
		(property "Reference" "R208"
			(at 1.655 0.4 0)
			(layer "B.SilkS")
			(effects
				(font
					(size 0.7 0.7)
					(thickness 0.15)
				)
				(justify right bottom mirror)
			)
		)
		(property "Value" "R_0R_0402"
			(at -1.011843 -1.772047 0)
			(layer "B.Fab")
			(effects
				(font
					(size 0.7 0.7)
					(thickness 0.15)
				)
				(justify right bottom mirror)
			)
		)
		(property "Datasheet" "https://industrial.panasonic.com/cdbs/www-data/pdf/RDA0000/AOA0000C301.pdf"
			(at 0 0 0)
			(layer "F.Fab")
			(hide yes)
			(effects
				(font
					(size 1.27 1.27)
					(thickness 0.15)
				)
			)
		)
		(property "MPN" "ERJ2GE0R00X"
			(at 0 0 0)
			(unlocked yes)
			(layer "B.Fab")
			(hide yes)
			(effects
				(font
					(size 1 1)
					(thickness 0.15)
				)
				(justify mirror)
			)
		)
		(property "Manufacturer" "Panasonic"
			(at 0 0 0)
			(unlocked yes)
			(layer "B.Fab")
			(hide yes)
			(effects
				(font
					(size 1 1)
					(thickness 0.15)
				)
				(justify mirror)
			)
		)
		(property "License" "Apache-2.0"
			(at 0 0 0)
			(unlocked yes)
			(layer "B.Fab")
			(hide yes)
			(effects
				(font
					(size 1 1)
					(thickness 0.15)
				)
				(justify mirror)
			)
		)
		(property "Author" "Antmicro"
			(at 0 0 0)
			(unlocked yes)
			(layer "B.Fab")
			(hide yes)
			(effects
				(font
					(size 1 1)
					(thickness 0.15)
				)
				(justify mirror)
			)
		)
		(property "Val" "0R"
			(at 0 0 0)
			(unlocked yes)
			(layer "B.Fab")
			(hide yes)
			(effects
				(font
					(size 1 1)
					(thickness 0.15)
				)
				(justify mirror)
			)
		)
		(property "Tolerance" "~"
			(at 0 0 0)
			(unlocked yes)
			(layer "B.Fab")
			(hide yes)
			(effects
				(font
					(size 1 1)
					(thickness 0.15)
				)
				(justify mirror)
			)
		)
		(property "Current" "1A"
			(at 0 0 0)
			(unlocked yes)
			(layer "B.Fab")
			(hide yes)
			(effects
				(font
					(size 1 1)
					(thickness 0.15)
				)
				(justify mirror)
			)
		)
		(sheetname "/Supply/DC-DC AUX, MGT/")
		(sheetfile "dc-dc-aux-mgt.kicad_sch")
		(attr smd exclude_from_bom dnp)
		(fp_rect
			(start -0.925 0.47)
			(end 0.925 -0.47)
			(stroke
				(width 0.05)
				(type default)
			)
			(fill no)
			(layer "B.CrtYd")
		)
		(fp_rect
			(start -0.5 0.25)
			(end 0.5 -0.25)
			(stroke
				(width 0.15)
				(type solid)
			)
			(fill no)
			(layer "B.Fab")
		)
		(fp_text user "Author: Antmicro"
			(at -0.95 -4.169 180)
			(layer "B.Fab")
			(effects
				(font
					(size 0.7 0.7)
					(thickness 0.15)
				)
				(justify left bottom mirror)
			)
		)
		(fp_text user "${REFERENCE}"
			(at -0.95 -3.168 180)
			(layer "B.Fab")
			(effects
				(font
					(size 0.7 0.7)
					(thickness 0.15)
				)
				(justify left bottom mirror)
			)
		)
		(fp_text user "License: Apache-2.0"
			(at -0.95 -5.169 180)
			(layer "B.Fab")
			(effects
				(font
					(size 0.7 0.7)
					(thickness 0.15)
				)
				(justify left bottom mirror)
			)
		)
		(pad "1" smd roundrect
			(at -0.48 0)
			(size 0.59 0.64)
			(layers "B.Cu" "B.Mask" "B.Paste")
			(roundrect_rratio 0.25)
			(net 1 "GND")
			(pintype "passive")
		)
		(pad "2" smd roundrect
			(at 0.48 0)
			(size 0.59 0.64)
			(layers "B.Cu" "B.Mask" "B.Paste")
			(roundrect_rratio 0.25)
			(net 729 "Net-(U3-ADDRSEL)")
			(pintype "passive")
		)
	)
	(footprint "antmicro-footprints:C_0402_1005Metric_EIA"
		(layer "B.Cu")
		(at 187 146.5 -90)
		(descr "Capacitor SMD 0402 (1005 Metric), square (rectangular) end terminal, IPC_7351 nominal, (Body size source: IPC-SM-782 page 76, https://www.pcb-3d.com/wordpress/wp-content/uploads/ipc-sm-782a_amendment_1_and_2.pdf)")
		(tags "capacitor 0402")
		(property "Reference" "C77"
			(at -12.025 30.625 90)
			(layer "B.SilkS")
			(effects
				(font
					(size 0.7 0.7)
					(thickness 0.15)
				)
				(justify left bottom mirror)
			)
		)
		(property "Value" "C_1u_25V_0402"
			(at 0 -1.169 90)
			(layer "B.Fab")
			(effects
				(font
					(size 0.7 0.7)
					(thickness 0.15)
				)
				(justify left bottom mirror)
			)
		)
		(property "Datasheet" "https://www.murata.com/products/productdetail?partno=GRM155R61E105KE11%23"
			(at 0 0 270)
			(layer "F.Fab")
			(hide yes)
			(effects
				(font
					(size 1.27 1.27)
					(thickness 0.15)
				)
			)
		)
		(property "MPN" "GRM155R61E105KE11J"
			(at 0 0 270)
			(unlocked yes)
			(layer "B.Fab")
			(hide yes)
			(effects
				(font
					(size 1 1)
					(thickness 0.15)
				)
				(justify mirror)
			)
		)
		(property "Manufacturer" "Murata"
			(at 0 0 270)
			(unlocked yes)
			(layer "B.Fab")
			(hide yes)
			(effects
				(font
					(size 1 1)
					(thickness 0.15)
				)
				(justify mirror)
			)
		)
		(property "License" "Apache-2.0"
			(at 0 0 270)
			(unlocked yes)
			(layer "B.Fab")
			(hide yes)
			(effects
				(font
					(size 1 1)
					(thickness 0.15)
				)
				(justify mirror)
			)
		)
		(property "Author" "Antmicro"
			(at 0 0 270)
			(unlocked yes)
			(layer "B.Fab")
			(hide yes)
			(effects
				(font
					(size 1 1)
					(thickness 0.15)
				)
				(justify mirror)
			)
		)
		(property "Val" "1u"
			(at 0 0 270)
			(unlocked yes)
			(layer "B.Fab")
			(hide yes)
			(effects
				(font
					(size 1 1)
					(thickness 0.15)
				)
				(justify mirror)
			)
		)
		(property "Voltage" "25V"
			(at 0 0 270)
			(unlocked yes)
			(layer "B.Fab")
			(hide yes)
			(effects
				(font
					(size 1 1)
					(thickness 0.15)
				)
				(justify mirror)
			)
		)
		(property "Dielectric" "X5R"
			(at 0 0 270)
			(unlocked yes)
			(layer "B.Fab")
			(hide yes)
			(effects
				(font
					(size 1 1)
					(thickness 0.15)
				)
				(justify mirror)
			)
		)
		(sheetname "/FPGA power/")
		(sheetfile "fpga-power.kicad_sch")
		(attr smd)
		(fp_rect
			(start -0.95 0.45)
			(end 0.95 -0.45)
			(stroke
				(width 0.05)
				(type default)
			)
			(fill no)
			(layer "B.CrtYd")
		)
		(fp_line
			(start -0.5 0.25)
			(end 0.498 0.25)
			(stroke
				(width 0.15)
				(type solid)
			)
			(layer "B.Fab")
		)
		(fp_line
			(start 0.498 0.25)
			(end 0.498 -0.248)
			(stroke
				(width 0.15)
				(type solid)
			)
			(layer "B.Fab")
		)
		(fp_line
			(start -0.5 -0.248)
			(end -0.5 0.25)
			(stroke
				(width 0.15)
				(type solid)
			)
			(layer "B.Fab")
		)
		(fp_line
			(start 0.498 -0.248)
			(end -0.5 -0.248)
			(stroke
				(width 0.15)
				(type solid)
			)
			(layer "B.Fab")
		)
		(fp_text user "License: Apache-2.0"
			(at -0.9656 -4.369 90)
			(layer "B.Fab")
			(effects
				(font
					(size 0.7 0.7)
					(thickness 0.15)
				)
				(justify left bottom mirror)
			)
		)
		(fp_text user "Author: Antmicro"
			(at -0.9656 -5.569 90)
			(layer "B.Fab")
			(effects
				(font
					(size 0.7 0.7)
					(thickness 0.15)
				)
				(justify left bottom mirror)
			)
		)
		(fp_text user "${REFERENCE}"
			(at -0.9656 -3.169 90)
			(layer "B.Fab")
			(effects
				(font
					(size 0.7 0.7)
					(thickness 0.15)
				)
				(justify left bottom mirror)
			)
		)
		(pad "1" smd roundrect
			(at -0.5 0 180)
			(size 0.6 0.6)
			(layers "B.Cu" "B.Mask" "B.Paste")
			(roundrect_rratio 0.25)
			(net 1 "GND")
			(pintype "passive")
		)
		(pad "2" smd roundrect
			(at 0.498 0 270)
			(size 0.6 0.6)
			(layers "B.Cu" "B.Mask" "B.Paste")
			(roundrect_rratio 0.25)
			(net 797 "+1V8")
			(pintype "passive")
		)
	)
	(footprint "antmicro-footprints:C_0402_1005Metric_EIA"
		(layer "B.Cu")
		(at 182 141.5 90)
		(descr "Capacitor SMD 0402 (1005 Metric), square (rectangular) end terminal, IPC_7351 nominal, (Body size source: IPC-SM-782 page 76, https://www.pcb-3d.com/wordpress/wp-content/uploads/ipc-sm-782a_amendment_1_and_2.pdf)")
		(tags "capacitor 0402")
		(property "Reference" "C24"
			(at -1.075 1.45 90)
			(layer "B.SilkS")
			(effects
				(font
					(size 0.7 0.7)
					(thickness 0.15)
				)
				(justify right bottom mirror)
			)
		)
		(property "Value" "C_100n_0402"
			(at 0 -1.169 90)
			(layer "B.Fab")
			(effects
				(font
					(size 0.7 0.7)
					(thickness 0.15)
				)
				(justify right bottom mirror)
			)
		)
		(property "Datasheet" "https://www.murata.com/products/productdetail?partno=GRM155R61H104KE14%23"
			(at 0 0 90)
			(layer "F.Fab")
			(hide yes)
			(effects
				(font
					(size 1.27 1.27)
					(thickness 0.15)
				)
			)
		)
		(property "MPN" "GRM155R61H104KE14D"
			(at 0 0 90)
			(unlocked yes)
			(layer "B.Fab")
			(hide yes)
			(effects
				(font
					(size 1 1)
					(thickness 0.15)
				)
				(justify mirror)
			)
		)
		(property "Manufacturer" "Murata"
			(at 0 0 90)
			(unlocked yes)
			(layer "B.Fab")
			(hide yes)
			(effects
				(font
					(size 1 1)
					(thickness 0.15)
				)
				(justify mirror)
			)
		)
		(property "License" "Apache-2.0"
			(at 0 0 90)
			(unlocked yes)
			(layer "B.Fab")
			(hide yes)
			(effects
				(font
					(size 1 1)
					(thickness 0.15)
				)
				(justify mirror)
			)
		)
		(property "Author" "Antmicro"
			(at 0 0 90)
			(unlocked yes)
			(layer "B.Fab")
			(hide yes)
			(effects
				(font
					(size 1 1)
					(thickness 0.15)
				)
				(justify mirror)
			)
		)
		(property "Val" "100n"
			(at 0 0 90)
			(unlocked yes)
			(layer "B.Fab")
			(hide yes)
			(effects
				(font
					(size 1 1)
					(thickness 0.15)
				)
				(justify mirror)
			)
		)
		(property "Voltage" "50V"
			(at 0 0 90)
			(unlocked yes)
			(layer "B.Fab")
			(hide yes)
			(effects
				(font
					(size 1 1)
					(thickness 0.15)
				)
				(justify mirror)
			)
		)
		(property "Dielectric" "X5R"
			(at 0 0 90)
			(unlocked yes)
			(layer "B.Fab")
			(hide yes)
			(effects
				(font
					(size 1 1)
					(thickness 0.15)
				)
				(justify mirror)
			)
		)
		(sheetname "/FPGA power/")
		(sheetfile "fpga-power.kicad_sch")
		(attr smd)
		(fp_rect
			(start -0.95 0.45)
			(end 0.95 -0.45)
			(stroke
				(width 0.05)
				(type default)
			)
			(fill no)
			(layer "B.CrtYd")
		)
		(fp_line
			(start 0.498 -0.248)
			(end -0.5 -0.248)
			(stroke
				(width 0.15)
				(type solid)
			)
			(layer "B.Fab")
		)
		(fp_line
			(start -0.5 -0.248)
			(end -0.5 0.25)
			(stroke
				(width 0.15)
				(type solid)
			)
			(layer "B.Fab")
		)
		(fp_line
			(start 0.498 0.25)
			(end 0.498 -0.248)
			(stroke
				(width 0.15)
				(type solid)
			)
			(layer "B.Fab")
		)
		(fp_line
			(start -0.5 0.25)
			(end 0.498 0.25)
			(stroke
				(width 0.15)
				(type solid)
			)
			(layer "B.Fab")
		)
		(fp_text user "License: Apache-2.0"
			(at -0.9656 -4.369 270)
			(layer "B.Fab")
			(effects
				(font
					(size 0.7 0.7)
					(thickness 0.15)
				)
				(justify left bottom mirror)
			)
		)
		(fp_text user "${REFERENCE}"
			(at -0.9656 -3.169 270)
			(layer "B.Fab")
			(effects
				(font
					(size 0.7 0.7)
					(thickness 0.15)
				)
				(justify left bottom mirror)
			)
		)
		(fp_text user "Author: Antmicro"
			(at -0.9656 -5.569 270)
			(layer "B.Fab")
			(effects
				(font
					(size 0.7 0.7)
					(thickness 0.15)
				)
				(justify left bottom mirror)
			)
		)
		(pad "1" smd roundrect
			(at -0.5 0)
			(size 0.6 0.6)
			(layers "B.Cu" "B.Mask" "B.Paste")
			(roundrect_rratio 0.25)
			(net 1 "GND")
			(pintype "passive")
		)
		(pad "2" smd roundrect
			(at 0.498 0 90)
			(size 0.6 0.6)
			(layers "B.Cu" "B.Mask" "B.Paste")
			(roundrect_rratio 0.25)
			(net 687 "VDDQ")
			(pintype "passive")
		)
	)
	(footprint "antmicro-footprints:C_0402_1005Metric_EIA"
		(layer "B.Cu")
		(at 195 162.500001 90)
		(descr "Capacitor SMD 0402 (1005 Metric), square (rectangular) end terminal, IPC_7351 nominal, (Body size source: IPC-SM-782 page 76, https://www.pcb-3d.com/wordpress/wp-content/uploads/ipc-sm-782a_amendment_1_and_2.pdf)")
		(tags "capacitor 0402")
		(property "Reference" "C105"
			(at -3.949999 0.25 90)
			(layer "B.SilkS")
			(effects
				(font
					(size 0.7 0.7)
					(thickness 0.15)
				)
				(justify right bottom mirror)
			)
		)
		(property "Value" "C_100n_0402"
			(at 0 -1.169 90)
			(layer "B.Fab")
			(effects
				(font
					(size 0.7 0.7)
					(thickness 0.15)
				)
				(justify right bottom mirror)
			)
		)
		(property "Datasheet" "https://www.murata.com/products/productdetail?partno=GRM155R61H104KE14%23"
			(at 0 0 90)
			(layer "F.Fab")
			(hide yes)
			(effects
				(font
					(size 1.27 1.27)
					(thickness 0.15)
				)
			)
		)
		(property "MPN" "GRM155R61H104KE14D"
			(at 0 0 90)
			(unlocked yes)
			(layer "B.Fab")
			(hide yes)
			(effects
				(font
					(size 1 1)
					(thickness 0.15)
				)
				(justify mirror)
			)
		)
		(property "Manufacturer" "Murata"
			(at 0 0 90)
			(unlocked yes)
			(layer "B.Fab")
			(hide yes)
			(effects
				(font
					(size 1 1)
					(thickness 0.15)
				)
				(justify mirror)
			)
		)
		(property "License" "Apache-2.0"
			(at 0 0 90)
			(unlocked yes)
			(layer "B.Fab")
			(hide yes)
			(effects
				(font
					(size 1 1)
					(thickness 0.15)
				)
				(justify mirror)
			)
		)
		(property "Author" "Antmicro"
			(at 0 0 90)
			(unlocked yes)
			(layer "B.Fab")
			(hide yes)
			(effects
				(font
					(size 1 1)
					(thickness 0.15)
				)
				(justify mirror)
			)
		)
		(property "Val" "100n"
			(at 0 0 90)
			(unlocked yes)
			(layer "B.Fab")
			(hide yes)
			(effects
				(font
					(size 1 1)
					(thickness 0.15)
				)
				(justify mirror)
			)
		)
		(property "Voltage" "50V"
			(at 0 0 90)
			(unlocked yes)
			(layer "B.Fab")
			(hide yes)
			(effects
				(font
					(size 1 1)
					(thickness 0.15)
				)
				(justify mirror)
			)
		)
		(property "Dielectric" "X5R"
			(at 0 0 90)
			(unlocked yes)
			(layer "B.Fab")
			(hide yes)
			(effects
				(font
					(size 1 1)
					(thickness 0.15)
				)
				(justify mirror)
			)
		)
		(sheetname "/FPGA power/")
		(sheetfile "fpga-power.kicad_sch")
		(attr smd)
		(fp_rect
			(start -0.95 0.45)
			(end 0.95 -0.45)
			(stroke
				(width 0.05)
				(type default)
			)
			(fill no)
			(layer "B.CrtYd")
		)
		(fp_line
			(start 0.498 -0.248)
			(end -0.5 -0.248)
			(stroke
				(width 0.15)
				(type solid)
			)
			(layer "B.Fab")
		)
		(fp_line
			(start -0.5 -0.248)
			(end -0.5 0.25)
			(stroke
				(width 0.15)
				(type solid)
			)
			(layer "B.Fab")
		)
		(fp_line
			(start 0.498 0.25)
			(end 0.498 -0.248)
			(stroke
				(width 0.15)
				(type solid)
			)
			(layer "B.Fab")
		)
		(fp_line
			(start -0.5 0.25)
			(end 0.498 0.25)
			(stroke
				(width 0.15)
				(type solid)
			)
			(layer "B.Fab")
		)
		(fp_text user "License: Apache-2.0"
			(at -0.9656 -4.369 270)
			(layer "B.Fab")
			(effects
				(font
					(size 0.7 0.7)
					(thickness 0.15)
				)
				(justify left bottom mirror)
			)
		)
		(fp_text user "Author: Antmicro"
			(at -0.9656 -5.569 270)
			(layer "B.Fab")
			(effects
				(font
					(size 0.7 0.7)
					(thickness 0.15)
				)
				(justify left bottom mirror)
			)
		)
		(fp_text user "${REFERENCE}"
			(at -0.9656 -3.169 270)
			(layer "B.Fab")
			(effects
				(font
					(size 0.7 0.7)
					(thickness 0.15)
				)
				(justify left bottom mirror)
			)
		)
		(pad "1" smd roundrect
			(at -0.5 0)
			(size 0.6 0.6)
			(layers "B.Cu" "B.Mask" "B.Paste")
			(roundrect_rratio 0.25)
			(net 1 "GND")
			(pintype "passive")
		)
		(pad "2" smd roundrect
			(at 0.498 0 90)
			(size 0.6 0.6)
			(layers "B.Cu" "B.Mask" "B.Paste")
			(roundrect_rratio 0.25)
			(net 172 "+1V2_MGTAVTT")
			(pintype "passive")
		)
	)
	(footprint "antmicro-footprints:C_0402_1005Metric_EIA"
		(layer "B.Cu")
		(at 196 140.5 -90)
		(descr "Capacitor SMD 0402 (1005 Metric), square (rectangular) end terminal, IPC_7351 nominal, (Body size source: IPC-SM-782 page 76, https://www.pcb-3d.com/wordpress/wp-content/uploads/ipc-sm-782a_amendment_1_and_2.pdf)")
		(tags "capacitor 0402")
		(property "Reference" "C74"
			(at -1.175 -1.475 90)
			(layer "B.SilkS")
			(effects
				(font
					(size 0.7 0.7)
					(thickness 0.15)
				)
				(justify left bottom mirror)
			)
		)
		(property "Value" "C_100n_0402"
			(at 0 -1.169 90)
			(layer "B.Fab")
			(effects
				(font
					(size 0.7 0.7)
					(thickness 0.15)
				)
				(justify left bottom mirror)
			)
		)
		(property "Datasheet" "https://www.murata.com/products/productdetail?partno=GRM155R61H104KE14%23"
			(at 0 0 270)
			(layer "F.Fab")
			(hide yes)
			(effects
				(font
					(size 1.27 1.27)
					(thickness 0.15)
				)
			)
		)
		(property "MPN" "GRM155R61H104KE14D"
			(at 0 0 270)
			(unlocked yes)
			(layer "B.Fab")
			(hide yes)
			(effects
				(font
					(size 1 1)
					(thickness 0.15)
				)
				(justify mirror)
			)
		)
		(property "Manufacturer" "Murata"
			(at 0 0 270)
			(unlocked yes)
			(layer "B.Fab")
			(hide yes)
			(effects
				(font
					(size 1 1)
					(thickness 0.15)
				)
				(justify mirror)
			)
		)
		(property "License" "Apache-2.0"
			(at 0 0 270)
			(unlocked yes)
			(layer "B.Fab")
			(hide yes)
			(effects
				(font
					(size 1 1)
					(thickness 0.15)
				)
				(justify mirror)
			)
		)
		(property "Author" "Antmicro"
			(at 0 0 270)
			(unlocked yes)
			(layer "B.Fab")
			(hide yes)
			(effects
				(font
					(size 1 1)
					(thickness 0.15)
				)
				(justify mirror)
			)
		)
		(property "Val" "100n"
			(at 0 0 270)
			(unlocked yes)
			(layer "B.Fab")
			(hide yes)
			(effects
				(font
					(size 1 1)
					(thickness 0.15)
				)
				(justify mirror)
			)
		)
		(property "Voltage" "50V"
			(at 0 0 270)
			(unlocked yes)
			(layer "B.Fab")
			(hide yes)
			(effects
				(font
					(size 1 1)
					(thickness 0.15)
				)
				(justify mirror)
			)
		)
		(property "Dielectric" "X5R"
			(at 0 0 270)
			(unlocked yes)
			(layer "B.Fab")
			(hide yes)
			(effects
				(font
					(size 1 1)
					(thickness 0.15)
				)
				(justify mirror)
			)
		)
		(sheetname "/FPGA power/")
		(sheetfile "fpga-power.kicad_sch")
		(attr smd)
		(fp_rect
			(start -0.95 0.45)
			(end 0.95 -0.45)
			(stroke
				(width 0.05)
				(type default)
			)
			(fill no)
			(layer "B.CrtYd")
		)
		(fp_line
			(start -0.5 0.25)
			(end 0.498 0.25)
			(stroke
				(width 0.15)
				(type solid)
			)
			(layer "B.Fab")
		)
		(fp_line
			(start 0.498 0.25)
			(end 0.498 -0.248)
			(stroke
				(width 0.15)
				(type solid)
			)
			(layer "B.Fab")
		)
		(fp_line
			(start -0.5 -0.248)
			(end -0.5 0.25)
			(stroke
				(width 0.15)
				(type solid)
			)
			(layer "B.Fab")
		)
		(fp_line
			(start 0.498 -0.248)
			(end -0.5 -0.248)
			(stroke
				(width 0.15)
				(type solid)
			)
			(layer "B.Fab")
		)
		(fp_text user "License: Apache-2.0"
			(at -0.9656 -4.369 90)
			(layer "B.Fab")
			(effects
				(font
					(size 0.7 0.7)
					(thickness 0.15)
				)
				(justify left bottom mirror)
			)
		)
		(fp_text user "Author: Antmicro"
			(at -0.9656 -5.569 90)
			(layer "B.Fab")
			(effects
				(font
					(size 0.7 0.7)
					(thickness 0.15)
				)
				(justify left bottom mirror)
			)
		)
		(fp_text user "${REFERENCE}"
			(at -0.9656 -3.169 90)
			(layer "B.Fab")
			(effects
				(font
					(size 0.7 0.7)
					(thickness 0.15)
				)
				(justify left bottom mirror)
			)
		)
		(pad "1" smd roundrect
			(at -0.5 0 180)
			(size 0.6 0.6)
			(layers "B.Cu" "B.Mask" "B.Paste")
			(roundrect_rratio 0.25)
			(net 1 "GND")
			(pintype "passive")
		)
		(pad "2" smd roundrect
			(at 0.498 0 270)
			(size 0.6 0.6)
			(layers "B.Cu" "B.Mask" "B.Paste")
			(roundrect_rratio 0.25)
			(net 687 "VDDQ")
			(pintype "passive")
		)
	)
	(footprint "antmicro-footprints:R_0402_1005Metric"
		(layer "B.Cu")
		(at 238.451999 164.2)
		(descr "Resistor SMD 0402")
		(tags "resistor SMD 0402")
		(property "Reference" "R137"
			(at 1.173001 0.475 0)
			(layer "B.SilkS")
			(effects
				(font
					(size 0.7 0.7)
					(thickness 0.15)
				)
				(justify right bottom mirror)
			)
		)
		(property "Value" "R_0R_0402"
			(at -1.011843 -1.772047 0)
			(layer "B.Fab")
			(effects
				(font
					(size 0.7 0.7)
					(thickness 0.15)
				)
				(justify right bottom mirror)
			)
		)
		(property "Datasheet" "https://industrial.panasonic.com/cdbs/www-data/pdf/RDA0000/AOA0000C301.pdf"
			(at 0 0 0)
			(layer "F.Fab")
			(hide yes)
			(effects
				(font
					(size 1.27 1.27)
					(thickness 0.15)
				)
			)
		)
		(property "MPN" "ERJ2GE0R00X"
			(at 0 0 0)
			(unlocked yes)
			(layer "B.Fab")
			(hide yes)
			(effects
				(font
					(size 1 1)
					(thickness 0.15)
				)
				(justify mirror)
			)
		)
		(property "Manufacturer" "Panasonic"
			(at 0 0 0)
			(unlocked yes)
			(layer "B.Fab")
			(hide yes)
			(effects
				(font
					(size 1 1)
					(thickness 0.15)
				)
				(justify mirror)
			)
		)
		(property "License" "Apache-2.0"
			(at 0 0 0)
			(unlocked yes)
			(layer "B.Fab")
			(hide yes)
			(effects
				(font
					(size 1 1)
					(thickness 0.15)
				)
				(justify mirror)
			)
		)
		(property "Author" "Antmicro"
			(at 0 0 0)
			(unlocked yes)
			(layer "B.Fab")
			(hide yes)
			(effects
				(font
					(size 1 1)
					(thickness 0.15)
				)
				(justify mirror)
			)
		)
		(property "Val" "0R"
			(at 0 0 0)
			(unlocked yes)
			(layer "B.Fab")
			(hide yes)
			(effects
				(font
					(size 1 1)
					(thickness 0.15)
				)
				(justify mirror)
			)
		)
		(property "Tolerance" "~"
			(at 0 0 0)
			(unlocked yes)
			(layer "B.Fab")
			(hide yes)
			(effects
				(font
					(size 1 1)
					(thickness 0.15)
				)
				(justify mirror)
			)
		)
		(property "Current" "1A"
			(at 0 0 0)
			(unlocked yes)
			(layer "B.Fab")
			(hide yes)
			(effects
				(font
					(size 1 1)
					(thickness 0.15)
				)
				(justify mirror)
			)
		)
		(sheetname "/Supply/")
		(sheetfile "supply.kicad_sch")
		(attr smd)
		(fp_rect
			(start -0.925 0.47)
			(end 0.925 -0.47)
			(stroke
				(width 0.05)
				(type default)
			)
			(fill no)
			(layer "B.CrtYd")
		)
		(fp_rect
			(start -0.5 0.25)
			(end 0.5 -0.25)
			(stroke
				(width 0.15)
				(type solid)
			)
			(fill no)
			(layer "B.Fab")
		)
		(fp_text user "${REFERENCE}"
			(at -0.95 -3.168 180)
			(layer "B.Fab")
			(effects
				(font
					(size 0.7 0.7)
					(thickness 0.15)
				)
				(justify left bottom mirror)
			)
		)
		(fp_text user "License: Apache-2.0"
			(at -0.95 -5.169 180)
			(layer "B.Fab")
			(effects
				(font
					(size 0.7 0.7)
					(thickness 0.15)
				)
				(justify left bottom mirror)
			)
		)
		(fp_text user "Author: Antmicro"
			(at -0.95 -4.169 180)
			(layer "B.Fab")
			(effects
				(font
					(size 0.7 0.7)
					(thickness 0.15)
				)
				(justify left bottom mirror)
			)
		)
		(pad "1" smd roundrect
			(at -0.48 0)
			(size 0.59 0.64)
			(layers "B.Cu" "B.Mask" "B.Paste")
			(roundrect_rratio 0.25)
			(net 183 "POWER")
			(pintype "passive")
		)
		(pad "2" smd roundrect
			(at 0.48 0)
			(size 0.59 0.64)
			(layers "B.Cu" "B.Mask" "B.Paste")
			(roundrect_rratio 0.25)
			(net 484 "PG2")
			(pintype "passive")
		)
	)
	(footprint "antmicro-footprints:C_0402_1005Metric_EIA"
		(layer "B.Cu")
		(at 185 148.5 -90)
		(descr "Capacitor SMD 0402 (1005 Metric), square (rectangular) end terminal, IPC_7351 nominal, (Body size source: IPC-SM-782 page 76, https://www.pcb-3d.com/wordpress/wp-content/uploads/ipc-sm-782a_amendment_1_and_2.pdf)")
		(tags "capacitor 0402")
		(property "Reference" "C35"
			(at -11.7 30.625 90)
			(layer "B.SilkS")
			(effects
				(font
					(size 0.7 0.7)
					(thickness 0.15)
				)
				(justify left bottom mirror)
			)
		)
		(property "Value" "C_1u_25V_0402"
			(at 0 -1.169 90)
			(layer "B.Fab")
			(effects
				(font
					(size 0.7 0.7)
					(thickness 0.15)
				)
				(justify left bottom mirror)
			)
		)
		(property "Datasheet" "https://www.murata.com/products/productdetail?partno=GRM155R61E105KE11%23"
			(at 0 0 270)
			(layer "F.Fab")
			(hide yes)
			(effects
				(font
					(size 1.27 1.27)
					(thickness 0.15)
				)
			)
		)
		(property "MPN" "GRM155R61E105KE11J"
			(at 0 0 270)
			(unlocked yes)
			(layer "B.Fab")
			(hide yes)
			(effects
				(font
					(size 1 1)
					(thickness 0.15)
				)
				(justify mirror)
			)
		)
		(property "Manufacturer" "Murata"
			(at 0 0 270)
			(unlocked yes)
			(layer "B.Fab")
			(hide yes)
			(effects
				(font
					(size 1 1)
					(thickness 0.15)
				)
				(justify mirror)
			)
		)
		(property "License" "Apache-2.0"
			(at 0 0 270)
			(unlocked yes)
			(layer "B.Fab")
			(hide yes)
			(effects
				(font
					(size 1 1)
					(thickness 0.15)
				)
				(justify mirror)
			)
		)
		(property "Author" "Antmicro"
			(at 0 0 270)
			(unlocked yes)
			(layer "B.Fab")
			(hide yes)
			(effects
				(font
					(size 1 1)
					(thickness 0.15)
				)
				(justify mirror)
			)
		)
		(property "Val" "1u"
			(at 0 0 270)
			(unlocked yes)
			(layer "B.Fab")
			(hide yes)
			(effects
				(font
					(size 1 1)
					(thickness 0.15)
				)
				(justify mirror)
			)
		)
		(property "Voltage" "25V"
			(at 0 0 270)
			(unlocked yes)
			(layer "B.Fab")
			(hide yes)
			(effects
				(font
					(size 1 1)
					(thickness 0.15)
				)
				(justify mirror)
			)
		)
		(property "Dielectric" "X5R"
			(at 0 0 270)
			(unlocked yes)
			(layer "B.Fab")
			(hide yes)
			(effects
				(font
					(size 1 1)
					(thickness 0.15)
				)
				(justify mirror)
			)
		)
		(sheetname "/FPGA power/")
		(sheetfile "fpga-power.kicad_sch")
		(attr smd)
		(fp_rect
			(start -0.95 0.45)
			(end 0.95 -0.45)
			(stroke
				(width 0.05)
				(type default)
			)
			(fill no)
			(layer "B.CrtYd")
		)
		(fp_line
			(start -0.5 0.25)
			(end 0.498 0.25)
			(stroke
				(width 0.15)
				(type solid)
			)
			(layer "B.Fab")
		)
		(fp_line
			(start 0.498 0.25)
			(end 0.498 -0.248)
			(stroke
				(width 0.15)
				(type solid)
			)
			(layer "B.Fab")
		)
		(fp_line
			(start -0.5 -0.248)
			(end -0.5 0.25)
			(stroke
				(width 0.15)
				(type solid)
			)
			(layer "B.Fab")
		)
		(fp_line
			(start 0.498 -0.248)
			(end -0.5 -0.248)
			(stroke
				(width 0.15)
				(type solid)
			)
			(layer "B.Fab")
		)
		(fp_text user "Author: Antmicro"
			(at -0.9656 -5.569 90)
			(layer "B.Fab")
			(effects
				(font
					(size 0.7 0.7)
					(thickness 0.15)
				)
				(justify left bottom mirror)
			)
		)
		(fp_text user "License: Apache-2.0"
			(at -0.9656 -4.369 90)
			(layer "B.Fab")
			(effects
				(font
					(size 0.7 0.7)
					(thickness 0.15)
				)
				(justify left bottom mirror)
			)
		)
		(fp_text user "${REFERENCE}"
			(at -0.9656 -3.169 90)
			(layer "B.Fab")
			(effects
				(font
					(size 0.7 0.7)
					(thickness 0.15)
				)
				(justify left bottom mirror)
			)
		)
		(pad "1" smd roundrect
			(at -0.5 0 180)
			(size 0.6 0.6)
			(layers "B.Cu" "B.Mask" "B.Paste")
			(roundrect_rratio 0.25)
			(net 1 "GND")
			(pintype "passive")
		)
		(pad "2" smd roundrect
			(at 0.498 0 270)
			(size 0.6 0.6)
			(layers "B.Cu" "B.Mask" "B.Paste")
			(roundrect_rratio 0.25)
			(net 553 "+0V85")
			(pintype "passive")
		)
	)
	(footprint "antmicro-footprints:C_0402_1005Metric_EIA"
		(layer "B.Cu")
		(at 190 158.5 90)
		(descr "Capacitor SMD 0402 (1005 Metric), square (rectangular) end terminal, IPC_7351 nominal, (Body size source: IPC-SM-782 page 76, https://www.pcb-3d.com/wordpress/wp-content/uploads/ipc-sm-782a_amendment_1_and_2.pdf)")
		(tags "capacitor 0402")
		(property "Reference" "C61"
			(at 9.525 -30.65 90)
			(layer "B.SilkS")
			(effects
				(font
					(size 0.7 0.7)
					(thickness 0.15)
				)
				(justify right bottom mirror)
			)
		)
		(property "Value" "C_100n_0402"
			(at 0 -1.169 90)
			(layer "B.Fab")
			(effects
				(font
					(size 0.7 0.7)
					(thickness 0.15)
				)
				(justify right bottom mirror)
			)
		)
		(property "Datasheet" "https://www.murata.com/products/productdetail?partno=GRM155R61H104KE14%23"
			(at 0 0 90)
			(layer "F.Fab")
			(hide yes)
			(effects
				(font
					(size 1.27 1.27)
					(thickness 0.15)
				)
			)
		)
		(property "MPN" "GRM155R61H104KE14D"
			(at 0 0 90)
			(unlocked yes)
			(layer "B.Fab")
			(hide yes)
			(effects
				(font
					(size 1 1)
					(thickness 0.15)
				)
				(justify mirror)
			)
		)
		(property "Manufacturer" "Murata"
			(at 0 0 90)
			(unlocked yes)
			(layer "B.Fab")
			(hide yes)
			(effects
				(font
					(size 1 1)
					(thickness 0.15)
				)
				(justify mirror)
			)
		)
		(property "License" "Apache-2.0"
			(at 0 0 90)
			(unlocked yes)
			(layer "B.Fab")
			(hide yes)
			(effects
				(font
					(size 1 1)
					(thickness 0.15)
				)
				(justify mirror)
			)
		)
		(property "Author" "Antmicro"
			(at 0 0 90)
			(unlocked yes)
			(layer "B.Fab")
			(hide yes)
			(effects
				(font
					(size 1 1)
					(thickness 0.15)
				)
				(justify mirror)
			)
		)
		(property "Val" "100n"
			(at 0 0 90)
			(unlocked yes)
			(layer "B.Fab")
			(hide yes)
			(effects
				(font
					(size 1 1)
					(thickness 0.15)
				)
				(justify mirror)
			)
		)
		(property "Voltage" "50V"
			(at 0 0 90)
			(unlocked yes)
			(layer "B.Fab")
			(hide yes)
			(effects
				(font
					(size 1 1)
					(thickness 0.15)
				)
				(justify mirror)
			)
		)
		(property "Dielectric" "X5R"
			(at 0 0 90)
			(unlocked yes)
			(layer "B.Fab")
			(hide yes)
			(effects
				(font
					(size 1 1)
					(thickness 0.15)
				)
				(justify mirror)
			)
		)
		(sheetname "/FPGA power/")
		(sheetfile "fpga-power.kicad_sch")
		(attr smd)
		(fp_rect
			(start -0.95 0.45)
			(end 0.95 -0.45)
			(stroke
				(width 0.05)
				(type default)
			)
			(fill no)
			(layer "B.CrtYd")
		)
		(fp_line
			(start 0.498 -0.248)
			(end -0.5 -0.248)
			(stroke
				(width 0.15)
				(type solid)
			)
			(layer "B.Fab")
		)
		(fp_line
			(start -0.5 -0.248)
			(end -0.5 0.25)
			(stroke
				(width 0.15)
				(type solid)
			)
			(layer "B.Fab")
		)
		(fp_line
			(start 0.498 0.25)
			(end 0.498 -0.248)
			(stroke
				(width 0.15)
				(type solid)
			)
			(layer "B.Fab")
		)
		(fp_line
			(start -0.5 0.25)
			(end 0.498 0.25)
			(stroke
				(width 0.15)
				(type solid)
			)
			(layer "B.Fab")
		)
		(fp_text user "${REFERENCE}"
			(at -0.9656 -3.169 270)
			(layer "B.Fab")
			(effects
				(font
					(size 0.7 0.7)
					(thickness 0.15)
				)
				(justify left bottom mirror)
			)
		)
		(fp_text user "License: Apache-2.0"
			(at -0.9656 -4.369 270)
			(layer "B.Fab")
			(effects
				(font
					(size 0.7 0.7)
					(thickness 0.15)
				)
				(justify left bottom mirror)
			)
		)
		(fp_text user "Author: Antmicro"
			(at -0.9656 -5.569 270)
			(layer "B.Fab")
			(effects
				(font
					(size 0.7 0.7)
					(thickness 0.15)
				)
				(justify left bottom mirror)
			)
		)
		(pad "1" smd roundrect
			(at -0.5 0)
			(size 0.6 0.6)
			(layers "B.Cu" "B.Mask" "B.Paste")
			(roundrect_rratio 0.25)
			(net 1 "GND")
			(pintype "passive")
		)
		(pad "2" smd roundrect
			(at 0.498 0 90)
			(size 0.6 0.6)
			(layers "B.Cu" "B.Mask" "B.Paste")
			(roundrect_rratio 0.25)
			(net 553 "+0V85")
			(pintype "passive")
		)
	)
	(footprint "antmicro-footprints:C_0402_1005Metric_EIA"
		(layer "B.Cu")
		(at 191 162.5 -90)
		(descr "Capacitor SMD 0402 (1005 Metric), square (rectangular) end terminal, IPC_7351 nominal, (Body size source: IPC-SM-782 page 76, https://www.pcb-3d.com/wordpress/wp-content/uploads/ipc-sm-782a_amendment_1_and_2.pdf)")
		(tags "capacitor 0402")
		(property "Reference" "C103"
			(at 1.1 -0.2 90)
			(layer "B.SilkS")
			(effects
				(font
					(size 0.7 0.7)
					(thickness 0.15)
				)
				(justify left bottom mirror)
			)
		)
		(property "Value" "C_4u7_0402"
			(at 0 -1.169 90)
			(layer "B.Fab")
			(effects
				(font
					(size 0.7 0.7)
					(thickness 0.15)
				)
				(justify left bottom mirror)
			)
		)
		(property "Datasheet" "https://www.murata.com/products/productdetail?partno=GRM155R61A475MEAA%23"
			(at 0 0 270)
			(layer "F.Fab")
			(hide yes)
			(effects
				(font
					(size 1.27 1.27)
					(thickness 0.15)
				)
			)
		)
		(property "Manufacturer" "Murata"
			(at 0 0 270)
			(unlocked yes)
			(layer "B.Fab")
			(hide yes)
			(effects
				(font
					(size 1 1)
					(thickness 0.15)
				)
				(justify mirror)
			)
		)
		(property "MPN" "GRM155R61A475MEAAD"
			(at 0 0 270)
			(unlocked yes)
			(layer "B.Fab")
			(hide yes)
			(effects
				(font
					(size 1 1)
					(thickness 0.15)
				)
				(justify mirror)
			)
		)
		(property "Val" "4u7"
			(at 0 0 270)
			(unlocked yes)
			(layer "B.Fab")
			(hide yes)
			(effects
				(font
					(size 1 1)
					(thickness 0.15)
				)
				(justify mirror)
			)
		)
		(property "License" "Apache-2.0"
			(at 0 0 270)
			(unlocked yes)
			(layer "B.Fab")
			(hide yes)
			(effects
				(font
					(size 1 1)
					(thickness 0.15)
				)
				(justify mirror)
			)
		)
		(property "Author" "Antmicro"
			(at 0 0 270)
			(unlocked yes)
			(layer "B.Fab")
			(hide yes)
			(effects
				(font
					(size 1 1)
					(thickness 0.15)
				)
				(justify mirror)
			)
		)
		(property "Voltage" ""
			(at 0 0 270)
			(unlocked yes)
			(layer "B.Fab")
			(hide yes)
			(effects
				(font
					(size 1 1)
					(thickness 0.15)
				)
				(justify mirror)
			)
		)
		(property "Dielectric" ""
			(at 0 0 270)
			(unlocked yes)
			(layer "B.Fab")
			(hide yes)
			(effects
				(font
					(size 1 1)
					(thickness 0.15)
				)
				(justify mirror)
			)
		)
		(sheetname "/FPGA power/")
		(sheetfile "fpga-power.kicad_sch")
		(attr smd)
		(fp_rect
			(start -0.95 0.45)
			(end 0.95 -0.45)
			(stroke
				(width 0.05)
				(type default)
			)
			(fill no)
			(layer "B.CrtYd")
		)
		(fp_line
			(start -0.5 0.25)
			(end 0.498 0.25)
			(stroke
				(width 0.15)
				(type solid)
			)
			(layer "B.Fab")
		)
		(fp_line
			(start 0.498 0.25)
			(end 0.498 -0.248)
			(stroke
				(width 0.15)
				(type solid)
			)
			(layer "B.Fab")
		)
		(fp_line
			(start -0.5 -0.248)
			(end -0.5 0.25)
			(stroke
				(width 0.15)
				(type solid)
			)
			(layer "B.Fab")
		)
		(fp_line
			(start 0.498 -0.248)
			(end -0.5 -0.248)
			(stroke
				(width 0.15)
				(type solid)
			)
			(layer "B.Fab")
		)
		(fp_text user "License: Apache-2.0"
			(at -0.9656 -4.369 90)
			(layer "B.Fab")
			(effects
				(font
					(size 0.7 0.7)
					(thickness 0.15)
				)
				(justify left bottom mirror)
			)
		)
		(fp_text user "${REFERENCE}"
			(at -0.9656 -3.169 90)
			(layer "B.Fab")
			(effects
				(font
					(size 0.7 0.7)
					(thickness 0.15)
				)
				(justify left bottom mirror)
			)
		)
		(fp_text user "Author: Antmicro"
			(at -0.9656 -5.569 90)
			(layer "B.Fab")
			(effects
				(font
					(size 0.7 0.7)
					(thickness 0.15)
				)
				(justify left bottom mirror)
			)
		)
		(pad "1" smd roundrect
			(at -0.5 0 180)
			(size 0.6 0.6)
			(layers "B.Cu" "B.Mask" "B.Paste")
			(roundrect_rratio 0.25)
			(net 172 "+1V2_MGTAVTT")
			(pintype "passive")
		)
		(pad "2" smd roundrect
			(at 0.498 0 270)
			(size 0.6 0.6)
			(layers "B.Cu" "B.Mask" "B.Paste")
			(roundrect_rratio 0.25)
			(net 1 "GND")
			(pintype "passive")
		)
	)
	(footprint "antmicro-footprints:C_0402_1005Metric"
		(layer "B.Cu")
		(at 175.65 193.249501 90)
		(descr "Capacitor SMD 0402")
		(tags "capacitor SMD 0402")
		(property "Reference" "C226"
			(at 0.994 0.403501 90)
			(layer "B.SilkS")
			(effects
				(font
					(size 0.7 0.7)
					(thickness 0.15)
				)
				(justify right bottom mirror)
			)
		)
		(property "Value" "C_100n_0402"
			(at -1.022927 -2.155213 90)
			(layer "B.Fab")
			(effects
				(font
					(size 0.7 0.7)
					(thickness 0.15)
				)
				(justify right bottom mirror)
			)
		)
		(property "Datasheet" "https://www.murata.com/products/productdetail?partno=GRM155R61H104KE14%23"
			(at 0 0 90)
			(layer "F.Fab")
			(hide yes)
			(effects
				(font
					(size 1.27 1.27)
					(thickness 0.15)
				)
			)
		)
		(property "Manufacturer" "Murata"
			(at 0 0 90)
			(unlocked yes)
			(layer "B.Fab")
			(hide yes)
			(effects
				(font
					(size 1 1)
					(thickness 0.15)
				)
				(justify mirror)
			)
		)
		(property "MPN" "GRM155R61H104KE14D"
			(at 0 0 90)
			(unlocked yes)
			(layer "B.Fab")
			(hide yes)
			(effects
				(font
					(size 1 1)
					(thickness 0.15)
				)
				(justify mirror)
			)
		)
		(property "Val" "100n"
			(at 0 0 90)
			(unlocked yes)
			(layer "B.Fab")
			(hide yes)
			(effects
				(font
					(size 1 1)
					(thickness 0.15)
				)
				(justify mirror)
			)
		)
		(property "License" "Apache-2.0"
			(at 0 0 90)
			(unlocked yes)
			(layer "B.Fab")
			(hide yes)
			(effects
				(font
					(size 1 1)
					(thickness 0.15)
				)
				(justify mirror)
			)
		)
		(property "Author" "Antmicro"
			(at 0 0 90)
			(unlocked yes)
			(layer "B.Fab")
			(hide yes)
			(effects
				(font
					(size 1 1)
					(thickness 0.15)
				)
				(justify mirror)
			)
		)
		(property "Voltage" "50V"
			(at 0 0 90)
			(unlocked yes)
			(layer "B.Fab")
			(hide yes)
			(effects
				(font
					(size 1 1)
					(thickness 0.15)
				)
				(justify mirror)
			)
		)
		(property "Dielectric" "X5R"
			(at 0 0 90)
			(unlocked yes)
			(layer "B.Fab")
			(hide yes)
			(effects
				(font
					(size 1 1)
					(thickness 0.15)
				)
				(justify mirror)
			)
		)
		(sheetname "/FPGA MGT Interface/")
		(sheetfile "fpga-mgt.kicad_sch")
		(attr smd)
		(fp_rect
			(start -0.925 0.47)
			(end 0.925 -0.47)
			(stroke
				(width 0.05)
				(type default)
			)
			(fill no)
			(layer "B.CrtYd")
		)
		(fp_line
			(start 0.504 -0.248)
			(end -0.494 -0.248)
			(stroke
				(width 0.15)
				(type solid)
			)
			(layer "B.Fab")
		)
		(fp_line
			(start -0.494 -0.248)
			(end -0.494 0.25)
			(stroke
				(width 0.15)
				(type solid)
			)
			(layer "B.Fab")
		)
		(fp_line
			(start 0.504 0.25)
			(end 0.504 -0.248)
			(stroke
				(width 0.15)
				(type solid)
			)
			(layer "B.Fab")
		)
		(fp_line
			(start -0.494 0.25)
			(end 0.504 0.25)
			(stroke
				(width 0.15)
				(type solid)
			)
			(layer "B.Fab")
		)
		(fp_text user "${REFERENCE}"
			(at -0.939 -4.599 270)
			(layer "B.Fab")
			(effects
				(font
					(size 0.7 0.7)
					(thickness 0.15)
				)
				(justify left bottom mirror)
			)
		)
		(fp_text user "License: Apache-2.0"
			(at -0.939 -5.799 270)
			(layer "B.Fab")
			(effects
				(font
					(size 0.7 0.7)
					(thickness 0.15)
				)
				(justify left bottom mirror)
			)
		)
		(fp_text user "Author: Antmicro"
			(at -0.939 -3.399 270)
			(layer "B.Fab")
			(effects
				(font
					(size 0.7 0.7)
					(thickness 0.15)
				)
				(justify left bottom mirror)
			)
		)
		(pad "1" smd roundrect
			(at -0.48 0 90)
			(size 0.59 0.64)
			(layers "B.Cu" "B.Mask" "B.Paste")
			(roundrect_rratio 0.25)
			(net 15 "/FPGA MGT Interface/PCIE.TXD3_P")
			(pintype "passive")
		)
		(pad "2" smd roundrect
			(at 0.48 0 90)
			(size 0.59 0.64)
			(layers "B.Cu" "B.Mask" "B.Paste")
			(roundrect_rratio 0.25)
			(net 16 "/FPGA MGT Interface/GTY_225_TX0_P")
			(pintype "passive")
		)
	)
	(footprint "antmicro-footprints:C_0402_1005Metric_EIA"
		(layer "B.Cu")
		(at 193 162.5 90)
		(descr "Capacitor SMD 0402 (1005 Metric), square (rectangular) end terminal, IPC_7351 nominal, (Body size source: IPC-SM-782 page 76, https://www.pcb-3d.com/wordpress/wp-content/uploads/ipc-sm-782a_amendment_1_and_2.pdf)")
		(tags "capacitor 0402")
		(property "Reference" "C104"
			(at -3.95 0.2 90)
			(layer "B.SilkS")
			(effects
				(font
					(size 0.7 0.7)
					(thickness 0.15)
				)
				(justify right bottom mirror)
			)
		)
		(property "Value" "C_100n_0402"
			(at 0 -1.169 90)
			(layer "B.Fab")
			(effects
				(font
					(size 0.7 0.7)
					(thickness 0.15)
				)
				(justify right bottom mirror)
			)
		)
		(property "Datasheet" "https://www.murata.com/products/productdetail?partno=GRM155R61H104KE14%23"
			(at 0 0 90)
			(layer "F.Fab")
			(hide yes)
			(effects
				(font
					(size 1.27 1.27)
					(thickness 0.15)
				)
			)
		)
		(property "MPN" "GRM155R61H104KE14D"
			(at 0 0 90)
			(unlocked yes)
			(layer "B.Fab")
			(hide yes)
			(effects
				(font
					(size 1 1)
					(thickness 0.15)
				)
				(justify mirror)
			)
		)
		(property "Manufacturer" "Murata"
			(at 0 0 90)
			(unlocked yes)
			(layer "B.Fab")
			(hide yes)
			(effects
				(font
					(size 1 1)
					(thickness 0.15)
				)
				(justify mirror)
			)
		)
		(property "License" "Apache-2.0"
			(at 0 0 90)
			(unlocked yes)
			(layer "B.Fab")
			(hide yes)
			(effects
				(font
					(size 1 1)
					(thickness 0.15)
				)
				(justify mirror)
			)
		)
		(property "Author" "Antmicro"
			(at 0 0 90)
			(unlocked yes)
			(layer "B.Fab")
			(hide yes)
			(effects
				(font
					(size 1 1)
					(thickness 0.15)
				)
				(justify mirror)
			)
		)
		(property "Val" "100n"
			(at 0 0 90)
			(unlocked yes)
			(layer "B.Fab")
			(hide yes)
			(effects
				(font
					(size 1 1)
					(thickness 0.15)
				)
				(justify mirror)
			)
		)
		(property "Voltage" "50V"
			(at 0 0 90)
			(unlocked yes)
			(layer "B.Fab")
			(hide yes)
			(effects
				(font
					(size 1 1)
					(thickness 0.15)
				)
				(justify mirror)
			)
		)
		(property "Dielectric" "X5R"
			(at 0 0 90)
			(unlocked yes)
			(layer "B.Fab")
			(hide yes)
			(effects
				(font
					(size 1 1)
					(thickness 0.15)
				)
				(justify mirror)
			)
		)
		(sheetname "/FPGA power/")
		(sheetfile "fpga-power.kicad_sch")
		(attr smd)
		(fp_rect
			(start -0.95 0.45)
			(end 0.95 -0.45)
			(stroke
				(width 0.05)
				(type default)
			)
			(fill no)
			(layer "B.CrtYd")
		)
		(fp_line
			(start 0.498 -0.248)
			(end -0.5 -0.248)
			(stroke
				(width 0.15)
				(type solid)
			)
			(layer "B.Fab")
		)
		(fp_line
			(start -0.5 -0.248)
			(end -0.5 0.25)
			(stroke
				(width 0.15)
				(type solid)
			)
			(layer "B.Fab")
		)
		(fp_line
			(start 0.498 0.25)
			(end 0.498 -0.248)
			(stroke
				(width 0.15)
				(type solid)
			)
			(layer "B.Fab")
		)
		(fp_line
			(start -0.5 0.25)
			(end 0.498 0.25)
			(stroke
				(width 0.15)
				(type solid)
			)
			(layer "B.Fab")
		)
		(fp_text user "Author: Antmicro"
			(at -0.9656 -5.569 270)
			(layer "B.Fab")
			(effects
				(font
					(size 0.7 0.7)
					(thickness 0.15)
				)
				(justify left bottom mirror)
			)
		)
		(fp_text user "License: Apache-2.0"
			(at -0.9656 -4.369 270)
			(layer "B.Fab")
			(effects
				(font
					(size 0.7 0.7)
					(thickness 0.15)
				)
				(justify left bottom mirror)
			)
		)
		(fp_text user "${REFERENCE}"
			(at -0.9656 -3.169 270)
			(layer "B.Fab")
			(effects
				(font
					(size 0.7 0.7)
					(thickness 0.15)
				)
				(justify left bottom mirror)
			)
		)
		(pad "1" smd roundrect
			(at -0.5 0)
			(size 0.6 0.6)
			(layers "B.Cu" "B.Mask" "B.Paste")
			(roundrect_rratio 0.25)
			(net 1 "GND")
			(pintype "passive")
		)
		(pad "2" smd roundrect
			(at 0.498 0 90)
			(size 0.6 0.6)
			(layers "B.Cu" "B.Mask" "B.Paste")
			(roundrect_rratio 0.25)
			(net 172 "+1V2_MGTAVTT")
			(pintype "passive")
		)
	)
	(footprint "antmicro-footprints:R_0402_1005Metric"
		(layer "B.Cu")
		(at 215.1 183.285 90)
		(descr "Resistor SMD 0402")
		(tags "resistor SMD 0402")
		(property "Reference" "R186"
			(at -0.865 -0.6 90)
			(layer "B.SilkS")
			(effects
				(font
					(size 0.7 0.7)
					(thickness 0.15)
				)
				(justify right bottom mirror)
			)
		)
		(property "Value" "R_0R_0402"
			(at -1.011843 -1.772047 90)
			(layer "B.Fab")
			(effects
				(font
					(size 0.7 0.7)
					(thickness 0.15)
				)
				(justify right bottom mirror)
			)
		)
		(property "Datasheet" "https://industrial.panasonic.com/cdbs/www-data/pdf/RDA0000/AOA0000C301.pdf"
			(at 0 0 90)
			(layer "F.Fab")
			(hide yes)
			(effects
				(font
					(size 1.27 1.27)
					(thickness 0.15)
				)
			)
		)
		(property "MPN" "ERJ2GE0R00X"
			(at 0 0 90)
			(unlocked yes)
			(layer "B.Fab")
			(hide yes)
			(effects
				(font
					(size 1 1)
					(thickness 0.15)
				)
				(justify mirror)
			)
		)
		(property "Manufacturer" "Panasonic"
			(at 0 0 90)
			(unlocked yes)
			(layer "B.Fab")
			(hide yes)
			(effects
				(font
					(size 1 1)
					(thickness 0.15)
				)
				(justify mirror)
			)
		)
		(property "License" "Apache-2.0"
			(at 0 0 90)
			(unlocked yes)
			(layer "B.Fab")
			(hide yes)
			(effects
				(font
					(size 1 1)
					(thickness 0.15)
				)
				(justify mirror)
			)
		)
		(property "Author" "Antmicro"
			(at 0 0 90)
			(unlocked yes)
			(layer "B.Fab")
			(hide yes)
			(effects
				(font
					(size 1 1)
					(thickness 0.15)
				)
				(justify mirror)
			)
		)
		(property "Val" "0R"
			(at 0 0 90)
			(unlocked yes)
			(layer "B.Fab")
			(hide yes)
			(effects
				(font
					(size 1 1)
					(thickness 0.15)
				)
				(justify mirror)
			)
		)
		(property "Tolerance" "~"
			(at 0 0 90)
			(unlocked yes)
			(layer "B.Fab")
			(hide yes)
			(effects
				(font
					(size 1 1)
					(thickness 0.15)
				)
				(justify mirror)
			)
		)
		(property "Current" "1A"
			(at 0 0 90)
			(unlocked yes)
			(layer "B.Fab")
			(hide yes)
			(effects
				(font
					(size 1 1)
					(thickness 0.15)
				)
				(justify mirror)
			)
		)
		(sheetname "/Supply/DC-DC VCCINT/")
		(sheetfile "dc-dc-vccint.kicad_sch")
		(attr smd exclude_from_bom dnp)
		(fp_rect
			(start -0.925 0.47)
			(end 0.925 -0.47)
			(stroke
				(width 0.05)
				(type default)
			)
			(fill no)
			(layer "B.CrtYd")
		)
		(fp_rect
			(start -0.5 0.25)
			(end 0.5 -0.25)
			(stroke
				(width 0.15)
				(type solid)
			)
			(fill no)
			(layer "B.Fab")
		)
		(fp_text user "License: Apache-2.0"
			(at -0.95 -5.169 270)
			(layer "B.Fab")
			(effects
				(font
					(size 0.7 0.7)
					(thickness 0.15)
				)
				(justify left bottom mirror)
			)
		)
		(fp_text user "${REFERENCE}"
			(at -0.95 -3.168 270)
			(layer "B.Fab")
			(effects
				(font
					(size 0.7 0.7)
					(thickness 0.15)
				)
				(justify left bottom mirror)
			)
		)
		(fp_text user "Author: Antmicro"
			(at -0.95 -4.169 270)
			(layer "B.Fab")
			(effects
				(font
					(size 0.7 0.7)
					(thickness 0.15)
				)
				(justify left bottom mirror)
			)
		)
		(pad "1" smd roundrect
			(at -0.48 0 90)
			(size 0.59 0.64)
			(layers "B.Cu" "B.Mask" "B.Paste")
			(roundrect_rratio 0.25)
			(net 724 "/Supply/DC-DC VCCINT/TAKE0")
			(pintype "passive")
		)
		(pad "2" smd roundrect
			(at 0.48 0 90)
			(size 0.59 0.64)
			(layers "B.Cu" "B.Mask" "B.Paste")
			(roundrect_rratio 0.25)
			(net 721 "/Supply/DC-DC VCCINT/PASS0")
			(pintype "passive")
		)
	)
	(footprint "antmicro-footprints:C_0402_1005Metric"
		(layer "B.Cu")
		(at 180.510001 167.45 90)
		(descr "Capacitor SMD 0402")
		(tags "capacitor SMD 0402")
		(property "Reference" "C244"
			(at -4 -0.134 90)
			(layer "B.SilkS")
			(effects
				(font
					(size 0.7 0.7)
					(thickness 0.15)
				)
				(justify right bottom mirror)
			)
		)
		(property "Value" "C_100n_0402"
			(at -1.022927 -2.155213 90)
			(layer "B.Fab")
			(effects
				(font
					(size 0.7 0.7)
					(thickness 0.15)
				)
				(justify right bottom mirror)
			)
		)
		(property "Datasheet" "https://www.murata.com/products/productdetail?partno=GRM155R61H104KE14%23"
			(at 0 0 90)
			(layer "F.Fab")
			(hide yes)
			(effects
				(font
					(size 1.27 1.27)
					(thickness 0.15)
				)
			)
		)
		(property "Manufacturer" "Murata"
			(at 0 0 90)
			(unlocked yes)
			(layer "B.Fab")
			(hide yes)
			(effects
				(font
					(size 1 1)
					(thickness 0.15)
				)
				(justify mirror)
			)
		)
		(property "MPN" "GRM155R61H104KE14D"
			(at 0 0 90)
			(unlocked yes)
			(layer "B.Fab")
			(hide yes)
			(effects
				(font
					(size 1 1)
					(thickness 0.15)
				)
				(justify mirror)
			)
		)
		(property "Val" "100n"
			(at 0 0 90)
			(unlocked yes)
			(layer "B.Fab")
			(hide yes)
			(effects
				(font
					(size 1 1)
					(thickness 0.15)
				)
				(justify mirror)
			)
		)
		(property "License" "Apache-2.0"
			(at 0 0 90)
			(unlocked yes)
			(layer "B.Fab")
			(hide yes)
			(effects
				(font
					(size 1 1)
					(thickness 0.15)
				)
				(justify mirror)
			)
		)
		(property "Author" "Antmicro"
			(at 0 0 90)
			(unlocked yes)
			(layer "B.Fab")
			(hide yes)
			(effects
				(font
					(size 1 1)
					(thickness 0.15)
				)
				(justify mirror)
			)
		)
		(property "Voltage" "50V"
			(at 0 0 90)
			(unlocked yes)
			(layer "B.Fab")
			(hide yes)
			(effects
				(font
					(size 1 1)
					(thickness 0.15)
				)
				(justify mirror)
			)
		)
		(property "Dielectric" "X5R"
			(at 0 0 90)
			(unlocked yes)
			(layer "B.Fab")
			(hide yes)
			(effects
				(font
					(size 1 1)
					(thickness 0.15)
				)
				(justify mirror)
			)
		)
		(sheetname "/FPGA MGT Interface/")
		(sheetfile "fpga-mgt.kicad_sch")
		(attr smd)
		(fp_rect
			(start -0.925 0.47)
			(end 0.925 -0.47)
			(stroke
				(width 0.05)
				(type default)
			)
			(fill no)
			(layer "B.CrtYd")
		)
		(fp_line
			(start 0.504 -0.248)
			(end -0.494 -0.248)
			(stroke
				(width 0.15)
				(type solid)
			)
			(layer "B.Fab")
		)
		(fp_line
			(start -0.494 -0.248)
			(end -0.494 0.25)
			(stroke
				(width 0.15)
				(type solid)
			)
			(layer "B.Fab")
		)
		(fp_line
			(start 0.504 0.25)
			(end 0.504 -0.248)
			(stroke
				(width 0.15)
				(type solid)
			)
			(layer "B.Fab")
		)
		(fp_line
			(start -0.494 0.25)
			(end 0.504 0.25)
			(stroke
				(width 0.15)
				(type solid)
			)
			(layer "B.Fab")
		)
		(fp_text user "Author: Antmicro"
			(at -0.939 -3.399 270)
			(layer "B.Fab")
			(effects
				(font
					(size 0.7 0.7)
					(thickness 0.15)
				)
				(justify left bottom mirror)
			)
		)
		(fp_text user "License: Apache-2.0"
			(at -0.939 -5.799 270)
			(layer "B.Fab")
			(effects
				(font
					(size 0.7 0.7)
					(thickness 0.15)
				)
				(justify left bottom mirror)
			)
		)
		(fp_text user "${REFERENCE}"
			(at -0.939 -4.599 270)
			(layer "B.Fab")
			(effects
				(font
					(size 0.7 0.7)
					(thickness 0.15)
				)
				(justify left bottom mirror)
			)
		)
		(pad "1" smd roundrect
			(at -0.48 0 90)
			(size 0.59 0.64)
			(layers "B.Cu" "B.Mask" "B.Paste")
			(roundrect_rratio 0.25)
			(net 381 "/FPGA MGT Interface/HDMI_OUT.CLK_P")
			(pintype "passive")
		)
		(pad "2" smd roundrect
			(at 0.48 0 90)
			(size 0.59 0.64)
			(layers "B.Cu" "B.Mask" "B.Paste")
			(roundrect_rratio 0.25)
			(net 382 "/FPGA MGT Interface/HDMI_FPGA.TX_CLK_P")
			(pintype "passive")
		)
	)
	(footprint "antmicro-footprints:C_0402_1005Metric_EIA"
		(layer "B.Cu")
		(at 192 143.5 90)
		(descr "Capacitor SMD 0402 (1005 Metric), square (rectangular) end terminal, IPC_7351 nominal, (Body size source: IPC-SM-782 page 76, https://www.pcb-3d.com/wordpress/wp-content/uploads/ipc-sm-782a_amendment_1_and_2.pdf)")
		(tags "capacitor 0402")
		(property "Reference" "C49"
			(at -1.05 1.475 90)
			(layer "B.SilkS")
			(effects
				(font
					(size 0.7 0.7)
					(thickness 0.15)
				)
				(justify right bottom mirror)
			)
		)
		(property "Value" "C_10u_10V_0402"
			(at 0 -1.169 90)
			(layer "B.Fab")
			(effects
				(font
					(size 0.7 0.7)
					(thickness 0.15)
				)
				(justify right bottom mirror)
			)
		)
		(property "Datasheet" "https://www.murata.com/products/productdetail?partno=GRM155R61A106ME11%23"
			(at 0 0 90)
			(layer "F.Fab")
			(hide yes)
			(effects
				(font
					(size 1.27 1.27)
					(thickness 0.15)
				)
			)
		)
		(property "MPN" "GRM155R61A106ME11D"
			(at 0 0 90)
			(unlocked yes)
			(layer "B.Fab")
			(hide yes)
			(effects
				(font
					(size 1 1)
					(thickness 0.15)
				)
				(justify mirror)
			)
		)
		(property "Manufacturer" "Murata"
			(at 0 0 90)
			(unlocked yes)
			(layer "B.Fab")
			(hide yes)
			(effects
				(font
					(size 1 1)
					(thickness 0.15)
				)
				(justify mirror)
			)
		)
		(property "License" "Apache-2.0"
			(at 0 0 90)
			(unlocked yes)
			(layer "B.Fab")
			(hide yes)
			(effects
				(font
					(size 1 1)
					(thickness 0.15)
				)
				(justify mirror)
			)
		)
		(property "Author" "Antmicro"
			(at 0 0 90)
			(unlocked yes)
			(layer "B.Fab")
			(hide yes)
			(effects
				(font
					(size 1 1)
					(thickness 0.15)
				)
				(justify mirror)
			)
		)
		(property "Val" "10u"
			(at 0 0 90)
			(unlocked yes)
			(layer "B.Fab")
			(hide yes)
			(effects
				(font
					(size 1 1)
					(thickness 0.15)
				)
				(justify mirror)
			)
		)
		(property "Voltage" "10V"
			(at 0 0 90)
			(unlocked yes)
			(layer "B.Fab")
			(hide yes)
			(effects
				(font
					(size 1 1)
					(thickness 0.15)
				)
				(justify mirror)
			)
		)
		(property "Dielectric" "X5R"
			(at 0 0 90)
			(unlocked yes)
			(layer "B.Fab")
			(hide yes)
			(effects
				(font
					(size 1 1)
					(thickness 0.15)
				)
				(justify mirror)
			)
		)
		(sheetname "/FPGA power/")
		(sheetfile "fpga-power.kicad_sch")
		(attr smd)
		(fp_rect
			(start -0.95 0.45)
			(end 0.95 -0.45)
			(stroke
				(width 0.05)
				(type default)
			)
			(fill no)
			(layer "B.CrtYd")
		)
		(fp_line
			(start 0.498 -0.248)
			(end -0.5 -0.248)
			(stroke
				(width 0.15)
				(type solid)
			)
			(layer "B.Fab")
		)
		(fp_line
			(start -0.5 -0.248)
			(end -0.5 0.25)
			(stroke
				(width 0.15)
				(type solid)
			)
			(layer "B.Fab")
		)
		(fp_line
			(start 0.498 0.25)
			(end 0.498 -0.248)
			(stroke
				(width 0.15)
				(type solid)
			)
			(layer "B.Fab")
		)
		(fp_line
			(start -0.5 0.25)
			(end 0.498 0.25)
			(stroke
				(width 0.15)
				(type solid)
			)
			(layer "B.Fab")
		)
		(fp_text user "${REFERENCE}"
			(at -0.9656 -3.169 270)
			(layer "B.Fab")
			(effects
				(font
					(size 0.7 0.7)
					(thickness 0.15)
				)
				(justify left bottom mirror)
			)
		)
		(fp_text user "License: Apache-2.0"
			(at -0.9656 -4.369 270)
			(layer "B.Fab")
			(effects
				(font
					(size 0.7 0.7)
					(thickness 0.15)
				)
				(justify left bottom mirror)
			)
		)
		(fp_text user "Author: Antmicro"
			(at -0.9656 -5.569 270)
			(layer "B.Fab")
			(effects
				(font
					(size 0.7 0.7)
					(thickness 0.15)
				)
				(justify left bottom mirror)
			)
		)
		(pad "1" smd roundrect
			(at -0.5 0)
			(size 0.6 0.6)
			(layers "B.Cu" "B.Mask" "B.Paste")
			(roundrect_rratio 0.25)
			(net 1 "GND")
			(pintype "passive")
		)
		(pad "2" smd roundrect
			(at 0.498 0 90)
			(size 0.6 0.6)
			(layers "B.Cu" "B.Mask" "B.Paste")
			(roundrect_rratio 0.25)
			(net 687 "VDDQ")
			(pintype "passive")
		)
	)
	(footprint "antmicro-footprints:R_0402_1005Metric"
		(layer "B.Cu")
		(at 125.92 186.94 180)
		(descr "Resistor SMD 0402")
		(tags "resistor SMD 0402")
		(property "Reference" "R237"
			(at 1.17 -0.46 0)
			(layer "B.SilkS")
			(effects
				(font
					(size 0.7 0.7)
					(thickness 0.15)
				)
				(justify left bottom mirror)
			)
		)
		(property "Value" "R_2k2_0402"
			(at -1.011843 -1.772047 0)
			(layer "B.Fab")
			(effects
				(font
					(size 0.7 0.7)
					(thickness 0.15)
				)
				(justify left bottom mirror)
			)
		)
		(property "Datasheet" "https://www.bourns.com/docs/product-datasheets/cr.pdf"
			(at 0 0 180)
			(layer "F.Fab")
			(hide yes)
			(effects
				(font
					(size 1.27 1.27)
					(thickness 0.15)
				)
			)
		)
		(property "MPN" "CR0402-FX-2201GLF"
			(at 0 0 180)
			(unlocked yes)
			(layer "B.Fab")
			(hide yes)
			(effects
				(font
					(size 1 1)
					(thickness 0.15)
				)
				(justify mirror)
			)
		)
		(property "Manufacturer" "Bourns"
			(at 0 0 180)
			(unlocked yes)
			(layer "B.Fab")
			(hide yes)
			(effects
				(font
					(size 1 1)
					(thickness 0.15)
				)
				(justify mirror)
			)
		)
		(property "License" "Apache-2.0"
			(at 0 0 180)
			(unlocked yes)
			(layer "B.Fab")
			(hide yes)
			(effects
				(font
					(size 1 1)
					(thickness 0.15)
				)
				(justify mirror)
			)
		)
		(property "Author" "Antmicro"
			(at 0 0 180)
			(unlocked yes)
			(layer "B.Fab")
			(hide yes)
			(effects
				(font
					(size 1 1)
					(thickness 0.15)
				)
				(justify mirror)
			)
		)
		(property "Val" "2k2"
			(at 0 0 180)
			(unlocked yes)
			(layer "B.Fab")
			(hide yes)
			(effects
				(font
					(size 1 1)
					(thickness 0.15)
				)
				(justify mirror)
			)
		)
		(property "Tolerance" "1%"
			(at 0 0 180)
			(unlocked yes)
			(layer "B.Fab")
			(hide yes)
			(effects
				(font
					(size 1 1)
					(thickness 0.15)
				)
				(justify mirror)
			)
		)
		(property "Public" ""
			(at 0 0 180)
			(unlocked yes)
			(layer "B.Fab")
			(hide yes)
			(effects
				(font
					(size 1 1)
					(thickness 0.15)
				)
				(justify mirror)
			)
		)
		(sheetname "/HDMI + SD Card/")
		(sheetfile "hdmi-sd-card.kicad_sch")
		(attr smd)
		(fp_rect
			(start -0.925 0.47)
			(end 0.925 -0.47)
			(stroke
				(width 0.05)
				(type default)
			)
			(fill no)
			(layer "B.CrtYd")
		)
		(fp_rect
			(start -0.5 0.25)
			(end 0.5 -0.25)
			(stroke
				(width 0.15)
				(type solid)
			)
			(fill no)
			(layer "B.Fab")
		)
		(fp_text user "License: Apache-2.0"
			(at -0.95 -5.169 0)
			(layer "B.Fab")
			(effects
				(font
					(size 0.7 0.7)
					(thickness 0.15)
				)
				(justify left bottom mirror)
			)
		)
		(fp_text user "${REFERENCE}"
			(at -0.95 -3.168 0)
			(layer "B.Fab")
			(effects
				(font
					(size 0.7 0.7)
					(thickness 0.15)
				)
				(justify left bottom mirror)
			)
		)
		(fp_text user "Author: Antmicro"
			(at -0.95 -4.169 0)
			(layer "B.Fab")
			(effects
				(font
					(size 0.7 0.7)
					(thickness 0.15)
				)
				(justify left bottom mirror)
			)
		)
		(pad "1" smd roundrect
			(at -0.48 0 180)
			(size 0.59 0.64)
			(layers "B.Cu" "B.Mask" "B.Paste")
			(roundrect_rratio 0.25)
			(net 644 "/FPGA banks HD/HDMI_OUT_I2C.SDA")
			(pintype "passive")
		)
		(pad "2" smd roundrect
			(at 0.48 0 180)
			(size 0.59 0.64)
			(layers "B.Cu" "B.Mask" "B.Paste")
			(roundrect_rratio 0.25)
			(net 151 "+3V3")
			(pintype "passive")
		)
	)
	(footprint "antmicro-footprints:R_0402_1005Metric"
		(layer "B.Cu")
		(at 125.92 187.94 180)
		(descr "Resistor SMD 0402")
		(tags "resistor SMD 0402")
		(property "Reference" "R236"
			(at 1.17 -0.46 0)
			(layer "B.SilkS")
			(effects
				(font
					(size 0.7 0.7)
					(thickness 0.15)
				)
				(justify left bottom mirror)
			)
		)
		(property "Value" "R_2k2_0402"
			(at -1.011843 -1.772047 0)
			(layer "B.Fab")
			(effects
				(font
					(size 0.7 0.7)
					(thickness 0.15)
				)
				(justify left bottom mirror)
			)
		)
		(property "Datasheet" "https://www.bourns.com/docs/product-datasheets/cr.pdf"
			(at 0 0 180)
			(layer "F.Fab")
			(hide yes)
			(effects
				(font
					(size 1.27 1.27)
					(thickness 0.15)
				)
			)
		)
		(property "MPN" "CR0402-FX-2201GLF"
			(at 0 0 180)
			(unlocked yes)
			(layer "B.Fab")
			(hide yes)
			(effects
				(font
					(size 1 1)
					(thickness 0.15)
				)
				(justify mirror)
			)
		)
		(property "Manufacturer" "Bourns"
			(at 0 0 180)
			(unlocked yes)
			(layer "B.Fab")
			(hide yes)
			(effects
				(font
					(size 1 1)
					(thickness 0.15)
				)
				(justify mirror)
			)
		)
		(property "License" "Apache-2.0"
			(at 0 0 180)
			(unlocked yes)
			(layer "B.Fab")
			(hide yes)
			(effects
				(font
					(size 1 1)
					(thickness 0.15)
				)
				(justify mirror)
			)
		)
		(property "Author" "Antmicro"
			(at 0 0 180)
			(unlocked yes)
			(layer "B.Fab")
			(hide yes)
			(effects
				(font
					(size 1 1)
					(thickness 0.15)
				)
				(justify mirror)
			)
		)
		(property "Val" "2k2"
			(at 0 0 180)
			(unlocked yes)
			(layer "B.Fab")
			(hide yes)
			(effects
				(font
					(size 1 1)
					(thickness 0.15)
				)
				(justify mirror)
			)
		)
		(property "Tolerance" "1%"
			(at 0 0 180)
			(unlocked yes)
			(layer "B.Fab")
			(hide yes)
			(effects
				(font
					(size 1 1)
					(thickness 0.15)
				)
				(justify mirror)
			)
		)
		(property "Public" ""
			(at 0 0 180)
			(unlocked yes)
			(layer "B.Fab")
			(hide yes)
			(effects
				(font
					(size 1 1)
					(thickness 0.15)
				)
				(justify mirror)
			)
		)
		(sheetname "/HDMI + SD Card/")
		(sheetfile "hdmi-sd-card.kicad_sch")
		(attr smd)
		(fp_rect
			(start -0.925 0.47)
			(end 0.925 -0.47)
			(stroke
				(width 0.05)
				(type default)
			)
			(fill no)
			(layer "B.CrtYd")
		)
		(fp_rect
			(start -0.5 0.25)
			(end 0.5 -0.25)
			(stroke
				(width 0.15)
				(type solid)
			)
			(fill no)
			(layer "B.Fab")
		)
		(fp_text user "${REFERENCE}"
			(at -0.95 -3.168 0)
			(layer "B.Fab")
			(effects
				(font
					(size 0.7 0.7)
					(thickness 0.15)
				)
				(justify left bottom mirror)
			)
		)
		(fp_text user "License: Apache-2.0"
			(at -0.95 -5.169 0)
			(layer "B.Fab")
			(effects
				(font
					(size 0.7 0.7)
					(thickness 0.15)
				)
				(justify left bottom mirror)
			)
		)
		(fp_text user "Author: Antmicro"
			(at -0.95 -4.169 0)
			(layer "B.Fab")
			(effects
				(font
					(size 0.7 0.7)
					(thickness 0.15)
				)
				(justify left bottom mirror)
			)
		)
		(pad "1" smd roundrect
			(at -0.48 0 180)
			(size 0.59 0.64)
			(layers "B.Cu" "B.Mask" "B.Paste")
			(roundrect_rratio 0.25)
			(net 554 "/FPGA banks HD/HDMI_OUT_I2C.SCL")
			(pintype "passive")
		)
		(pad "2" smd roundrect
			(at 0.48 0 180)
			(size 0.59 0.64)
			(layers "B.Cu" "B.Mask" "B.Paste")
			(roundrect_rratio 0.25)
			(net 151 "+3V3")
			(pintype "passive")
		)
	)
	(footprint "antmicro-footprints:C_0805_2012Metric"
		(layer "B.Cu")
		(at 178.000001 167.5 180)
		(descr "Capacitor SMD 0805")
		(tags "capacitor SMD 0805")
		(property "Reference" "C54"
			(at -0.499999 -1.8 0)
			(layer "B.SilkS")
			(effects
				(font
					(size 0.7 0.7)
					(thickness 0.15)
				)
				(justify left bottom mirror)
			)
		)
		(property "Value" "C_100u_0805"
			(at -2.055717 -1.963152 0)
			(layer "B.Fab")
			(effects
				(font
					(size 0.7 0.7)
					(thickness 0.15)
				)
				(justify left bottom mirror)
			)
		)
		(property "Datasheet" "https://www.murata.com/products/productdetail?partno=GRM21BR60J107ME15%23"
			(at 0 0 180)
			(layer "F.Fab")
			(hide yes)
			(effects
				(font
					(size 1.27 1.27)
					(thickness 0.15)
				)
			)
		)
		(property "MPN" "GRM21BR60J107ME15L"
			(at 0 0 180)
			(unlocked yes)
			(layer "B.Fab")
			(hide yes)
			(effects
				(font
					(size 1 1)
					(thickness 0.15)
				)
				(justify mirror)
			)
		)
		(property "Manufacturer" "Murata"
			(at 0 0 180)
			(unlocked yes)
			(layer "B.Fab")
			(hide yes)
			(effects
				(font
					(size 1 1)
					(thickness 0.15)
				)
				(justify mirror)
			)
		)
		(property "License" "Apache-2.0"
			(at 0 0 180)
			(unlocked yes)
			(layer "B.Fab")
			(hide yes)
			(effects
				(font
					(size 1 1)
					(thickness 0.15)
				)
				(justify mirror)
			)
		)
		(property "Author" "Antmicro"
			(at 0 0 180)
			(unlocked yes)
			(layer "B.Fab")
			(hide yes)
			(effects
				(font
					(size 1 1)
					(thickness 0.15)
				)
				(justify mirror)
			)
		)
		(property "Val" "100u"
			(at 0 0 180)
			(unlocked yes)
			(layer "B.Fab")
			(hide yes)
			(effects
				(font
					(size 1 1)
					(thickness 0.15)
				)
				(justify mirror)
			)
		)
		(property "Voltage" ""
			(at 0 0 180)
			(unlocked yes)
			(layer "B.Fab")
			(hide yes)
			(effects
				(font
					(size 1 1)
					(thickness 0.15)
				)
				(justify mirror)
			)
		)
		(property "Dielectric" ""
			(at 0 0 180)
			(unlocked yes)
			(layer "B.Fab")
			(hide yes)
			(effects
				(font
					(size 1 1)
					(thickness 0.15)
				)
				(justify mirror)
			)
		)
		(property "Public" "False"
			(at 0 0 180)
			(unlocked yes)
			(layer "B.Fab")
			(hide yes)
			(effects
				(font
					(size 1 1)
					(thickness 0.15)
				)
				(justify mirror)
			)
		)
		(sheetname "/FPGA power/")
		(sheetfile "fpga-power.kicad_sch")
		(attr smd)
		(fp_line
			(start -0.3 0.7)
			(end 0.3 0.7)
			(stroke
				(width 0.15)
				(type solid)
			)
			(layer "B.SilkS")
		)
		(fp_line
			(start -0.3 -0.7)
			(end 0.3 -0.7)
			(stroke
				(width 0.15)
				(type solid)
			)
			(layer "B.SilkS")
		)
		(fp_rect
			(start 1.95 0.9)
			(end -1.95 -0.9)
			(stroke
				(width 0.05)
				(type default)
			)
			(fill no)
			(layer "B.CrtYd")
		)
		(fp_rect
			(start -0.95 0.675)
			(end 0.95 -0.675)
			(stroke
				(width 0.15)
				(type solid)
			)
			(fill no)
			(layer "B.Fab")
		)
		(fp_text user "Author: Antmicro"
			(at -1.9 -5.947 0)
			(layer "B.Fab")
			(effects
				(font
					(size 0.7 0.7)
					(thickness 0.15)
				)
				(justify left bottom mirror)
			)
		)
		(fp_text user "License: Apache-2.0"
			(at -1.9 -4.947 0)
			(layer "B.Fab")
			(effects
				(font
					(size 0.7 0.7)
					(thickness 0.15)
				)
				(justify left bottom mirror)
			)
		)
		(fp_text user "${REFERENCE}"
			(at -1.9 -3.947 0)
			(layer "B.Fab")
			(effects
				(font
					(size 0.7 0.7)
					(thickness 0.15)
				)
				(justify left bottom mirror)
			)
		)
		(pad "1" smd roundrect
			(at -1.1 0 180)
			(size 1.2 1.3)
			(layers "B.Cu" "B.Mask" "B.Paste")
			(roundrect_rratio 0.25)
			(net 1 "GND")
			(pintype "passive")
		)
		(pad "2" smd roundrect
			(at 1.1 0 180)
			(size 1.2 1.3)
			(layers "B.Cu" "B.Mask" "B.Paste")
			(roundrect_rratio 0.25)
			(net 553 "+0V85")
			(pintype "passive")
		)
	)
	(footprint "antmicro-footprints:NetTie-2_SMD_Pad0.127mm"
		(layer "B.Cu")
		(at 222.135 176.66 90)
		(descr "Net tie, 2 pin, 0.127mm  SMD pads")
		(tags "net tie")
		(property "Reference" "TP24"
			(at 1.36 -0.085 90)
			(layer "B.SilkS")
			(hide yes)
			(effects
				(font
					(size 0.7 0.7)
					(thickness 0.15)
				)
				(justify right bottom mirror)
			)
		)
		(property "Value" "Net-Tie_P0.127mm"
			(at 0 -1.199 90)
			(layer "B.Fab")
			(effects
				(font
					(size 0.7 0.7)
					(thickness 0.15)
				)
				(justify right bottom mirror)
			)
		)
		(property "MPN" ""
			(at 0 0 90)
			(unlocked yes)
			(layer "B.Fab")
			(hide yes)
			(effects
				(font
					(size 1 1)
					(thickness 0.15)
				)
				(justify mirror)
			)
		)
		(property "Manufacturer" ""
			(at 0 0 90)
			(unlocked yes)
			(layer "B.Fab")
			(hide yes)
			(effects
				(font
					(size 1 1)
					(thickness 0.15)
				)
				(justify mirror)
			)
		)
		(property "Author" "Antmicro"
			(at 0 0 90)
			(unlocked yes)
			(layer "B.Fab")
			(hide yes)
			(effects
				(font
					(size 1 1)
					(thickness 0.15)
				)
				(justify mirror)
			)
		)
		(property "License" "Apache-2.0"
			(at 0 0 90)
			(unlocked yes)
			(layer "B.Fab")
			(hide yes)
			(effects
				(font
					(size 1 1)
					(thickness 0.15)
				)
				(justify mirror)
			)
		)
		(property ki_fp_filters "Net*Tie*")
		(sheetname "/Supply/DC-DC VCCINT/")
		(sheetfile "dc-dc-vccint.kicad_sch")
		(attr through_hole exclude_from_pos_files exclude_from_bom)
		(net_tie_pad_groups "1, 2")
		(fp_poly
			(pts
				(xy -0.0635 0.0635) (xy 0.0625 0.0635) (xy 0.0625 -0.0635) (xy -0.0635 -0.0635)
			)
			(stroke
				(width 0)
				(type solid)
			)
			(fill yes)
			(layer "B.Cu")
		)
		(fp_poly
			(pts
				(xy 0.2 0.16) (xy 0.29 0.07) (xy 0.29 -0.07) (xy 0.2 -0.16) (xy -0.2 -0.16) (xy -0.29 -0.07) (xy -0.29 0.06)
				(xy -0.19 0.16)
			)
			(stroke
				(width 0.05)
				(type solid)
			)
			(fill no)
			(layer "B.CrtYd")
		)
		(fp_text user "${REFERENCE}"
			(at -0.128 -3.2 270)
			(layer "B.Fab")
			(effects
				(font
					(size 0.7 0.7)
					(thickness 0.15)
				)
				(justify left bottom mirror)
			)
		)
		(fp_text user "License: Apache-2.0"
			(at -0.128 -5.6 270)
			(layer "B.Fab")
			(effects
				(font
					(size 0.7 0.7)
					(thickness 0.15)
				)
				(justify left bottom mirror)
			)
		)
		(fp_text user "Author: Antmicro"
			(at -0.128 -4.4 270)
			(layer "B.Fab")
			(effects
				(font
					(size 0.7 0.7)
					(thickness 0.15)
				)
				(justify left bottom mirror)
			)
		)
		(pad "1" smd roundrect
			(at -0.127 0 270)
			(size 0.127 0.127)
			(layers "B.Cu")
			(roundrect_rratio 0.5)
			(chamfer_ratio 0)
			(chamfer top_left bottom_left)
			(net 754 "/Supply/DC-DC VCCINT/VREF+")
			(pinfunction "1")
			(pintype "passive")
		)
		(pad "2" smd roundrect
			(at 0.126 0 90)
			(size 0.127 0.127)
			(layers "B.Cu")
			(roundrect_rratio 0.5)
			(chamfer_ratio 0)
			(chamfer top_left bottom_left)
			(net 553 "+0V85")
			(pinfunction "2")
			(pintype "passive")
		)
	)
	(footprint "antmicro-footprints:R_0402_1005Metric"
		(layer "B.Cu")
		(at 240.675 157.605 -90)
		(descr "Resistor SMD 0402")
		(tags "resistor SMD 0402")
		(property "Reference" "R173"
			(at 0.875 -0.485 90)
			(layer "B.SilkS")
			(effects
				(font
					(size 0.7 0.7)
					(thickness 0.15)
				)
				(justify left bottom mirror)
			)
		)
		(property "Value" "R_47k_0402"
			(at -1.011843 -1.772047 90)
			(layer "B.Fab")
			(effects
				(font
					(size 0.7 0.7)
					(thickness 0.15)
				)
				(justify left bottom mirror)
			)
		)
		(property "Datasheet" "https://www.bourns.com/docs/product-datasheets/cr.pdf"
			(at 0 0 270)
			(layer "F.Fab")
			(hide yes)
			(effects
				(font
					(size 1.27 1.27)
					(thickness 0.15)
				)
			)
		)
		(property "Manufacturer" "Bourns"
			(at 0 0 270)
			(unlocked yes)
			(layer "B.Fab")
			(hide yes)
			(effects
				(font
					(size 1 1)
					(thickness 0.15)
				)
				(justify mirror)
			)
		)
		(property "MPN" "CR0402-FX-4702GLF"
			(at 0 0 270)
			(unlocked yes)
			(layer "B.Fab")
			(hide yes)
			(effects
				(font
					(size 1 1)
					(thickness 0.15)
				)
				(justify mirror)
			)
		)
		(property "Val" "47k"
			(at 0 0 270)
			(unlocked yes)
			(layer "B.Fab")
			(hide yes)
			(effects
				(font
					(size 1 1)
					(thickness 0.15)
				)
				(justify mirror)
			)
		)
		(property "License" "Apache-2.0"
			(at 0 0 270)
			(unlocked yes)
			(layer "B.Fab")
			(hide yes)
			(effects
				(font
					(size 1 1)
					(thickness 0.15)
				)
				(justify mirror)
			)
		)
		(property "Author" "Antmicro"
			(at 0 0 270)
			(unlocked yes)
			(layer "B.Fab")
			(hide yes)
			(effects
				(font
					(size 1 1)
					(thickness 0.15)
				)
				(justify mirror)
			)
		)
		(property "Tolerance" "1%"
			(at 0 0 270)
			(unlocked yes)
			(layer "B.Fab")
			(hide yes)
			(effects
				(font
					(size 1 1)
					(thickness 0.15)
				)
				(justify mirror)
			)
		)
		(sheetname "/Supply/DC-DC IO/")
		(sheetfile "dc-dc-io.kicad_sch")
		(attr smd)
		(fp_rect
			(start -0.925 0.47)
			(end 0.925 -0.47)
			(stroke
				(width 0.05)
				(type default)
			)
			(fill no)
			(layer "B.CrtYd")
		)
		(fp_rect
			(start -0.5 0.25)
			(end 0.5 -0.25)
			(stroke
				(width 0.15)
				(type solid)
			)
			(fill no)
			(layer "B.Fab")
		)
		(fp_text user "${REFERENCE}"
			(at -0.95 -3.168 90)
			(layer "B.Fab")
			(effects
				(font
					(size 0.7 0.7)
					(thickness 0.15)
				)
				(justify left bottom mirror)
			)
		)
		(fp_text user "Author: Antmicro"
			(at -0.95 -4.169 90)
			(layer "B.Fab")
			(effects
				(font
					(size 0.7 0.7)
					(thickness 0.15)
				)
				(justify left bottom mirror)
			)
		)
		(fp_text user "License: Apache-2.0"
			(at -0.95 -5.169 90)
			(layer "B.Fab")
			(effects
				(font
					(size 0.7 0.7)
					(thickness 0.15)
				)
				(justify left bottom mirror)
			)
		)
		(pad "1" smd roundrect
			(at -0.48 0 270)
			(size 0.59 0.64)
			(layers "B.Cu" "B.Mask" "B.Paste")
			(roundrect_rratio 0.25)
			(net 720 "Net-(U28-~{PWRDN})")
			(pintype "passive")
		)
		(pad "2" smd roundrect
			(at 0.48 0 270)
			(size 0.59 0.64)
			(layers "B.Cu" "B.Mask" "B.Paste")
			(roundrect_rratio 0.25)
			(net 38 "+3V3_AON")
			(pintype "passive")
		)
	)
	(footprint "antmicro-footprints:C_0402_1005Metric"
		(layer "B.Cu")
		(at 148.275 193.875 180)
		(descr "Capacitor SMD 0402")
		(tags "capacitor SMD 0402")
		(property "Reference" "C170"
			(at -4.035 -0.525 0)
			(layer "B.SilkS")
			(effects
				(font
					(size 0.7 0.7)
					(thickness 0.15)
				)
				(justify left bottom mirror)
			)
		)
		(property "Value" "C_100n_0402"
			(at -1.022927 -2.155213 0)
			(layer "B.Fab")
			(effects
				(font
					(size 0.7 0.7)
					(thickness 0.15)
				)
				(justify left bottom mirror)
			)
		)
		(property "Datasheet" "https://www.murata.com/products/productdetail?partno=GRM155R61H104KE14%23"
			(at 0 0 180)
			(layer "F.Fab")
			(hide yes)
			(effects
				(font
					(size 1.27 1.27)
					(thickness 0.15)
				)
			)
		)
		(property "Manufacturer" "Murata"
			(at 0 0 180)
			(unlocked yes)
			(layer "B.Fab")
			(hide yes)
			(effects
				(font
					(size 1 1)
					(thickness 0.15)
				)
				(justify mirror)
			)
		)
		(property "MPN" "GRM155R61H104KE14D"
			(at 0 0 180)
			(unlocked yes)
			(layer "B.Fab")
			(hide yes)
			(effects
				(font
					(size 1 1)
					(thickness 0.15)
				)
				(justify mirror)
			)
		)
		(property "Val" "100n"
			(at 0 0 180)
			(unlocked yes)
			(layer "B.Fab")
			(hide yes)
			(effects
				(font
					(size 1 1)
					(thickness 0.15)
				)
				(justify mirror)
			)
		)
		(property "License" "Apache-2.0"
			(at 0 0 180)
			(unlocked yes)
			(layer "B.Fab")
			(hide yes)
			(effects
				(font
					(size 1 1)
					(thickness 0.15)
				)
				(justify mirror)
			)
		)
		(property "Author" "Antmicro"
			(at 0 0 180)
			(unlocked yes)
			(layer "B.Fab")
			(hide yes)
			(effects
				(font
					(size 1 1)
					(thickness 0.15)
				)
				(justify mirror)
			)
		)
		(property "Voltage" "50V"
			(at 0 0 180)
			(unlocked yes)
			(layer "B.Fab")
			(hide yes)
			(effects
				(font
					(size 1 1)
					(thickness 0.15)
				)
				(justify mirror)
			)
		)
		(property "Dielectric" "X5R"
			(at 0 0 180)
			(unlocked yes)
			(layer "B.Fab")
			(hide yes)
			(effects
				(font
					(size 1 1)
					(thickness 0.15)
				)
				(justify mirror)
			)
		)
		(sheetname "/Supply/")
		(sheetfile "supply.kicad_sch")
		(attr smd)
		(fp_rect
			(start -0.925 0.47)
			(end 0.925 -0.47)
			(stroke
				(width 0.05)
				(type default)
			)
			(fill no)
			(layer "B.CrtYd")
		)
		(fp_line
			(start 0.504 0.25)
			(end 0.504 -0.248)
			(stroke
				(width 0.15)
				(type solid)
			)
			(layer "B.Fab")
		)
		(fp_line
			(start 0.504 -0.248)
			(end -0.494 -0.248)
			(stroke
				(width 0.15)
				(type solid)
			)
			(layer "B.Fab")
		)
		(fp_line
			(start -0.494 0.25)
			(end 0.504 0.25)
			(stroke
				(width 0.15)
				(type solid)
			)
			(layer "B.Fab")
		)
		(fp_line
			(start -0.494 -0.248)
			(end -0.494 0.25)
			(stroke
				(width 0.15)
				(type solid)
			)
			(layer "B.Fab")
		)
		(fp_text user "${REFERENCE}"
			(at -0.939 -4.599 0)
			(layer "B.Fab")
			(effects
				(font
					(size 0.7 0.7)
					(thickness 0.15)
				)
				(justify left bottom mirror)
			)
		)
		(fp_text user "Author: Antmicro"
			(at -0.939 -3.399 0)
			(layer "B.Fab")
			(effects
				(font
					(size 0.7 0.7)
					(thickness 0.15)
				)
				(justify left bottom mirror)
			)
		)
		(fp_text user "License: Apache-2.0"
			(at -0.939 -5.799 0)
			(layer "B.Fab")
			(effects
				(font
					(size 0.7 0.7)
					(thickness 0.15)
				)
				(justify left bottom mirror)
			)
		)
		(pad "1" smd roundrect
			(at -0.48 0 180)
			(size 0.59 0.64)
			(layers "B.Cu" "B.Mask" "B.Paste")
			(roundrect_rratio 0.25)
			(net 1 "GND")
			(pintype "passive")
		)
		(pad "2" smd roundrect
			(at 0.48 0 180)
			(size 0.59 0.64)
			(layers "B.Cu" "B.Mask" "B.Paste")
			(roundrect_rratio 0.25)
			(net 10 "+12V")
			(pintype "passive")
		)
	)
	(footprint "antmicro-footprints:R_0402_1005Metric"
		(layer "B.Cu")
		(at 242.97 132.855 -90)
		(descr "Resistor SMD 0402")
		(tags "resistor SMD 0402")
		(property "Reference" "R122"
			(at -3.855 -0.33 90)
			(layer "B.SilkS")
			(effects
				(font
					(size 0.7 0.7)
					(thickness 0.15)
				)
				(justify left bottom mirror)
			)
		)
		(property "Value" "R_4k7_0402"
			(at -2.4 -0.65 90)
			(layer "B.Fab")
			(effects
				(font
					(size 0.7 0.7)
					(thickness 0.15)
				)
				(justify left bottom mirror)
			)
		)
		(property "Datasheet" "https://www.bourns.com/docs/product-datasheets/cr.pdf"
			(at 0 0 270)
			(layer "F.Fab")
			(hide yes)
			(effects
				(font
					(size 1.27 1.27)
					(thickness 0.15)
				)
			)
		)
		(property "Manufacturer" "Bourns"
			(at 0 0 270)
			(unlocked yes)
			(layer "B.Fab")
			(hide yes)
			(effects
				(font
					(size 1 1)
					(thickness 0.15)
				)
				(justify mirror)
			)
		)
		(property "MPN" "CR0402-FX-4701GLF"
			(at 0 0 270)
			(unlocked yes)
			(layer "B.Fab")
			(hide yes)
			(effects
				(font
					(size 1 1)
					(thickness 0.15)
				)
				(justify mirror)
			)
		)
		(property "Val" "4k7"
			(at 0 0 270)
			(unlocked yes)
			(layer "B.Fab")
			(hide yes)
			(effects
				(font
					(size 1 1)
					(thickness 0.15)
				)
				(justify mirror)
			)
		)
		(property "License" "Apache-2.0"
			(at 0 0 270)
			(unlocked yes)
			(layer "B.Fab")
			(hide yes)
			(effects
				(font
					(size 1 1)
					(thickness 0.15)
				)
				(justify mirror)
			)
		)
		(property "Author" "Antmicro"
			(at 0 0 270)
			(unlocked yes)
			(layer "B.Fab")
			(hide yes)
			(effects
				(font
					(size 1 1)
					(thickness 0.15)
				)
				(justify mirror)
			)
		)
		(property "Tolerance" "1%"
			(at 0 0 270)
			(unlocked yes)
			(layer "B.Fab")
			(hide yes)
			(effects
				(font
					(size 1 1)
					(thickness 0.15)
				)
				(justify mirror)
			)
		)
		(sheetname "/I^{2}C + I3C/")
		(sheetfile "i2c.kicad_sch")
		(attr smd)
		(fp_rect
			(start -0.925 0.47)
			(end 0.925 -0.47)
			(stroke
				(width 0.05)
				(type default)
			)
			(fill no)
			(layer "B.CrtYd")
		)
		(fp_rect
			(start -0.5 0.25)
			(end 0.5 -0.25)
			(stroke
				(width 0.15)
				(type solid)
			)
			(fill no)
			(layer "B.Fab")
		)
		(fp_text user "License: Apache-2.0"
			(at -0.95 -5.169 90)
			(layer "B.Fab")
			(effects
				(font
					(size 0.7 0.7)
					(thickness 0.15)
				)
				(justify left bottom mirror)
			)
		)
		(fp_text user "Author: Antmicro"
			(at -0.95 -4.169 90)
			(layer "B.Fab")
			(effects
				(font
					(size 0.7 0.7)
					(thickness 0.15)
				)
				(justify left bottom mirror)
			)
		)
		(fp_text user "${REFERENCE}"
			(at -0.95 -3.168 90)
			(layer "B.Fab")
			(effects
				(font
					(size 0.7 0.7)
					(thickness 0.15)
				)
				(justify left bottom mirror)
			)
		)
		(pad "1" smd roundrect
			(at -0.48 0 270)
			(size 0.59 0.64)
			(layers "B.Cu" "B.Mask" "B.Paste")
			(roundrect_rratio 0.25)
			(net 151 "+3V3")
			(pintype "passive")
		)
		(pad "2" smd roundrect
			(at 0.48 0 270)
			(size 0.59 0.64)
			(layers "B.Cu" "B.Mask" "B.Paste")
			(roundrect_rratio 0.25)
			(net 465 "/FPGA banks HD/FPGA_DDR.SCL")
			(pintype "passive")
		)
	)
	(footprint "antmicro-footprints:R_0402_1005Metric"
		(layer "B.Cu")
		(at 260.5055 158.671 90)
		(descr "Resistor SMD 0402")
		(tags "resistor SMD 0402")
		(property "Reference" "R169"
			(at -3.729 0.4445 90)
			(layer "B.SilkS")
			(effects
				(font
					(size 0.7 0.7)
					(thickness 0.15)
				)
				(justify right bottom mirror)
			)
		)
		(property "Value" "R_0R_0402"
			(at -1.011843 -1.772047 90)
			(layer "B.Fab")
			(effects
				(font
					(size 0.7 0.7)
					(thickness 0.15)
				)
				(justify right bottom mirror)
			)
		)
		(property "Datasheet" "https://industrial.panasonic.com/cdbs/www-data/pdf/RDA0000/AOA0000C301.pdf"
			(at 0 0 90)
			(layer "F.Fab")
			(hide yes)
			(effects
				(font
					(size 1.27 1.27)
					(thickness 0.15)
				)
			)
		)
		(property "Manufacturer" "Panasonic"
			(at 0 0 90)
			(unlocked yes)
			(layer "B.Fab")
			(hide yes)
			(effects
				(font
					(size 1 1)
					(thickness 0.15)
				)
				(justify mirror)
			)
		)
		(property "MPN" "ERJ2GE0R00X"
			(at 0 0 90)
			(unlocked yes)
			(layer "B.Fab")
			(hide yes)
			(effects
				(font
					(size 1 1)
					(thickness 0.15)
				)
				(justify mirror)
			)
		)
		(property "Val" "0R"
			(at 0 0 90)
			(unlocked yes)
			(layer "B.Fab")
			(hide yes)
			(effects
				(font
					(size 1 1)
					(thickness 0.15)
				)
				(justify mirror)
			)
		)
		(property "License" "Apache-2.0"
			(at 0 0 90)
			(unlocked yes)
			(layer "B.Fab")
			(hide yes)
			(effects
				(font
					(size 1 1)
					(thickness 0.15)
				)
				(justify mirror)
			)
		)
		(property "Author" "Antmicro"
			(at 0 0 90)
			(unlocked yes)
			(layer "B.Fab")
			(hide yes)
			(effects
				(font
					(size 1 1)
					(thickness 0.15)
				)
				(justify mirror)
			)
		)
		(property "Tolerance" "~"
			(at 0 0 90)
			(unlocked yes)
			(layer "B.Fab")
			(hide yes)
			(effects
				(font
					(size 1 1)
					(thickness 0.15)
				)
				(justify mirror)
			)
		)
		(property "Current" "1A"
			(at 0 0 90)
			(unlocked yes)
			(layer "B.Fab")
			(hide yes)
			(effects
				(font
					(size 1 1)
					(thickness 0.15)
				)
				(justify mirror)
			)
		)
		(sheetname "/Supply/DC-DC IO/")
		(sheetfile "dc-dc-io.kicad_sch")
		(attr smd exclude_from_bom dnp)
		(fp_rect
			(start -0.925 0.47)
			(end 0.925 -0.47)
			(stroke
				(width 0.05)
				(type default)
			)
			(fill no)
			(layer "B.CrtYd")
		)
		(fp_rect
			(start -0.5 0.25)
			(end 0.5 -0.25)
			(stroke
				(width 0.15)
				(type solid)
			)
			(fill no)
			(layer "B.Fab")
		)
		(fp_text user "${REFERENCE}"
			(at -0.95 -3.168 270)
			(layer "B.Fab")
			(effects
				(font
					(size 0.7 0.7)
					(thickness 0.15)
				)
				(justify left bottom mirror)
			)
		)
		(fp_text user "Author: Antmicro"
			(at -0.95 -4.169 270)
			(layer "B.Fab")
			(effects
				(font
					(size 0.7 0.7)
					(thickness 0.15)
				)
				(justify left bottom mirror)
			)
		)
		(fp_text user "License: Apache-2.0"
			(at -0.95 -5.169 270)
			(layer "B.Fab")
			(effects
				(font
					(size 0.7 0.7)
					(thickness 0.15)
				)
				(justify left bottom mirror)
			)
		)
		(pad "1" smd roundrect
			(at -0.48 0 90)
			(size 0.59 0.64)
			(layers "B.Cu" "B.Mask" "B.Paste")
			(roundrect_rratio 0.25)
			(net 1 "GND")
			(pintype "passive")
		)
		(pad "2" smd roundrect
			(at 0.48 0 90)
			(size 0.59 0.64)
			(layers "B.Cu" "B.Mask" "B.Paste")
			(roundrect_rratio 0.25)
			(net 719 "/Supply/DC-DC IO/FB8")
			(pintype "passive")
		)
	)
	(footprint "antmicro-footprints:C_0402_1005Metric_EIA"
		(layer "B.Cu")
		(at 200.498 155 180)
		(descr "Capacitor SMD 0402 (1005 Metric), square (rectangular) end terminal, IPC_7351 nominal, (Body size source: IPC-SM-782 page 76, https://www.pcb-3d.com/wordpress/wp-content/uploads/ipc-sm-782a_amendment_1_and_2.pdf)")
		(tags "capacitor 0402")
		(property "Reference" "C15"
			(at -1.177 -1.425 0)
			(layer "B.SilkS")
			(effects
				(font
					(size 0.7 0.7)
					(thickness 0.15)
				)
				(justify left bottom mirror)
			)
		)
		(property "Value" "C_100n_0402"
			(at 0 -1.169 0)
			(layer "B.Fab")
			(effects
				(font
					(size 0.7 0.7)
					(thickness 0.15)
				)
				(justify left bottom mirror)
			)
		)
		(property "Datasheet" "https://www.murata.com/products/productdetail?partno=GRM155R61H104KE14%23"
			(at 0 0 180)
			(layer "F.Fab")
			(hide yes)
			(effects
				(font
					(size 1.27 1.27)
					(thickness 0.15)
				)
			)
		)
		(property "MPN" "GRM155R61H104KE14D"
			(at 0 0 180)
			(unlocked yes)
			(layer "B.Fab")
			(hide yes)
			(effects
				(font
					(size 1 1)
					(thickness 0.15)
				)
				(justify mirror)
			)
		)
		(property "Manufacturer" "Murata"
			(at 0 0 180)
			(unlocked yes)
			(layer "B.Fab")
			(hide yes)
			(effects
				(font
					(size 1 1)
					(thickness 0.15)
				)
				(justify mirror)
			)
		)
		(property "License" "Apache-2.0"
			(at 0 0 180)
			(unlocked yes)
			(layer "B.Fab")
			(hide yes)
			(effects
				(font
					(size 1 1)
					(thickness 0.15)
				)
				(justify mirror)
			)
		)
		(property "Author" "Antmicro"
			(at 0 0 180)
			(unlocked yes)
			(layer "B.Fab")
			(hide yes)
			(effects
				(font
					(size 1 1)
					(thickness 0.15)
				)
				(justify mirror)
			)
		)
		(property "Val" "100n"
			(at 0 0 180)
			(unlocked yes)
			(layer "B.Fab")
			(hide yes)
			(effects
				(font
					(size 1 1)
					(thickness 0.15)
				)
				(justify mirror)
			)
		)
		(property "Voltage" "50V"
			(at 0 0 180)
			(unlocked yes)
			(layer "B.Fab")
			(hide yes)
			(effects
				(font
					(size 1 1)
					(thickness 0.15)
				)
				(justify mirror)
			)
		)
		(property "Dielectric" "X5R"
			(at 0 0 180)
			(unlocked yes)
			(layer "B.Fab")
			(hide yes)
			(effects
				(font
					(size 1 1)
					(thickness 0.15)
				)
				(justify mirror)
			)
		)
		(sheetname "/FPGA power/")
		(sheetfile "fpga-power.kicad_sch")
		(attr smd)
		(fp_rect
			(start -0.95 0.45)
			(end 0.95 -0.45)
			(stroke
				(width 0.05)
				(type default)
			)
			(fill no)
			(layer "B.CrtYd")
		)
		(fp_line
			(start 0.498 0.25)
			(end 0.498 -0.248)
			(stroke
				(width 0.15)
				(type solid)
			)
			(layer "B.Fab")
		)
		(fp_line
			(start 0.498 -0.248)
			(end -0.5 -0.248)
			(stroke
				(width 0.15)
				(type solid)
			)
			(layer "B.Fab")
		)
		(fp_line
			(start -0.5 0.25)
			(end 0.498 0.25)
			(stroke
				(width 0.15)
				(type solid)
			)
			(layer "B.Fab")
		)
		(fp_line
			(start -0.5 -0.248)
			(end -0.5 0.25)
			(stroke
				(width 0.15)
				(type solid)
			)
			(layer "B.Fab")
		)
		(fp_text user "License: Apache-2.0"
			(at -0.9656 -4.369 0)
			(layer "B.Fab")
			(effects
				(font
					(size 0.7 0.7)
					(thickness 0.15)
				)
				(justify left bottom mirror)
			)
		)
		(fp_text user "${REFERENCE}"
			(at -0.9656 -3.169 0)
			(layer "B.Fab")
			(effects
				(font
					(size 0.7 0.7)
					(thickness 0.15)
				)
				(justify left bottom mirror)
			)
		)
		(fp_text user "Author: Antmicro"
			(at -0.9656 -5.569 0)
			(layer "B.Fab")
			(effects
				(font
					(size 0.7 0.7)
					(thickness 0.15)
				)
				(justify left bottom mirror)
			)
		)
		(pad "1" smd roundrect
			(at -0.5 0 90)
			(size 0.6 0.6)
			(layers "B.Cu" "B.Mask" "B.Paste")
			(roundrect_rratio 0.25)
			(net 1 "GND")
			(pintype "passive")
		)
		(pad "2" smd roundrect
			(at 0.498 0 180)
			(size 0.6 0.6)
			(layers "B.Cu" "B.Mask" "B.Paste")
			(roundrect_rratio 0.25)
			(net 797 "+1V8")
			(pintype "passive")
		)
	)
	(footprint "antmicro-footprints:C_0402_1005Metric_EIA"
		(layer "B.Cu")
		(at 187 150.5 -90)
		(descr "Capacitor SMD 0402 (1005 Metric), square (rectangular) end terminal, IPC_7351 nominal, (Body size source: IPC-SM-782 page 76, https://www.pcb-3d.com/wordpress/wp-content/uploads/ipc-sm-782a_amendment_1_and_2.pdf)")
		(tags "capacitor 0402")
		(property "Reference" "C81"
			(at -11.525 30.625 90)
			(layer "B.SilkS")
			(effects
				(font
					(size 0.7 0.7)
					(thickness 0.15)
				)
				(justify left bottom mirror)
			)
		)
		(property "Value" "C_1u_25V_0402"
			(at 0 -1.169 90)
			(layer "B.Fab")
			(effects
				(font
					(size 0.7 0.7)
					(thickness 0.15)
				)
				(justify left bottom mirror)
			)
		)
		(property "Datasheet" "https://www.murata.com/products/productdetail?partno=GRM155R61E105KE11%23"
			(at 0 0 270)
			(layer "F.Fab")
			(hide yes)
			(effects
				(font
					(size 1.27 1.27)
					(thickness 0.15)
				)
			)
		)
		(property "MPN" "GRM155R61E105KE11J"
			(at 0 0 270)
			(unlocked yes)
			(layer "B.Fab")
			(hide yes)
			(effects
				(font
					(size 1 1)
					(thickness 0.15)
				)
				(justify mirror)
			)
		)
		(property "Manufacturer" "Murata"
			(at 0 0 270)
			(unlocked yes)
			(layer "B.Fab")
			(hide yes)
			(effects
				(font
					(size 1 1)
					(thickness 0.15)
				)
				(justify mirror)
			)
		)
		(property "License" "Apache-2.0"
			(at 0 0 270)
			(unlocked yes)
			(layer "B.Fab")
			(hide yes)
			(effects
				(font
					(size 1 1)
					(thickness 0.15)
				)
				(justify mirror)
			)
		)
		(property "Author" "Antmicro"
			(at 0 0 270)
			(unlocked yes)
			(layer "B.Fab")
			(hide yes)
			(effects
				(font
					(size 1 1)
					(thickness 0.15)
				)
				(justify mirror)
			)
		)
		(property "Val" "1u"
			(at 0 0 270)
			(unlocked yes)
			(layer "B.Fab")
			(hide yes)
			(effects
				(font
					(size 1 1)
					(thickness 0.15)
				)
				(justify mirror)
			)
		)
		(property "Voltage" "25V"
			(at 0 0 270)
			(unlocked yes)
			(layer "B.Fab")
			(hide yes)
			(effects
				(font
					(size 1 1)
					(thickness 0.15)
				)
				(justify mirror)
			)
		)
		(property "Dielectric" "X5R"
			(at 0 0 270)
			(unlocked yes)
			(layer "B.Fab")
			(hide yes)
			(effects
				(font
					(size 1 1)
					(thickness 0.15)
				)
				(justify mirror)
			)
		)
		(sheetname "/FPGA power/")
		(sheetfile "fpga-power.kicad_sch")
		(attr smd)
		(fp_rect
			(start -0.95 0.45)
			(end 0.95 -0.45)
			(stroke
				(width 0.05)
				(type default)
			)
			(fill no)
			(layer "B.CrtYd")
		)
		(fp_line
			(start -0.5 0.25)
			(end 0.498 0.25)
			(stroke
				(width 0.15)
				(type solid)
			)
			(layer "B.Fab")
		)
		(fp_line
			(start 0.498 0.25)
			(end 0.498 -0.248)
			(stroke
				(width 0.15)
				(type solid)
			)
			(layer "B.Fab")
		)
		(fp_line
			(start -0.5 -0.248)
			(end -0.5 0.25)
			(stroke
				(width 0.15)
				(type solid)
			)
			(layer "B.Fab")
		)
		(fp_line
			(start 0.498 -0.248)
			(end -0.5 -0.248)
			(stroke
				(width 0.15)
				(type solid)
			)
			(layer "B.Fab")
		)
		(fp_text user "License: Apache-2.0"
			(at -0.9656 -4.369 90)
			(layer "B.Fab")
			(effects
				(font
					(size 0.7 0.7)
					(thickness 0.15)
				)
				(justify left bottom mirror)
			)
		)
		(fp_text user "${REFERENCE}"
			(at -0.9656 -3.169 90)
			(layer "B.Fab")
			(effects
				(font
					(size 0.7 0.7)
					(thickness 0.15)
				)
				(justify left bottom mirror)
			)
		)
		(fp_text user "Author: Antmicro"
			(at -0.9656 -5.569 90)
			(layer "B.Fab")
			(effects
				(font
					(size 0.7 0.7)
					(thickness 0.15)
				)
				(justify left bottom mirror)
			)
		)
		(pad "1" smd roundrect
			(at -0.5 0 180)
			(size 0.6 0.6)
			(layers "B.Cu" "B.Mask" "B.Paste")
			(roundrect_rratio 0.25)
			(net 1 "GND")
			(pintype "passive")
		)
		(pad "2" smd roundrect
			(at 0.498 0 270)
			(size 0.6 0.6)
			(layers "B.Cu" "B.Mask" "B.Paste")
			(roundrect_rratio 0.25)
			(net 797 "+1V8")
			(pintype "passive")
		)
	)
	(footprint "antmicro-footprints:C_0402_1005Metric"
		(layer "B.Cu")
		(at 183.49 167.45 90)
		(descr "Capacitor SMD 0402")
		(tags "capacitor SMD 0402")
		(property "Reference" "C293"
			(at -4 0.115999 90)
			(layer "B.SilkS")
			(effects
				(font
					(size 0.7 0.7)
					(thickness 0.15)
				)
				(justify right bottom mirror)
			)
		)
		(property "Value" "C_100n_0402"
			(at -1.022927 -2.155213 90)
			(layer "B.Fab")
			(effects
				(font
					(size 0.7 0.7)
					(thickness 0.15)
				)
				(justify right bottom mirror)
			)
		)
		(property "Datasheet" "https://www.murata.com/products/productdetail?partno=GRM155R61H104KE14%23"
			(at 0 0 90)
			(layer "F.Fab")
			(hide yes)
			(effects
				(font
					(size 1.27 1.27)
					(thickness 0.15)
				)
			)
		)
		(property "Manufacturer" "Murata"
			(at 0 0 90)
			(unlocked yes)
			(layer "B.Fab")
			(hide yes)
			(effects
				(font
					(size 1 1)
					(thickness 0.15)
				)
				(justify mirror)
			)
		)
		(property "MPN" "GRM155R61H104KE14D"
			(at 0 0 90)
			(unlocked yes)
			(layer "B.Fab")
			(hide yes)
			(effects
				(font
					(size 1 1)
					(thickness 0.15)
				)
				(justify mirror)
			)
		)
		(property "Val" "100n"
			(at 0 0 90)
			(unlocked yes)
			(layer "B.Fab")
			(hide yes)
			(effects
				(font
					(size 1 1)
					(thickness 0.15)
				)
				(justify mirror)
			)
		)
		(property "License" "Apache-2.0"
			(at 0 0 90)
			(unlocked yes)
			(layer "B.Fab")
			(hide yes)
			(effects
				(font
					(size 1 1)
					(thickness 0.15)
				)
				(justify mirror)
			)
		)
		(property "Author" "Antmicro"
			(at 0 0 90)
			(unlocked yes)
			(layer "B.Fab")
			(hide yes)
			(effects
				(font
					(size 1 1)
					(thickness 0.15)
				)
				(justify mirror)
			)
		)
		(property "Voltage" "50V"
			(at 0 0 90)
			(unlocked yes)
			(layer "B.Fab")
			(hide yes)
			(effects
				(font
					(size 1 1)
					(thickness 0.15)
				)
				(justify mirror)
			)
		)
		(property "Dielectric" "X5R"
			(at 0 0 90)
			(unlocked yes)
			(layer "B.Fab")
			(hide yes)
			(effects
				(font
					(size 1 1)
					(thickness 0.15)
				)
				(justify mirror)
			)
		)
		(sheetname "/FPGA MGT Interface/")
		(sheetfile "fpga-mgt.kicad_sch")
		(attr smd)
		(fp_rect
			(start -0.925 0.47)
			(end 0.925 -0.47)
			(stroke
				(width 0.05)
				(type default)
			)
			(fill no)
			(layer "B.CrtYd")
		)
		(fp_line
			(start 0.504 -0.248)
			(end -0.494 -0.248)
			(stroke
				(width 0.15)
				(type solid)
			)
			(layer "B.Fab")
		)
		(fp_line
			(start -0.494 -0.248)
			(end -0.494 0.25)
			(stroke
				(width 0.15)
				(type solid)
			)
			(layer "B.Fab")
		)
		(fp_line
			(start 0.504 0.25)
			(end 0.504 -0.248)
			(stroke
				(width 0.15)
				(type solid)
			)
			(layer "B.Fab")
		)
		(fp_line
			(start -0.494 0.25)
			(end 0.504 0.25)
			(stroke
				(width 0.15)
				(type solid)
			)
			(layer "B.Fab")
		)
		(fp_text user "${REFERENCE}"
			(at -0.939 -4.599 270)
			(layer "B.Fab")
			(effects
				(font
					(size 0.7 0.7)
					(thickness 0.15)
				)
				(justify left bottom mirror)
			)
		)
		(fp_text user "Author: Antmicro"
			(at -0.939 -3.399 270)
			(layer "B.Fab")
			(effects
				(font
					(size 0.7 0.7)
					(thickness 0.15)
				)
				(justify left bottom mirror)
			)
		)
		(fp_text user "License: Apache-2.0"
			(at -0.939 -5.799 270)
			(layer "B.Fab")
			(effects
				(font
					(size 0.7 0.7)
					(thickness 0.15)
				)
				(justify left bottom mirror)
			)
		)
		(pad "1" smd roundrect
			(at -0.48 0 90)
			(size 0.59 0.64)
			(layers "B.Cu" "B.Mask" "B.Paste")
			(roundrect_rratio 0.25)
			(net 295 "/FPGA MGT Interface/HDMI_OUT.D2_N")
			(pintype "passive")
		)
		(pad "2" smd roundrect
			(at 0.48 0 90)
			(size 0.59 0.64)
			(layers "B.Cu" "B.Mask" "B.Paste")
			(roundrect_rratio 0.25)
			(net 627 "/FPGA MGT Interface/HDMI_FPGA.TX2_N")
			(pintype "passive")
		)
	)
	(footprint "antmicro-footprints:R_0402_1005Metric"
		(layer "B.Cu")
		(at 240.12 170.425 180)
		(descr "Resistor SMD 0402")
		(tags "resistor SMD 0402")
		(property "Reference" "R210"
			(at -4.505 -0.425 0)
			(layer "B.SilkS")
			(effects
				(font
					(size 0.7 0.7)
					(thickness 0.15)
				)
				(justify left bottom mirror)
			)
		)
		(property "Value" "R_47k_0402"
			(at -1.011843 -1.772047 0)
			(layer "B.Fab")
			(effects
				(font
					(size 0.7 0.7)
					(thickness 0.15)
				)
				(justify left bottom mirror)
			)
		)
		(property "Datasheet" "https://www.bourns.com/docs/product-datasheets/cr.pdf"
			(at 0 0 180)
			(layer "F.Fab")
			(hide yes)
			(effects
				(font
					(size 1.27 1.27)
					(thickness 0.15)
				)
			)
		)
		(property "Manufacturer" "Bourns"
			(at 0 0 180)
			(unlocked yes)
			(layer "B.Fab")
			(hide yes)
			(effects
				(font
					(size 1 1)
					(thickness 0.15)
				)
				(justify mirror)
			)
		)
		(property "MPN" "CR0402-FX-4702GLF"
			(at 0 0 180)
			(unlocked yes)
			(layer "B.Fab")
			(hide yes)
			(effects
				(font
					(size 1 1)
					(thickness 0.15)
				)
				(justify mirror)
			)
		)
		(property "Val" "47k"
			(at 0 0 180)
			(unlocked yes)
			(layer "B.Fab")
			(hide yes)
			(effects
				(font
					(size 1 1)
					(thickness 0.15)
				)
				(justify mirror)
			)
		)
		(property "License" "Apache-2.0"
			(at 0 0 180)
			(unlocked yes)
			(layer "B.Fab")
			(hide yes)
			(effects
				(font
					(size 1 1)
					(thickness 0.15)
				)
				(justify mirror)
			)
		)
		(property "Author" "Antmicro"
			(at 0 0 180)
			(unlocked yes)
			(layer "B.Fab")
			(hide yes)
			(effects
				(font
					(size 1 1)
					(thickness 0.15)
				)
				(justify mirror)
			)
		)
		(property "Tolerance" "1%"
			(at 0 0 180)
			(unlocked yes)
			(layer "B.Fab")
			(hide yes)
			(effects
				(font
					(size 1 1)
					(thickness 0.15)
				)
				(justify mirror)
			)
		)
		(sheetname "/Supply/DC-DC AUX, MGT/")
		(sheetfile "dc-dc-aux-mgt.kicad_sch")
		(attr smd)
		(fp_rect
			(start -0.925 0.47)
			(end 0.925 -0.47)
			(stroke
				(width 0.05)
				(type default)
			)
			(fill no)
			(layer "B.CrtYd")
		)
		(fp_rect
			(start -0.5 0.25)
			(end 0.5 -0.25)
			(stroke
				(width 0.15)
				(type solid)
			)
			(fill no)
			(layer "B.Fab")
		)
		(fp_text user "${REFERENCE}"
			(at -0.95 -3.168 0)
			(layer "B.Fab")
			(effects
				(font
					(size 0.7 0.7)
					(thickness 0.15)
				)
				(justify left bottom mirror)
			)
		)
		(fp_text user "License: Apache-2.0"
			(at -0.95 -5.169 0)
			(layer "B.Fab")
			(effects
				(font
					(size 0.7 0.7)
					(thickness 0.15)
				)
				(justify left bottom mirror)
			)
		)
		(fp_text user "Author: Antmicro"
			(at -0.95 -4.169 0)
			(layer "B.Fab")
			(effects
				(font
					(size 0.7 0.7)
					(thickness 0.15)
				)
				(justify left bottom mirror)
			)
		)
		(pad "1" smd roundrect
			(at -0.48 0 180)
			(size 0.59 0.64)
			(layers "B.Cu" "B.Mask" "B.Paste")
			(roundrect_rratio 0.25)
			(net 731 "Net-(U25-~{ALERT})")
			(pintype "passive")
		)
		(pad "2" smd roundrect
			(at 0.48 0 180)
			(size 0.59 0.64)
			(layers "B.Cu" "B.Mask" "B.Paste")
			(roundrect_rratio 0.25)
			(net 38 "+3V3_AON")
			(pintype "passive")
		)
	)
	(footprint "antmicro-footprints:C_0402_1005Metric_EIA"
		(layer "B.Cu")
		(at 190 150.5 -90)
		(descr "Capacitor SMD 0402 (1005 Metric), square (rectangular) end terminal, IPC_7351 nominal, (Body size source: IPC-SM-782 page 76, https://www.pcb-3d.com/wordpress/wp-content/uploads/ipc-sm-782a_amendment_1_and_2.pdf)")
		(tags "capacitor 0402")
		(property "Reference" "C86"
			(at -11.975 30.675 90)
			(layer "B.SilkS")
			(effects
				(font
					(size 0.7 0.7)
					(thickness 0.15)
				)
				(justify left bottom mirror)
			)
		)
		(property "Value" "C_1u_25V_0402"
			(at 0 -1.169 90)
			(layer "B.Fab")
			(effects
				(font
					(size 0.7 0.7)
					(thickness 0.15)
				)
				(justify left bottom mirror)
			)
		)
		(property "Datasheet" "https://www.murata.com/products/productdetail?partno=GRM155R61E105KE11%23"
			(at 0 0 270)
			(layer "F.Fab")
			(hide yes)
			(effects
				(font
					(size 1.27 1.27)
					(thickness 0.15)
				)
			)
		)
		(property "MPN" "GRM155R61E105KE11J"
			(at 0 0 270)
			(unlocked yes)
			(layer "B.Fab")
			(hide yes)
			(effects
				(font
					(size 1 1)
					(thickness 0.15)
				)
				(justify mirror)
			)
		)
		(property "Manufacturer" "Murata"
			(at 0 0 270)
			(unlocked yes)
			(layer "B.Fab")
			(hide yes)
			(effects
				(font
					(size 1 1)
					(thickness 0.15)
				)
				(justify mirror)
			)
		)
		(property "License" "Apache-2.0"
			(at 0 0 270)
			(unlocked yes)
			(layer "B.Fab")
			(hide yes)
			(effects
				(font
					(size 1 1)
					(thickness 0.15)
				)
				(justify mirror)
			)
		)
		(property "Author" "Antmicro"
			(at 0 0 270)
			(unlocked yes)
			(layer "B.Fab")
			(hide yes)
			(effects
				(font
					(size 1 1)
					(thickness 0.15)
				)
				(justify mirror)
			)
		)
		(property "Val" "1u"
			(at 0 0 270)
			(unlocked yes)
			(layer "B.Fab")
			(hide yes)
			(effects
				(font
					(size 1 1)
					(thickness 0.15)
				)
				(justify mirror)
			)
		)
		(property "Voltage" "25V"
			(at 0 0 270)
			(unlocked yes)
			(layer "B.Fab")
			(hide yes)
			(effects
				(font
					(size 1 1)
					(thickness 0.15)
				)
				(justify mirror)
			)
		)
		(property "Dielectric" "X5R"
			(at 0 0 270)
			(unlocked yes)
			(layer "B.Fab")
			(hide yes)
			(effects
				(font
					(size 1 1)
					(thickness 0.15)
				)
				(justify mirror)
			)
		)
		(sheetname "/FPGA power/")
		(sheetfile "fpga-power.kicad_sch")
		(attr smd)
		(fp_rect
			(start -0.95 0.45)
			(end 0.95 -0.45)
			(stroke
				(width 0.05)
				(type default)
			)
			(fill no)
			(layer "B.CrtYd")
		)
		(fp_line
			(start -0.5 0.25)
			(end 0.498 0.25)
			(stroke
				(width 0.15)
				(type solid)
			)
			(layer "B.Fab")
		)
		(fp_line
			(start 0.498 0.25)
			(end 0.498 -0.248)
			(stroke
				(width 0.15)
				(type solid)
			)
			(layer "B.Fab")
		)
		(fp_line
			(start -0.5 -0.248)
			(end -0.5 0.25)
			(stroke
				(width 0.15)
				(type solid)
			)
			(layer "B.Fab")
		)
		(fp_line
			(start 0.498 -0.248)
			(end -0.5 -0.248)
			(stroke
				(width 0.15)
				(type solid)
			)
			(layer "B.Fab")
		)
		(fp_text user "${REFERENCE}"
			(at -0.9656 -3.169 90)
			(layer "B.Fab")
			(effects
				(font
					(size 0.7 0.7)
					(thickness 0.15)
				)
				(justify left bottom mirror)
			)
		)
		(fp_text user "Author: Antmicro"
			(at -0.9656 -5.569 90)
			(layer "B.Fab")
			(effects
				(font
					(size 0.7 0.7)
					(thickness 0.15)
				)
				(justify left bottom mirror)
			)
		)
		(fp_text user "License: Apache-2.0"
			(at -0.9656 -4.369 90)
			(layer "B.Fab")
			(effects
				(font
					(size 0.7 0.7)
					(thickness 0.15)
				)
				(justify left bottom mirror)
			)
		)
		(pad "1" smd roundrect
			(at -0.5 0 180)
			(size 0.6 0.6)
			(layers "B.Cu" "B.Mask" "B.Paste")
			(roundrect_rratio 0.25)
			(net 1 "GND")
			(pintype "passive")
		)
		(pad "2" smd roundrect
			(at 0.498 0 270)
			(size 0.6 0.6)
			(layers "B.Cu" "B.Mask" "B.Paste")
			(roundrect_rratio 0.25)
			(net 553 "+0V85")
			(pintype "passive")
		)
	)
	(footprint "antmicro-footprints:C_0402_1005Metric"
		(layer "B.Cu")
		(at 174.32 108.3 180)
		(descr "Capacitor SMD 0402")
		(tags "capacitor SMD 0402")
		(property "Reference" "C10"
			(at 1.07 -0.44 0)
			(layer "B.SilkS")
			(effects
				(font
					(size 0.7 0.7)
					(thickness 0.15)
				)
				(justify left bottom mirror)
			)
		)
		(property "Value" "C_100n_0402"
			(at -1.022927 -2.155213 0)
			(layer "B.Fab")
			(effects
				(font
					(size 0.7 0.7)
					(thickness 0.15)
				)
				(justify left bottom mirror)
			)
		)
		(property "Datasheet" "https://www.murata.com/products/productdetail?partno=GRM155R61H104KE14%23"
			(at 0 0 180)
			(layer "F.Fab")
			(hide yes)
			(effects
				(font
					(size 1.27 1.27)
					(thickness 0.15)
				)
			)
		)
		(property "MPN" "GRM155R61H104KE14D"
			(at 0 0 180)
			(unlocked yes)
			(layer "B.Fab")
			(hide yes)
			(effects
				(font
					(size 1 1)
					(thickness 0.15)
				)
				(justify mirror)
			)
		)
		(property "Manufacturer" "Murata"
			(at 0 0 180)
			(unlocked yes)
			(layer "B.Fab")
			(hide yes)
			(effects
				(font
					(size 1 1)
					(thickness 0.15)
				)
				(justify mirror)
			)
		)
		(property "License" "Apache-2.0"
			(at 0 0 180)
			(unlocked yes)
			(layer "B.Fab")
			(hide yes)
			(effects
				(font
					(size 1 1)
					(thickness 0.15)
				)
				(justify mirror)
			)
		)
		(property "Author" "Antmicro"
			(at 0 0 180)
			(unlocked yes)
			(layer "B.Fab")
			(hide yes)
			(effects
				(font
					(size 1 1)
					(thickness 0.15)
				)
				(justify mirror)
			)
		)
		(property "Val" "100n"
			(at 0 0 180)
			(unlocked yes)
			(layer "B.Fab")
			(hide yes)
			(effects
				(font
					(size 1 1)
					(thickness 0.15)
				)
				(justify mirror)
			)
		)
		(property "Voltage" "50V"
			(at 0 0 180)
			(unlocked yes)
			(layer "B.Fab")
			(hide yes)
			(effects
				(font
					(size 1 1)
					(thickness 0.15)
				)
				(justify mirror)
			)
		)
		(property "Dielectric" "X5R"
			(at 0 0 180)
			(unlocked yes)
			(layer "B.Fab")
			(hide yes)
			(effects
				(font
					(size 1 1)
					(thickness 0.15)
				)
				(justify mirror)
			)
		)
		(sheetname "/DDR5 RDIMM/")
		(sheetfile "ddr5-rdimm.kicad_sch")
		(attr smd)
		(fp_rect
			(start -0.925 0.47)
			(end 0.925 -0.47)
			(stroke
				(width 0.05)
				(type default)
			)
			(fill no)
			(layer "B.CrtYd")
		)
		(fp_line
			(start 0.504 0.25)
			(end 0.504 -0.248)
			(stroke
				(width 0.15)
				(type solid)
			)
			(layer "B.Fab")
		)
		(fp_line
			(start 0.504 -0.248)
			(end -0.494 -0.248)
			(stroke
				(width 0.15)
				(type solid)
			)
			(layer "B.Fab")
		)
		(fp_line
			(start -0.494 0.25)
			(end 0.504 0.25)
			(stroke
				(width 0.15)
				(type solid)
			)
			(layer "B.Fab")
		)
		(fp_line
			(start -0.494 -0.248)
			(end -0.494 0.25)
			(stroke
				(width 0.15)
				(type solid)
			)
			(layer "B.Fab")
		)
		(fp_text user "Author: Antmicro"
			(at -0.939 -3.399 0)
			(layer "B.Fab")
			(effects
				(font
					(size 0.7 0.7)
					(thickness 0.15)
				)
				(justify left bottom mirror)
			)
		)
		(fp_text user "${REFERENCE}"
			(at -0.939 -4.599 0)
			(layer "B.Fab")
			(effects
				(font
					(size 0.7 0.7)
					(thickness 0.15)
				)
				(justify left bottom mirror)
			)
		)
		(fp_text user "License: Apache-2.0"
			(at -0.939 -5.799 0)
			(layer "B.Fab")
			(effects
				(font
					(size 0.7 0.7)
					(thickness 0.15)
				)
				(justify left bottom mirror)
			)
		)
		(pad "1" smd roundrect
			(at -0.48 0 180)
			(size 0.59 0.64)
			(layers "B.Cu" "B.Mask" "B.Paste")
			(roundrect_rratio 0.25)
			(net 1 "GND")
			(pintype "passive")
		)
		(pad "2" smd roundrect
			(at 0.48 0 180)
			(size 0.59 0.64)
			(layers "B.Cu" "B.Mask" "B.Paste")
			(roundrect_rratio 0.25)
			(net 687 "VDDQ")
			(pintype "passive")
		)
	)
	(footprint "antmicro-footprints:R_0402_1005Metric_EIA"
		(layer "B.Cu")
		(at 196 148.499 90)
		(descr "Resistor SMD 0402 (1005 Metric), square (rectangular) end terminal, IPC_7351 nominal, (Body size source: IPC-SM-782 page 76, https://www.pcb-3d.com/wordpress/wp-content/uploads/ipc-sm-782a_amendment_1_and_2.pdf)")
		(tags "resistor 0402")
		(property "Reference" "R129"
			(at -3.901 0.4 90)
			(layer "B.SilkS")
			(effects
				(font
					(size 0.7 0.7)
					(thickness 0.15)
				)
				(justify right bottom mirror)
			)
		)
		(property "Value" "R_1k_0402"
			(at 0 -1.169 90)
			(layer "B.Fab")
			(effects
				(font
					(size 0.7 0.7)
					(thickness 0.15)
				)
				(justify right bottom mirror)
			)
		)
		(property "Datasheet" "https://www.bourns.com/docs/product-datasheets/cr.pdf"
			(at 0 0 90)
			(layer "F.Fab")
			(hide yes)
			(effects
				(font
					(size 1.27 1.27)
					(thickness 0.15)
				)
			)
		)
		(property "MPN" "CR0402-FX-1001GLF"
			(at 0 0 90)
			(unlocked yes)
			(layer "B.Fab")
			(hide yes)
			(effects
				(font
					(size 1 1)
					(thickness 0.15)
				)
				(justify mirror)
			)
		)
		(property "Manufacturer" "Bourns"
			(at 0 0 90)
			(unlocked yes)
			(layer "B.Fab")
			(hide yes)
			(effects
				(font
					(size 1 1)
					(thickness 0.15)
				)
				(justify mirror)
			)
		)
		(property "License" "Apache-2.0"
			(at 0 0 90)
			(unlocked yes)
			(layer "B.Fab")
			(hide yes)
			(effects
				(font
					(size 1 1)
					(thickness 0.15)
				)
				(justify mirror)
			)
		)
		(property "Author" "Antmicro"
			(at 0 0 90)
			(unlocked yes)
			(layer "B.Fab")
			(hide yes)
			(effects
				(font
					(size 1 1)
					(thickness 0.15)
				)
				(justify mirror)
			)
		)
		(property "Val" "1k"
			(at 0 0 90)
			(unlocked yes)
			(layer "B.Fab")
			(hide yes)
			(effects
				(font
					(size 1 1)
					(thickness 0.15)
				)
				(justify mirror)
			)
		)
		(property "Tolerance" "1%"
			(at 0 0 90)
			(unlocked yes)
			(layer "B.Fab")
			(hide yes)
			(effects
				(font
					(size 1 1)
					(thickness 0.15)
				)
				(justify mirror)
			)
		)
		(sheetname "/FPGA banks HP/")
		(sheetfile "fpga-hp-banks.kicad_sch")
		(attr smd exclude_from_bom dnp)
		(fp_rect
			(start -0.95 0.45)
			(end 0.95 -0.45)
			(stroke
				(width 0.05)
				(type default)
			)
			(fill no)
			(layer "B.CrtYd")
		)
		(fp_line
			(start 0.499 -0.249)
			(end -0.5 -0.249)
			(stroke
				(width 0.15)
				(type solid)
			)
			(layer "B.Fab")
		)
		(fp_line
			(start -0.5 -0.249)
			(end -0.5 0.25)
			(stroke
				(width 0.15)
				(type solid)
			)
			(layer "B.Fab")
		)
		(fp_line
			(start 0.499 0.25)
			(end 0.499 -0.249)
			(stroke
				(width 0.15)
				(type solid)
			)
			(layer "B.Fab")
		)
		(fp_line
			(start -0.5 0.25)
			(end 0.499 0.25)
			(stroke
				(width 0.15)
				(type solid)
			)
			(layer "B.Fab")
		)
		(fp_text user "${REFERENCE}"
			(at -0.95 -3.169 90)
			(layer "B.Fab")
			(effects
				(font
					(size 0.7 0.7)
					(thickness 0.15)
				)
				(justify right top mirror)
			)
		)
		(fp_text user "License: Apache-2.0"
			(at -0.95 -4.369 90)
			(layer "B.Fab")
			(effects
				(font
					(size 0.7 0.7)
					(thickness 0.15)
				)
				(justify right top mirror)
			)
		)
		(fp_text user "Author: Antmicro"
			(at -0.95 -5.569 90)
			(layer "B.Fab")
			(effects
				(font
					(size 0.7 0.7)
					(thickness 0.15)
				)
				(justify right top mirror)
			)
		)
		(pad "1" smd roundrect
			(at -0.5 0)
			(size 0.6 0.6)
			(layers "B.Cu" "B.Mask" "B.Paste")
			(roundrect_rratio 0.25)
			(net 1 "GND")
			(pintype "passive")
		)
		(pad "2" smd roundrect
			(at 0.499 0 90)
			(size 0.6 0.6)
			(layers "B.Cu" "B.Mask" "B.Paste")
			(roundrect_rratio 0.25)
			(net 535 "/FPGA banks HP/VREF_64")
			(pintype "passive")
		)
	)
	(footprint "antmicro-footprints:C_0402_1005Metric_EIA"
		(layer "B.Cu")
		(at 180 162.5 90)
		(descr "Capacitor SMD 0402 (1005 Metric), square (rectangular) end terminal, IPC_7351 nominal, (Body size source: IPC-SM-782 page 76, https://www.pcb-3d.com/wordpress/wp-content/uploads/ipc-sm-782a_amendment_1_and_2.pdf)")
		(tags "capacitor 0402")
		(property "Reference" "C83"
			(at -3.3 0.45 90)
			(layer "B.SilkS")
			(effects
				(font
					(size 0.7 0.7)
					(thickness 0.15)
				)
				(justify right bottom mirror)
			)
		)
		(property "Value" "C_100n_0402"
			(at 0 -1.169 90)
			(layer "B.Fab")
			(effects
				(font
					(size 0.7 0.7)
					(thickness 0.15)
				)
				(justify right bottom mirror)
			)
		)
		(property "Datasheet" "https://www.murata.com/products/productdetail?partno=GRM155R61H104KE14%23"
			(at 0 0 90)
			(layer "F.Fab")
			(hide yes)
			(effects
				(font
					(size 1.27 1.27)
					(thickness 0.15)
				)
			)
		)
		(property "MPN" "GRM155R61H104KE14D"
			(at 0 0 90)
			(unlocked yes)
			(layer "B.Fab")
			(hide yes)
			(effects
				(font
					(size 1 1)
					(thickness 0.15)
				)
				(justify mirror)
			)
		)
		(property "Manufacturer" "Murata"
			(at 0 0 90)
			(unlocked yes)
			(layer "B.Fab")
			(hide yes)
			(effects
				(font
					(size 1 1)
					(thickness 0.15)
				)
				(justify mirror)
			)
		)
		(property "License" "Apache-2.0"
			(at 0 0 90)
			(unlocked yes)
			(layer "B.Fab")
			(hide yes)
			(effects
				(font
					(size 1 1)
					(thickness 0.15)
				)
				(justify mirror)
			)
		)
		(property "Author" "Antmicro"
			(at 0 0 90)
			(unlocked yes)
			(layer "B.Fab")
			(hide yes)
			(effects
				(font
					(size 1 1)
					(thickness 0.15)
				)
				(justify mirror)
			)
		)
		(property "Val" "100n"
			(at 0 0 90)
			(unlocked yes)
			(layer "B.Fab")
			(hide yes)
			(effects
				(font
					(size 1 1)
					(thickness 0.15)
				)
				(justify mirror)
			)
		)
		(property "Voltage" "50V"
			(at 0 0 90)
			(unlocked yes)
			(layer "B.Fab")
			(hide yes)
			(effects
				(font
					(size 1 1)
					(thickness 0.15)
				)
				(justify mirror)
			)
		)
		(property "Dielectric" "X5R"
			(at 0 0 90)
			(unlocked yes)
			(layer "B.Fab")
			(hide yes)
			(effects
				(font
					(size 1 1)
					(thickness 0.15)
				)
				(justify mirror)
			)
		)
		(sheetname "/FPGA power/")
		(sheetfile "fpga-power.kicad_sch")
		(attr smd)
		(fp_rect
			(start -0.95 0.45)
			(end 0.95 -0.45)
			(stroke
				(width 0.05)
				(type default)
			)
			(fill no)
			(layer "B.CrtYd")
		)
		(fp_line
			(start 0.498 -0.248)
			(end -0.5 -0.248)
			(stroke
				(width 0.15)
				(type solid)
			)
			(layer "B.Fab")
		)
		(fp_line
			(start -0.5 -0.248)
			(end -0.5 0.25)
			(stroke
				(width 0.15)
				(type solid)
			)
			(layer "B.Fab")
		)
		(fp_line
			(start 0.498 0.25)
			(end 0.498 -0.248)
			(stroke
				(width 0.15)
				(type solid)
			)
			(layer "B.Fab")
		)
		(fp_line
			(start -0.5 0.25)
			(end 0.498 0.25)
			(stroke
				(width 0.15)
				(type solid)
			)
			(layer "B.Fab")
		)
		(fp_text user "${REFERENCE}"
			(at -0.9656 -3.169 270)
			(layer "B.Fab")
			(effects
				(font
					(size 0.7 0.7)
					(thickness 0.15)
				)
				(justify left bottom mirror)
			)
		)
		(fp_text user "License: Apache-2.0"
			(at -0.9656 -4.369 270)
			(layer "B.Fab")
			(effects
				(font
					(size 0.7 0.7)
					(thickness 0.15)
				)
				(justify left bottom mirror)
			)
		)
		(fp_text user "Author: Antmicro"
			(at -0.9656 -5.569 270)
			(layer "B.Fab")
			(effects
				(font
					(size 0.7 0.7)
					(thickness 0.15)
				)
				(justify left bottom mirror)
			)
		)
		(pad "1" smd roundrect
			(at -0.5 0)
			(size 0.6 0.6)
			(layers "B.Cu" "B.Mask" "B.Paste")
			(roundrect_rratio 0.25)
			(net 1 "GND")
			(pintype "passive")
		)
		(pad "2" smd roundrect
			(at 0.498 0 90)
			(size 0.6 0.6)
			(layers "B.Cu" "B.Mask" "B.Paste")
			(roundrect_rratio 0.25)
			(net 172 "+1V2_MGTAVTT")
			(pintype "passive")
		)
	)
	(footprint "antmicro-footprints:SC70-3"
		(layer "B.Cu")
		(at 250.375 120.275 90)
		(property "Reference" "Q25"
			(at 0.115 -3.435 180)
			(layer "B.SilkS")
			(effects
				(font
					(size 0.7 0.7)
					(thickness 0.15)
				)
				(justify right bottom mirror)
			)
		)
		(property "Value" "BSS138PW"
			(at 0 -2.3 90)
			(layer "B.Fab")
			(effects
				(font
					(size 0.7 0.7)
					(thickness 0.15)
				)
				(justify right bottom mirror)
			)
		)
		(property "Datasheet" "https://assets.nexperia.com/documents/data-sheet/BSS138PW.pdf"
			(at 0 0 90)
			(layer "F.Fab")
			(hide yes)
			(effects
				(font
					(size 1.27 1.27)
					(thickness 0.15)
				)
			)
		)
		(property "MPN" "BSS138PW"
			(at 0 0 90)
			(unlocked yes)
			(layer "B.Fab")
			(hide yes)
			(effects
				(font
					(size 1 1)
					(thickness 0.15)
				)
				(justify mirror)
			)
		)
		(property "Manufacturer" "Nexperia"
			(at 0 0 90)
			(unlocked yes)
			(layer "B.Fab")
			(hide yes)
			(effects
				(font
					(size 1 1)
					(thickness 0.15)
				)
				(justify mirror)
			)
		)
		(property "Author" "Antmicro"
			(at 0 0 90)
			(unlocked yes)
			(layer "B.Fab")
			(hide yes)
			(effects
				(font
					(size 1 1)
					(thickness 0.15)
				)
				(justify mirror)
			)
		)
		(property "License" "Apache-2.0"
			(at 0 0 90)
			(unlocked yes)
			(layer "B.Fab")
			(hide yes)
			(effects
				(font
					(size 1 1)
					(thickness 0.15)
				)
				(justify mirror)
			)
		)
		(sheetname "/DDR5 RDIMM/")
		(sheetfile "ddr5-rdimm.kicad_sch")
		(attr smd)
		(fp_line
			(start -0.3 -1)
			(end 0.627 -1.001)
			(stroke
				(width 0.15)
				(type solid)
			)
			(layer "B.SilkS")
		)
		(fp_line
			(start 0.627 -0.6)
			(end 0.627 -1.001)
			(stroke
				(width 0.15)
				(type solid)
			)
			(layer "B.SilkS")
		)
		(fp_line
			(start 0.627 0.6)
			(end 0.627 0.999)
			(stroke
				(width 0.15)
				(type solid)
			)
			(layer "B.SilkS")
		)
		(fp_line
			(start -0.3 1)
			(end 0.627 0.999)
			(stroke
				(width 0.15)
				(type solid)
			)
			(layer "B.SilkS")
		)
		(fp_line
			(start 0.9 -1.3)
			(end -0.9 -1.3)
			(stroke
				(width 0.05)
				(type solid)
			)
			(layer "B.CrtYd")
		)
		(fp_line
			(start -0.9 -1.3)
			(end -0.9 -1)
			(stroke
				(width 0.05)
				(type solid)
			)
			(layer "B.CrtYd")
		)
		(fp_line
			(start -0.9 -1)
			(end -1.4 -1)
			(stroke
				(width 0.05)
				(type solid)
			)
			(layer "B.CrtYd")
		)
		(fp_line
			(start -1.4 -1)
			(end -1.4 1)
			(stroke
				(width 0.05)
				(type solid)
			)
			(layer "B.CrtYd")
		)
		(fp_line
			(start 1.4 -0.4)
			(end 0.9 -0.4)
			(stroke
				(width 0.05)
				(type solid)
			)
			(layer "B.CrtYd")
		)
		(fp_line
			(start 0.9 -0.4)
			(end 0.9 -1.3)
			(stroke
				(width 0.05)
				(type solid)
			)
			(layer "B.CrtYd")
		)
		(fp_line
			(start 1.4 0.4)
			(end 1.4 -0.4)
			(stroke
				(width 0.05)
				(type solid)
			)
			(layer "B.CrtYd")
		)
		(fp_line
			(start 0.9 0.4)
			(end 1.4 0.4)
			(stroke
				(width 0.05)
				(type solid)
			)
			(layer "B.CrtYd")
		)
		(fp_line
			(start -0.9 1)
			(end -1.4 1)
			(stroke
				(width 0.05)
				(type solid)
			)
			(layer "B.CrtYd")
		)
		(fp_line
			(start 0.9 1.3)
			(end 0.9 0.4)
			(stroke
				(width 0.05)
				(type solid)
			)
			(layer "B.CrtYd")
		)
		(fp_line
			(start -0.9 1.3)
			(end -0.9 1)
			(stroke
				(width 0.05)
				(type solid)
			)
			(layer "B.CrtYd")
		)
		(fp_line
			(start -0.9 1.3)
			(end 0.9 1.3)
			(stroke
				(width 0.05)
				(type solid)
			)
			(layer "B.CrtYd")
		)
		(fp_rect
			(start -0.623 0.999)
			(end 0.627 -1.001)
			(stroke
				(width 0.15)
				(type solid)
			)
			(fill no)
			(layer "B.Fab")
		)
		(fp_text user "Author: Antmicro"
			(at -1.45 -5.782 270)
			(layer "B.Fab")
			(effects
				(font
					(size 0.7 0.7)
					(thickness 0.15)
				)
				(justify left bottom mirror)
			)
		)
		(fp_text user "License: Apache-2.0"
			(at -1.45 -6.782 270)
			(layer "B.Fab")
			(effects
				(font
					(size 0.7 0.7)
					(thickness 0.15)
				)
				(justify left bottom mirror)
			)
		)
		(fp_text user "${REFERENCE}"
			(at -1.45 -4.783 270)
			(layer "B.Fab")
			(effects
				(font
					(size 0.7 0.7)
					(thickness 0.15)
				)
				(justify left bottom mirror)
			)
		)
		(pad "1" smd rect
			(at -1.051 0.65)
			(size 0.6 0.6)
			(layers "B.Cu" "B.Mask" "B.Paste")
			(net 808 "VIN_BULK_EN")
			(pinfunction "G")
			(pintype "passive")
		)
		(pad "2" smd rect
			(at -1.051 -0.65)
			(size 0.6 0.6)
			(layers "B.Cu" "B.Mask" "B.Paste")
			(net 1 "GND")
			(pinfunction "S")
			(pintype "passive")
		)
		(pad "3" smd rect
			(at 1.05 0)
			(size 0.6 0.6)
			(layers "B.Cu" "B.Mask" "B.Paste")
			(net 806 "Net-(Q23-G)")
			(pinfunction "D")
			(pintype "passive")
		)
	)
	(footprint "antmicro-footprints:C_0402_1005Metric"
		(layer "B.Cu")
		(at 181.622499 193.2285 90)
		(descr "Capacitor SMD 0402")
		(tags "capacitor SMD 0402")
		(property "Reference" "C256"
			(at 0.994 0.403501 90)
			(layer "B.SilkS")
			(effects
				(font
					(size 0.7 0.7)
					(thickness 0.15)
				)
				(justify right bottom mirror)
			)
		)
		(property "Value" "C_100n_0402"
			(at -1.022927 -2.155213 90)
			(layer "B.Fab")
			(effects
				(font
					(size 0.7 0.7)
					(thickness 0.15)
				)
				(justify right bottom mirror)
			)
		)
		(property "Datasheet" "https://www.murata.com/products/productdetail?partno=GRM155R61H104KE14%23"
			(at 0 0 90)
			(layer "F.Fab")
			(hide yes)
			(effects
				(font
					(size 1.27 1.27)
					(thickness 0.15)
				)
			)
		)
		(property "Manufacturer" "Murata"
			(at 0 0 90)
			(unlocked yes)
			(layer "B.Fab")
			(hide yes)
			(effects
				(font
					(size 1 1)
					(thickness 0.15)
				)
				(justify mirror)
			)
		)
		(property "MPN" "GRM155R61H104KE14D"
			(at 0 0 90)
			(unlocked yes)
			(layer "B.Fab")
			(hide yes)
			(effects
				(font
					(size 1 1)
					(thickness 0.15)
				)
				(justify mirror)
			)
		)
		(property "Val" "100n"
			(at 0 0 90)
			(unlocked yes)
			(layer "B.Fab")
			(hide yes)
			(effects
				(font
					(size 1 1)
					(thickness 0.15)
				)
				(justify mirror)
			)
		)
		(property "License" "Apache-2.0"
			(at 0 0 90)
			(unlocked yes)
			(layer "B.Fab")
			(hide yes)
			(effects
				(font
					(size 1 1)
					(thickness 0.15)
				)
				(justify mirror)
			)
		)
		(property "Author" "Antmicro"
			(at 0 0 90)
			(unlocked yes)
			(layer "B.Fab")
			(hide yes)
			(effects
				(font
					(size 1 1)
					(thickness 0.15)
				)
				(justify mirror)
			)
		)
		(property "Voltage" "50V"
			(at 0 0 90)
			(unlocked yes)
			(layer "B.Fab")
			(hide yes)
			(effects
				(font
					(size 1 1)
					(thickness 0.15)
				)
				(justify mirror)
			)
		)
		(property "Dielectric" "X5R"
			(at 0 0 90)
			(unlocked yes)
			(layer "B.Fab")
			(hide yes)
			(effects
				(font
					(size 1 1)
					(thickness 0.15)
				)
				(justify mirror)
			)
		)
		(sheetname "/FPGA MGT Interface/")
		(sheetfile "fpga-mgt.kicad_sch")
		(attr smd)
		(fp_rect
			(start -0.925 0.47)
			(end 0.925 -0.47)
			(stroke
				(width 0.05)
				(type default)
			)
			(fill no)
			(layer "B.CrtYd")
		)
		(fp_line
			(start 0.504 -0.248)
			(end -0.494 -0.248)
			(stroke
				(width 0.15)
				(type solid)
			)
			(layer "B.Fab")
		)
		(fp_line
			(start -0.494 -0.248)
			(end -0.494 0.25)
			(stroke
				(width 0.15)
				(type solid)
			)
			(layer "B.Fab")
		)
		(fp_line
			(start 0.504 0.25)
			(end 0.504 -0.248)
			(stroke
				(width 0.15)
				(type solid)
			)
			(layer "B.Fab")
		)
		(fp_line
			(start -0.494 0.25)
			(end 0.504 0.25)
			(stroke
				(width 0.15)
				(type solid)
			)
			(layer "B.Fab")
		)
		(fp_text user "${REFERENCE}"
			(at -0.939 -4.599 270)
			(layer "B.Fab")
			(effects
				(font
					(size 0.7 0.7)
					(thickness 0.15)
				)
				(justify left bottom mirror)
			)
		)
		(fp_text user "License: Apache-2.0"
			(at -0.939 -5.799 270)
			(layer "B.Fab")
			(effects
				(font
					(size 0.7 0.7)
					(thickness 0.15)
				)
				(justify left bottom mirror)
			)
		)
		(fp_text user "Author: Antmicro"
			(at -0.939 -3.399 270)
			(layer "B.Fab")
			(effects
				(font
					(size 0.7 0.7)
					(thickness 0.15)
				)
				(justify left bottom mirror)
			)
		)
		(pad "1" smd roundrect
			(at -0.48 0 90)
			(size 0.59 0.64)
			(layers "B.Cu" "B.Mask" "B.Paste")
			(roundrect_rratio 0.25)
			(net 258 "/FPGA MGT Interface/PCIE.TXD4_P")
			(pintype "passive")
		)
		(pad "2" smd roundrect
			(at 0.48 0 90)
			(size 0.59 0.64)
			(layers "B.Cu" "B.Mask" "B.Paste")
			(roundrect_rratio 0.25)
			(net 566 "/FPGA MGT Interface/GTY_224_TX3_P")
			(pintype "passive")
		)
	)
	(footprint "antmicro-footprints:SC70-3"
		(layer "B.Cu")
		(at 244.86 120.275 90)
		(property "Reference" "Q28"
			(at 0.125 -3.33 180)
			(layer "B.SilkS")
			(effects
				(font
					(size 0.7 0.7)
					(thickness 0.15)
				)
				(justify right bottom mirror)
			)
		)
		(property "Value" "BSS138PW"
			(at 0 -2.3 90)
			(layer "B.Fab")
			(effects
				(font
					(size 0.7 0.7)
					(thickness 0.15)
				)
				(justify right bottom mirror)
			)
		)
		(property "Datasheet" "https://assets.nexperia.com/documents/data-sheet/BSS138PW.pdf"
			(at 0 0 90)
			(layer "F.Fab")
			(hide yes)
			(effects
				(font
					(size 1.27 1.27)
					(thickness 0.15)
				)
			)
		)
		(property "MPN" "BSS138PW"
			(at 0 0 90)
			(unlocked yes)
			(layer "B.Fab")
			(hide yes)
			(effects
				(font
					(size 1 1)
					(thickness 0.15)
				)
				(justify mirror)
			)
		)
		(property "Manufacturer" "Nexperia"
			(at 0 0 90)
			(unlocked yes)
			(layer "B.Fab")
			(hide yes)
			(effects
				(font
					(size 1 1)
					(thickness 0.15)
				)
				(justify mirror)
			)
		)
		(property "Author" "Antmicro"
			(at 0 0 90)
			(unlocked yes)
			(layer "B.Fab")
			(hide yes)
			(effects
				(font
					(size 1 1)
					(thickness 0.15)
				)
				(justify mirror)
			)
		)
		(property "License" "Apache-2.0"
			(at 0 0 90)
			(unlocked yes)
			(layer "B.Fab")
			(hide yes)
			(effects
				(font
					(size 1 1)
					(thickness 0.15)
				)
				(justify mirror)
			)
		)
		(sheetname "/Supply/")
		(sheetfile "supply.kicad_sch")
		(attr smd)
		(fp_line
			(start -0.3 -1)
			(end 0.627 -1.001)
			(stroke
				(width 0.15)
				(type solid)
			)
			(layer "B.SilkS")
		)
		(fp_line
			(start 0.627 -0.6)
			(end 0.627 -1.001)
			(stroke
				(width 0.15)
				(type solid)
			)
			(layer "B.SilkS")
		)
		(fp_line
			(start 0.627 0.6)
			(end 0.627 0.999)
			(stroke
				(width 0.15)
				(type solid)
			)
			(layer "B.SilkS")
		)
		(fp_line
			(start -0.3 1)
			(end 0.627 0.999)
			(stroke
				(width 0.15)
				(type solid)
			)
			(layer "B.SilkS")
		)
		(fp_line
			(start 0.9 -1.3)
			(end -0.9 -1.3)
			(stroke
				(width 0.05)
				(type solid)
			)
			(layer "B.CrtYd")
		)
		(fp_line
			(start -0.9 -1.3)
			(end -0.9 -1)
			(stroke
				(width 0.05)
				(type solid)
			)
			(layer "B.CrtYd")
		)
		(fp_line
			(start -0.9 -1)
			(end -1.4 -1)
			(stroke
				(width 0.05)
				(type solid)
			)
			(layer "B.CrtYd")
		)
		(fp_line
			(start -1.4 -1)
			(end -1.4 1)
			(stroke
				(width 0.05)
				(type solid)
			)
			(layer "B.CrtYd")
		)
		(fp_line
			(start 1.4 -0.4)
			(end 0.9 -0.4)
			(stroke
				(width 0.05)
				(type solid)
			)
			(layer "B.CrtYd")
		)
		(fp_line
			(start 0.9 -0.4)
			(end 0.9 -1.3)
			(stroke
				(width 0.05)
				(type solid)
			)
			(layer "B.CrtYd")
		)
		(fp_line
			(start 1.4 0.4)
			(end 1.4 -0.4)
			(stroke
				(width 0.05)
				(type solid)
			)
			(layer "B.CrtYd")
		)
		(fp_line
			(start 0.9 0.4)
			(end 1.4 0.4)
			(stroke
				(width 0.05)
				(type solid)
			)
			(layer "B.CrtYd")
		)
		(fp_line
			(start -0.9 1)
			(end -1.4 1)
			(stroke
				(width 0.05)
				(type solid)
			)
			(layer "B.CrtYd")
		)
		(fp_line
			(start 0.9 1.3)
			(end 0.9 0.4)
			(stroke
				(width 0.05)
				(type solid)
			)
			(layer "B.CrtYd")
		)
		(fp_line
			(start -0.9 1.3)
			(end -0.9 1)
			(stroke
				(width 0.05)
				(type solid)
			)
			(layer "B.CrtYd")
		)
		(fp_line
			(start -0.9 1.3)
			(end 0.9 1.3)
			(stroke
				(width 0.05)
				(type solid)
			)
			(layer "B.CrtYd")
		)
		(fp_rect
			(start -0.623 0.999)
			(end 0.627 -1.001)
			(stroke
				(width 0.15)
				(type solid)
			)
			(fill no)
			(layer "B.Fab")
		)
		(fp_text user "License: Apache-2.0"
			(at -1.45 -6.782 270)
			(layer "B.Fab")
			(effects
				(font
					(size 0.7 0.7)
					(thickness 0.15)
				)
				(justify left bottom mirror)
			)
		)
		(fp_text user "Author: Antmicro"
			(at -1.45 -5.782 270)
			(layer "B.Fab")
			(effects
				(font
					(size 0.7 0.7)
					(thickness 0.15)
				)
				(justify left bottom mirror)
			)
		)
		(fp_text user "${REFERENCE}"
			(at -1.45 -4.783 270)
			(layer "B.Fab")
			(effects
				(font
					(size 0.7 0.7)
					(thickness 0.15)
				)
				(justify left bottom mirror)
			)
		)
		(pad "1" smd rect
			(at -1.051 0.65)
			(size 0.6 0.6)
			(layers "B.Cu" "B.Mask" "B.Paste")
			(net 812 "Heater_PWM")
			(pinfunction "G")
			(pintype "passive")
		)
		(pad "2" smd rect
			(at -1.051 -0.65)
			(size 0.6 0.6)
			(layers "B.Cu" "B.Mask" "B.Paste")
			(net 1 "GND")
			(pinfunction "S")
			(pintype "passive")
		)
		(pad "3" smd rect
			(at 1.05 0)
			(size 0.6 0.6)
			(layers "B.Cu" "B.Mask" "B.Paste")
			(net 813 "Net-(Q28-D)")
			(pinfunction "D")
			(pintype "passive")
		)
	)
	(footprint "antmicro-footprints:R_0402_1005Metric"
		(layer "B.Cu")
		(at 254.324499 167.849 180)
		(descr "Resistor SMD 0402")
		(tags "resistor SMD 0402")
		(property "Reference" "R162"
			(at 0.9455 -0.304499 0)
			(layer "B.SilkS")
			(effects
				(font
					(size 0.7 0.7)
					(thickness 0.15)
				)
				(justify left bottom mirror)
			)
		)
		(property "Value" "R_0R_0402"
			(at -1.011843 -1.772047 0)
			(layer "B.Fab")
			(effects
				(font
					(size 0.7 0.7)
					(thickness 0.15)
				)
				(justify left bottom mirror)
			)
		)
		(property "Datasheet" "https://industrial.panasonic.com/cdbs/www-data/pdf/RDA0000/AOA0000C301.pdf"
			(at 0 0 180)
			(layer "F.Fab")
			(hide yes)
			(effects
				(font
					(size 1.27 1.27)
					(thickness 0.15)
				)
			)
		)
		(property "Manufacturer" "Panasonic"
			(at 0 0 180)
			(unlocked yes)
			(layer "B.Fab")
			(hide yes)
			(effects
				(font
					(size 1 1)
					(thickness 0.15)
				)
				(justify mirror)
			)
		)
		(property "MPN" "ERJ2GE0R00X"
			(at 0 0 180)
			(unlocked yes)
			(layer "B.Fab")
			(hide yes)
			(effects
				(font
					(size 1 1)
					(thickness 0.15)
				)
				(justify mirror)
			)
		)
		(property "Val" "0R"
			(at 0 0 180)
			(unlocked yes)
			(layer "B.Fab")
			(hide yes)
			(effects
				(font
					(size 1 1)
					(thickness 0.15)
				)
				(justify mirror)
			)
		)
		(property "License" "Apache-2.0"
			(at 0 0 180)
			(unlocked yes)
			(layer "B.Fab")
			(hide yes)
			(effects
				(font
					(size 1 1)
					(thickness 0.15)
				)
				(justify mirror)
			)
		)
		(property "Author" "Antmicro"
			(at 0 0 180)
			(unlocked yes)
			(layer "B.Fab")
			(hide yes)
			(effects
				(font
					(size 1 1)
					(thickness 0.15)
				)
				(justify mirror)
			)
		)
		(property "Tolerance" "~"
			(at 0 0 180)
			(unlocked yes)
			(layer "B.Fab")
			(hide yes)
			(effects
				(font
					(size 1 1)
					(thickness 0.15)
				)
				(justify mirror)
			)
		)
		(property "Current" "1A"
			(at 0 0 180)
			(unlocked yes)
			(layer "B.Fab")
			(hide yes)
			(effects
				(font
					(size 1 1)
					(thickness 0.15)
				)
				(justify mirror)
			)
		)
		(sheetname "/Supply/DC-DC AUX, MGT/")
		(sheetfile "dc-dc-aux-mgt.kicad_sch")
		(attr smd exclude_from_bom dnp)
		(fp_rect
			(start -0.925 0.47)
			(end 0.925 -0.47)
			(stroke
				(width 0.05)
				(type default)
			)
			(fill no)
			(layer "B.CrtYd")
		)
		(fp_rect
			(start -0.5 0.25)
			(end 0.5 -0.25)
			(stroke
				(width 0.15)
				(type solid)
			)
			(fill no)
			(layer "B.Fab")
		)
		(fp_text user "${REFERENCE}"
			(at -0.95 -3.168 0)
			(layer "B.Fab")
			(effects
				(font
					(size 0.7 0.7)
					(thickness 0.15)
				)
				(justify left bottom mirror)
			)
		)
		(fp_text user "License: Apache-2.0"
			(at -0.95 -5.169 0)
			(layer "B.Fab")
			(effects
				(font
					(size 0.7 0.7)
					(thickness 0.15)
				)
				(justify left bottom mirror)
			)
		)
		(fp_text user "Author: Antmicro"
			(at -0.95 -4.169 0)
			(layer "B.Fab")
			(effects
				(font
					(size 0.7 0.7)
					(thickness 0.15)
				)
				(justify left bottom mirror)
			)
		)
		(pad "1" smd roundrect
			(at -0.48 0 180)
			(size 0.59 0.64)
			(layers "B.Cu" "B.Mask" "B.Paste")
			(roundrect_rratio 0.25)
			(net 1 "GND")
			(pintype "passive")
		)
		(pad "2" smd roundrect
			(at 0.48 0 180)
			(size 0.59 0.64)
			(layers "B.Cu" "B.Mask" "B.Paste")
			(roundrect_rratio 0.25)
			(net 713 "/Supply/DC-DC AUX, MGT/FB2")
			(pintype "passive")
		)
	)
	(footprint "antmicro-footprints:C_0402_1005Metric_EIA"
		(layer "B.Cu")
		(at 185 150.5 -90)
		(descr "Capacitor SMD 0402 (1005 Metric), square (rectangular) end terminal, IPC_7351 nominal, (Body size source: IPC-SM-782 page 76, https://www.pcb-3d.com/wordpress/wp-content/uploads/ipc-sm-782a_amendment_1_and_2.pdf)")
		(tags "capacitor 0402")
		(property "Reference" "C36"
			(at -11.525 30.625 90)
			(layer "B.SilkS")
			(effects
				(font
					(size 0.7 0.7)
					(thickness 0.15)
				)
				(justify left bottom mirror)
			)
		)
		(property "Value" "C_1u_25V_0402"
			(at 0 -1.169 90)
			(layer "B.Fab")
			(effects
				(font
					(size 0.7 0.7)
					(thickness 0.15)
				)
				(justify left bottom mirror)
			)
		)
		(property "Datasheet" "https://www.murata.com/products/productdetail?partno=GRM155R61E105KE11%23"
			(at 0 0 270)
			(layer "F.Fab")
			(hide yes)
			(effects
				(font
					(size 1.27 1.27)
					(thickness 0.15)
				)
			)
		)
		(property "MPN" "GRM155R61E105KE11J"
			(at 0 0 270)
			(unlocked yes)
			(layer "B.Fab")
			(hide yes)
			(effects
				(font
					(size 1 1)
					(thickness 0.15)
				)
				(justify mirror)
			)
		)
		(property "Manufacturer" "Murata"
			(at 0 0 270)
			(unlocked yes)
			(layer "B.Fab")
			(hide yes)
			(effects
				(font
					(size 1 1)
					(thickness 0.15)
				)
				(justify mirror)
			)
		)
		(property "License" "Apache-2.0"
			(at 0 0 270)
			(unlocked yes)
			(layer "B.Fab")
			(hide yes)
			(effects
				(font
					(size 1 1)
					(thickness 0.15)
				)
				(justify mirror)
			)
		)
		(property "Author" "Antmicro"
			(at 0 0 270)
			(unlocked yes)
			(layer "B.Fab")
			(hide yes)
			(effects
				(font
					(size 1 1)
					(thickness 0.15)
				)
				(justify mirror)
			)
		)
		(property "Val" "1u"
			(at 0 0 270)
			(unlocked yes)
			(layer "B.Fab")
			(hide yes)
			(effects
				(font
					(size 1 1)
					(thickness 0.15)
				)
				(justify mirror)
			)
		)
		(property "Voltage" "25V"
			(at 0 0 270)
			(unlocked yes)
			(layer "B.Fab")
			(hide yes)
			(effects
				(font
					(size 1 1)
					(thickness 0.15)
				)
				(justify mirror)
			)
		)
		(property "Dielectric" "X5R"
			(at 0 0 270)
			(unlocked yes)
			(layer "B.Fab")
			(hide yes)
			(effects
				(font
					(size 1 1)
					(thickness 0.15)
				)
				(justify mirror)
			)
		)
		(sheetname "/FPGA power/")
		(sheetfile "fpga-power.kicad_sch")
		(attr smd)
		(fp_rect
			(start -0.95 0.45)
			(end 0.95 -0.45)
			(stroke
				(width 0.05)
				(type default)
			)
			(fill no)
			(layer "B.CrtYd")
		)
		(fp_line
			(start -0.5 0.25)
			(end 0.498 0.25)
			(stroke
				(width 0.15)
				(type solid)
			)
			(layer "B.Fab")
		)
		(fp_line
			(start 0.498 0.25)
			(end 0.498 -0.248)
			(stroke
				(width 0.15)
				(type solid)
			)
			(layer "B.Fab")
		)
		(fp_line
			(start -0.5 -0.248)
			(end -0.5 0.25)
			(stroke
				(width 0.15)
				(type solid)
			)
			(layer "B.Fab")
		)
		(fp_line
			(start 0.498 -0.248)
			(end -0.5 -0.248)
			(stroke
				(width 0.15)
				(type solid)
			)
			(layer "B.Fab")
		)
		(fp_text user "License: Apache-2.0"
			(at -0.9656 -4.369 90)
			(layer "B.Fab")
			(effects
				(font
					(size 0.7 0.7)
					(thickness 0.15)
				)
				(justify left bottom mirror)
			)
		)
		(fp_text user "${REFERENCE}"
			(at -0.9656 -3.169 90)
			(layer "B.Fab")
			(effects
				(font
					(size 0.7 0.7)
					(thickness 0.15)
				)
				(justify left bottom mirror)
			)
		)
		(fp_text user "Author: Antmicro"
			(at -0.9656 -5.569 90)
			(layer "B.Fab")
			(effects
				(font
					(size 0.7 0.7)
					(thickness 0.15)
				)
				(justify left bottom mirror)
			)
		)
		(pad "1" smd roundrect
			(at -0.5 0 180)
			(size 0.6 0.6)
			(layers "B.Cu" "B.Mask" "B.Paste")
			(roundrect_rratio 0.25)
			(net 1 "GND")
			(pintype "passive")
		)
		(pad "2" smd roundrect
			(at 0.498 0 270)
			(size 0.6 0.6)
			(layers "B.Cu" "B.Mask" "B.Paste")
			(roundrect_rratio 0.25)
			(net 553 "+0V85")
			(pintype "passive")
		)
	)
	(footprint "antmicro-footprints:R_0402_1005Metric"
		(layer "B.Cu")
		(at 254.365 177.6)
		(descr "Resistor SMD 0402")
		(tags "resistor SMD 0402")
		(property "Reference" "R153"
			(at 0.935 0.45 0)
			(layer "B.SilkS")
			(effects
				(font
					(size 0.7 0.7)
					(thickness 0.15)
				)
				(justify right bottom mirror)
			)
		)
		(property "Value" "R_0R_0402"
			(at -1.011843 -1.772047 0)
			(layer "B.Fab")
			(effects
				(font
					(size 0.7 0.7)
					(thickness 0.15)
				)
				(justify right bottom mirror)
			)
		)
		(property "Datasheet" "https://industrial.panasonic.com/cdbs/www-data/pdf/RDA0000/AOA0000C301.pdf"
			(at 0 0 0)
			(layer "F.Fab")
			(hide yes)
			(effects
				(font
					(size 1.27 1.27)
					(thickness 0.15)
				)
			)
		)
		(property "Manufacturer" "Panasonic"
			(at 0 0 0)
			(unlocked yes)
			(layer "B.Fab")
			(hide yes)
			(effects
				(font
					(size 1 1)
					(thickness 0.15)
				)
				(justify mirror)
			)
		)
		(property "MPN" "ERJ2GE0R00X"
			(at 0 0 0)
			(unlocked yes)
			(layer "B.Fab")
			(hide yes)
			(effects
				(font
					(size 1 1)
					(thickness 0.15)
				)
				(justify mirror)
			)
		)
		(property "Val" "0R"
			(at 0 0 0)
			(unlocked yes)
			(layer "B.Fab")
			(hide yes)
			(effects
				(font
					(size 1 1)
					(thickness 0.15)
				)
				(justify mirror)
			)
		)
		(property "License" "Apache-2.0"
			(at 0 0 0)
			(unlocked yes)
			(layer "B.Fab")
			(hide yes)
			(effects
				(font
					(size 1 1)
					(thickness 0.15)
				)
				(justify mirror)
			)
		)
		(property "Author" "Antmicro"
			(at 0 0 0)
			(unlocked yes)
			(layer "B.Fab")
			(hide yes)
			(effects
				(font
					(size 1 1)
					(thickness 0.15)
				)
				(justify mirror)
			)
		)
		(property "Tolerance" "~"
			(at 0 0 0)
			(unlocked yes)
			(layer "B.Fab")
			(hide yes)
			(effects
				(font
					(size 1 1)
					(thickness 0.15)
				)
				(justify mirror)
			)
		)
		(property "Current" "1A"
			(at 0 0 0)
			(unlocked yes)
			(layer "B.Fab")
			(hide yes)
			(effects
				(font
					(size 1 1)
					(thickness 0.15)
				)
				(justify mirror)
			)
		)
		(sheetname "/Supply/DC-DC AUX, MGT/")
		(sheetfile "dc-dc-aux-mgt.kicad_sch")
		(attr smd exclude_from_bom dnp)
		(fp_rect
			(start -0.925 0.47)
			(end 0.925 -0.47)
			(stroke
				(width 0.05)
				(type default)
			)
			(fill no)
			(layer "B.CrtYd")
		)
		(fp_rect
			(start -0.5 0.25)
			(end 0.5 -0.25)
			(stroke
				(width 0.15)
				(type solid)
			)
			(fill no)
			(layer "B.Fab")
		)
		(fp_text user "Author: Antmicro"
			(at -0.95 -4.169 180)
			(layer "B.Fab")
			(effects
				(font
					(size 0.7 0.7)
					(thickness 0.15)
				)
				(justify left bottom mirror)
			)
		)
		(fp_text user "${REFERENCE}"
			(at -0.95 -3.168 180)
			(layer "B.Fab")
			(effects
				(font
					(size 0.7 0.7)
					(thickness 0.15)
				)
				(justify left bottom mirror)
			)
		)
		(fp_text user "License: Apache-2.0"
			(at -0.95 -5.169 180)
			(layer "B.Fab")
			(effects
				(font
					(size 0.7 0.7)
					(thickness 0.15)
				)
				(justify left bottom mirror)
			)
		)
		(pad "1" smd roundrect
			(at -0.48 0)
			(size 0.59 0.64)
			(layers "B.Cu" "B.Mask" "B.Paste")
			(roundrect_rratio 0.25)
			(net 1 "GND")
			(pintype "passive")
		)
		(pad "2" smd roundrect
			(at 0.48 0)
			(size 0.59 0.64)
			(layers "B.Cu" "B.Mask" "B.Paste")
			(roundrect_rratio 0.25)
			(net 712 "/Supply/DC-DC AUX, MGT/FB1")
			(pintype "passive")
		)
	)
	(footprint "antmicro-footprints:C_0402_1005Metric_EIA"
		(layer "B.Cu")
		(at 197 148.5 90)
		(descr "Capacitor SMD 0402 (1005 Metric), square (rectangular) end terminal, IPC_7351 nominal, (Body size source: IPC-SM-782 page 76, https://www.pcb-3d.com/wordpress/wp-content/uploads/ipc-sm-782a_amendment_1_and_2.pdf)")
		(tags "capacitor 0402")
		(property "Reference" "C20"
			(at -3.15 0.45 90)
			(layer "B.SilkS")
			(effects
				(font
					(size 0.7 0.7)
					(thickness 0.15)
				)
				(justify right bottom mirror)
			)
		)
		(property "Value" "C_100n_0402"
			(at 0 -1.169 90)
			(layer "B.Fab")
			(effects
				(font
					(size 0.7 0.7)
					(thickness 0.15)
				)
				(justify right bottom mirror)
			)
		)
		(property "Datasheet" "https://www.murata.com/products/productdetail?partno=GRM155R61H104KE14%23"
			(at 0 0 90)
			(layer "F.Fab")
			(hide yes)
			(effects
				(font
					(size 1.27 1.27)
					(thickness 0.15)
				)
			)
		)
		(property "MPN" "GRM155R61H104KE14D"
			(at 0 0 90)
			(unlocked yes)
			(layer "B.Fab")
			(hide yes)
			(effects
				(font
					(size 1 1)
					(thickness 0.15)
				)
				(justify mirror)
			)
		)
		(property "Manufacturer" "Murata"
			(at 0 0 90)
			(unlocked yes)
			(layer "B.Fab")
			(hide yes)
			(effects
				(font
					(size 1 1)
					(thickness 0.15)
				)
				(justify mirror)
			)
		)
		(property "License" "Apache-2.0"
			(at 0 0 90)
			(unlocked yes)
			(layer "B.Fab")
			(hide yes)
			(effects
				(font
					(size 1 1)
					(thickness 0.15)
				)
				(justify mirror)
			)
		)
		(property "Author" "Antmicro"
			(at 0 0 90)
			(unlocked yes)
			(layer "B.Fab")
			(hide yes)
			(effects
				(font
					(size 1 1)
					(thickness 0.15)
				)
				(justify mirror)
			)
		)
		(property "Val" "100n"
			(at 0 0 90)
			(unlocked yes)
			(layer "B.Fab")
			(hide yes)
			(effects
				(font
					(size 1 1)
					(thickness 0.15)
				)
				(justify mirror)
			)
		)
		(property "Voltage" "50V"
			(at 0 0 90)
			(unlocked yes)
			(layer "B.Fab")
			(hide yes)
			(effects
				(font
					(size 1 1)
					(thickness 0.15)
				)
				(justify mirror)
			)
		)
		(property "Dielectric" "X5R"
			(at 0 0 90)
			(unlocked yes)
			(layer "B.Fab")
			(hide yes)
			(effects
				(font
					(size 1 1)
					(thickness 0.15)
				)
				(justify mirror)
			)
		)
		(sheetname "/FPGA power/")
		(sheetfile "fpga-power.kicad_sch")
		(attr smd)
		(fp_rect
			(start -0.95 0.45)
			(end 0.95 -0.45)
			(stroke
				(width 0.05)
				(type default)
			)
			(fill no)
			(layer "B.CrtYd")
		)
		(fp_line
			(start 0.498 -0.248)
			(end -0.5 -0.248)
			(stroke
				(width 0.15)
				(type solid)
			)
			(layer "B.Fab")
		)
		(fp_line
			(start -0.5 -0.248)
			(end -0.5 0.25)
			(stroke
				(width 0.15)
				(type solid)
			)
			(layer "B.Fab")
		)
		(fp_line
			(start 0.498 0.25)
			(end 0.498 -0.248)
			(stroke
				(width 0.15)
				(type solid)
			)
			(layer "B.Fab")
		)
		(fp_line
			(start -0.5 0.25)
			(end 0.498 0.25)
			(stroke
				(width 0.15)
				(type solid)
			)
			(layer "B.Fab")
		)
		(fp_text user "${REFERENCE}"
			(at -0.9656 -3.169 270)
			(layer "B.Fab")
			(effects
				(font
					(size 0.7 0.7)
					(thickness 0.15)
				)
				(justify left bottom mirror)
			)
		)
		(fp_text user "License: Apache-2.0"
			(at -0.9656 -4.369 270)
			(layer "B.Fab")
			(effects
				(font
					(size 0.7 0.7)
					(thickness 0.15)
				)
				(justify left bottom mirror)
			)
		)
		(fp_text user "Author: Antmicro"
			(at -0.9656 -5.569 270)
			(layer "B.Fab")
			(effects
				(font
					(size 0.7 0.7)
					(thickness 0.15)
				)
				(justify left bottom mirror)
			)
		)
		(pad "1" smd roundrect
			(at -0.5 0)
			(size 0.6 0.6)
			(layers "B.Cu" "B.Mask" "B.Paste")
			(roundrect_rratio 0.25)
			(net 1 "GND")
			(pintype "passive")
		)
		(pad "2" smd roundrect
			(at 0.498 0 90)
			(size 0.6 0.6)
			(layers "B.Cu" "B.Mask" "B.Paste")
			(roundrect_rratio 0.25)
			(net 687 "VDDQ")
			(pintype "passive")
		)
	)
	(footprint "antmicro-footprints:C_0402_1005Metric"
		(layer "B.Cu")
		(at 176.65 193.249501 90)
		(descr "Capacitor SMD 0402")
		(tags "capacitor SMD 0402")
		(property "Reference" "C230"
			(at 0.994 0.403501 90)
			(layer "B.SilkS")
			(effects
				(font
					(size 0.7 0.7)
					(thickness 0.15)
				)
				(justify right bottom mirror)
			)
		)
		(property "Value" "C_100n_0402"
			(at -1.022927 -2.155213 90)
			(layer "B.Fab")
			(effects
				(font
					(size 0.7 0.7)
					(thickness 0.15)
				)
				(justify right bottom mirror)
			)
		)
		(property "Datasheet" "https://www.murata.com/products/productdetail?partno=GRM155R61H104KE14%23"
			(at 0 0 90)
			(layer "F.Fab")
			(hide yes)
			(effects
				(font
					(size 1.27 1.27)
					(thickness 0.15)
				)
			)
		)
		(property "Manufacturer" "Murata"
			(at 0 0 90)
			(unlocked yes)
			(layer "B.Fab")
			(hide yes)
			(effects
				(font
					(size 1 1)
					(thickness 0.15)
				)
				(justify mirror)
			)
		)
		(property "MPN" "GRM155R61H104KE14D"
			(at 0 0 90)
			(unlocked yes)
			(layer "B.Fab")
			(hide yes)
			(effects
				(font
					(size 1 1)
					(thickness 0.15)
				)
				(justify mirror)
			)
		)
		(property "Val" "100n"
			(at 0 0 90)
			(unlocked yes)
			(layer "B.Fab")
			(hide yes)
			(effects
				(font
					(size 1 1)
					(thickness 0.15)
				)
				(justify mirror)
			)
		)
		(property "License" "Apache-2.0"
			(at 0 0 90)
			(unlocked yes)
			(layer "B.Fab")
			(hide yes)
			(effects
				(font
					(size 1 1)
					(thickness 0.15)
				)
				(justify mirror)
			)
		)
		(property "Author" "Antmicro"
			(at 0 0 90)
			(unlocked yes)
			(layer "B.Fab")
			(hide yes)
			(effects
				(font
					(size 1 1)
					(thickness 0.15)
				)
				(justify mirror)
			)
		)
		(property "Voltage" "50V"
			(at 0 0 90)
			(unlocked yes)
			(layer "B.Fab")
			(hide yes)
			(effects
				(font
					(size 1 1)
					(thickness 0.15)
				)
				(justify mirror)
			)
		)
		(property "Dielectric" "X5R"
			(at 0 0 90)
			(unlocked yes)
			(layer "B.Fab")
			(hide yes)
			(effects
				(font
					(size 1 1)
					(thickness 0.15)
				)
				(justify mirror)
			)
		)
		(sheetname "/FPGA MGT Interface/")
		(sheetfile "fpga-mgt.kicad_sch")
		(attr smd)
		(fp_rect
			(start -0.925 0.47)
			(end 0.925 -0.47)
			(stroke
				(width 0.05)
				(type default)
			)
			(fill no)
			(layer "B.CrtYd")
		)
		(fp_line
			(start 0.504 -0.248)
			(end -0.494 -0.248)
			(stroke
				(width 0.15)
				(type solid)
			)
			(layer "B.Fab")
		)
		(fp_line
			(start -0.494 -0.248)
			(end -0.494 0.25)
			(stroke
				(width 0.15)
				(type solid)
			)
			(layer "B.Fab")
		)
		(fp_line
			(start 0.504 0.25)
			(end 0.504 -0.248)
			(stroke
				(width 0.15)
				(type solid)
			)
			(layer "B.Fab")
		)
		(fp_line
			(start -0.494 0.25)
			(end 0.504 0.25)
			(stroke
				(width 0.15)
				(type solid)
			)
			(layer "B.Fab")
		)
		(fp_text user "${REFERENCE}"
			(at -0.939 -4.599 270)
			(layer "B.Fab")
			(effects
				(font
					(size 0.7 0.7)
					(thickness 0.15)
				)
				(justify left bottom mirror)
			)
		)
		(fp_text user "License: Apache-2.0"
			(at -0.939 -5.799 270)
			(layer "B.Fab")
			(effects
				(font
					(size 0.7 0.7)
					(thickness 0.15)
				)
				(justify left bottom mirror)
			)
		)
		(fp_text user "Author: Antmicro"
			(at -0.939 -3.399 270)
			(layer "B.Fab")
			(effects
				(font
					(size 0.7 0.7)
					(thickness 0.15)
				)
				(justify left bottom mirror)
			)
		)
		(pad "1" smd roundrect
			(at -0.48 0 90)
			(size 0.59 0.64)
			(layers "B.Cu" "B.Mask" "B.Paste")
			(roundrect_rratio 0.25)
			(net 23 "/FPGA MGT Interface/PCIE.TXD3_N")
			(pintype "passive")
		)
		(pad "2" smd roundrect
			(at 0.48 0 90)
			(size 0.59 0.64)
			(layers "B.Cu" "B.Mask" "B.Paste")
			(roundrect_rratio 0.25)
			(net 24 "/FPGA MGT Interface/GTY_225_TX0_N")
			(pintype "passive")
		)
	)
	(footprint "antmicro-footprints:Fiducial_1mm_Mask2mm"
		(layer "B.Cu")
		(at 259.8 182.15 180)
		(descr "Circular Fiducial, 1mm bare copper, 3mm soldermask opening")
		(tags "fiducial")
		(property "Reference" "FID1002"
			(at -1.865 1.745 0)
			(layer "B.SilkS")
			(hide yes)
			(effects
				(font
					(size 0.7 0.7)
					(thickness 0.15)
				)
				(justify left bottom mirror)
			)
		)
		(property "Value" "Fiducial_1mm_Mask2mm"
			(at 0 -2.2 0)
			(layer "B.Fab")
			(effects
				(font
					(size 0.7 0.7)
					(thickness 0.15)
				)
				(justify left bottom mirror)
			)
		)
		(sheetfile "data-center-rdimm-ddr5-tester.kicad_sch")
		(attr board_only exclude_from_pos_files exclude_from_bom)
		(fp_circle
			(center 0 0)
			(end 1.24 0)
			(stroke
				(width 0.05)
				(type solid)
			)
			(fill no)
			(layer "B.CrtYd")
		)
		(fp_circle
			(center 0 0)
			(end 0.999 0)
			(stroke
				(width 0.15)
				(type solid)
			)
			(fill no)
			(layer "B.Fab")
		)
		(fp_text user "${REFERENCE}"
			(at -1.25 -4.603 0)
			(layer "B.Fab")
			(effects
				(font
					(size 0.7 0.7)
					(thickness 0.15)
				)
				(justify left bottom mirror)
			)
		)
		(fp_text user "License: Apache-2.0"
			(at -1.25 -7.003 0)
			(layer "B.Fab")
			(effects
				(font
					(size 0.7 0.7)
					(thickness 0.15)
				)
				(justify left bottom mirror)
			)
		)
		(fp_text user "Author: Antmicro"
			(at -1.25 -5.803 0)
			(layer "B.Fab")
			(effects
				(font
					(size 0.7 0.7)
					(thickness 0.15)
				)
				(justify left bottom mirror)
			)
		)
		(pad "" smd circle
			(at 0 0 180)
			(size 1 1)
			(layers "B.Cu" "B.Mask")
			(solder_mask_margin 0.5)
			(clearance 0.5)
		)
	)
	(footprint "antmicro-footprints:C_0402_1005Metric"
		(layer "B.Cu")
		(at 134.924499 152.9005 180)
		(descr "Capacitor SMD 0402")
		(tags "capacitor SMD 0402")
		(property "Reference" "C161"
			(at 1.320499 -0.5155 0)
			(layer "B.SilkS")
			(effects
				(font
					(size 0.7 0.7)
					(thickness 0.15)
				)
				(justify left bottom mirror)
			)
		)
		(property "Value" "C_100n_0402"
			(at -1.022927 -2.155213 0)
			(layer "B.Fab")
			(effects
				(font
					(size 0.7 0.7)
					(thickness 0.15)
				)
				(justify left bottom mirror)
			)
		)
		(property "Datasheet" "https://www.murata.com/products/productdetail?partno=GRM155R61H104KE14%23"
			(at 0 0 180)
			(layer "F.Fab")
			(hide yes)
			(effects
				(font
					(size 1.27 1.27)
					(thickness 0.15)
				)
			)
		)
		(property "MPN" "GRM155R61H104KE14D"
			(at 0 0 180)
			(unlocked yes)
			(layer "B.Fab")
			(hide yes)
			(effects
				(font
					(size 1 1)
					(thickness 0.15)
				)
				(justify mirror)
			)
		)
		(property "Manufacturer" "Murata"
			(at 0 0 180)
			(unlocked yes)
			(layer "B.Fab")
			(hide yes)
			(effects
				(font
					(size 1 1)
					(thickness 0.15)
				)
				(justify mirror)
			)
		)
		(property "License" "Apache-2.0"
			(at 0 0 180)
			(unlocked yes)
			(layer "B.Fab")
			(hide yes)
			(effects
				(font
					(size 1 1)
					(thickness 0.15)
				)
				(justify mirror)
			)
		)
		(property "Author" "Antmicro"
			(at 0 0 180)
			(unlocked yes)
			(layer "B.Fab")
			(hide yes)
			(effects
				(font
					(size 1 1)
					(thickness 0.15)
				)
				(justify mirror)
			)
		)
		(property "Val" "100n"
			(at 0 0 180)
			(unlocked yes)
			(layer "B.Fab")
			(hide yes)
			(effects
				(font
					(size 1 1)
					(thickness 0.15)
				)
				(justify mirror)
			)
		)
		(property "Voltage" "50V"
			(at 0 0 180)
			(unlocked yes)
			(layer "B.Fab")
			(hide yes)
			(effects
				(font
					(size 1 1)
					(thickness 0.15)
				)
				(justify mirror)
			)
		)
		(property "Dielectric" "X5R"
			(at 0 0 180)
			(unlocked yes)
			(layer "B.Fab")
			(hide yes)
			(effects
				(font
					(size 1 1)
					(thickness 0.15)
				)
				(justify mirror)
			)
		)
		(sheetname "/Ethernet/")
		(sheetfile "ethernet.kicad_sch")
		(attr smd)
		(fp_rect
			(start -0.925 0.47)
			(end 0.925 -0.47)
			(stroke
				(width 0.05)
				(type default)
			)
			(fill no)
			(layer "B.CrtYd")
		)
		(fp_line
			(start 0.504 0.25)
			(end 0.504 -0.248)
			(stroke
				(width 0.15)
				(type solid)
			)
			(layer "B.Fab")
		)
		(fp_line
			(start 0.504 -0.248)
			(end -0.494 -0.248)
			(stroke
				(width 0.15)
				(type solid)
			)
			(layer "B.Fab")
		)
		(fp_line
			(start -0.494 0.25)
			(end 0.504 0.25)
			(stroke
				(width 0.15)
				(type solid)
			)
			(layer "B.Fab")
		)
		(fp_line
			(start -0.494 -0.248)
			(end -0.494 0.25)
			(stroke
				(width 0.15)
				(type solid)
			)
			(layer "B.Fab")
		)
		(fp_text user "License: Apache-2.0"
			(at -0.939 -5.799 0)
			(layer "B.Fab")
			(effects
				(font
					(size 0.7 0.7)
					(thickness 0.15)
				)
				(justify left bottom mirror)
			)
		)
		(fp_text user "${REFERENCE}"
			(at -0.939 -4.599 0)
			(layer "B.Fab")
			(effects
				(font
					(size 0.7 0.7)
					(thickness 0.15)
				)
				(justify left bottom mirror)
			)
		)
		(fp_text user "Author: Antmicro"
			(at -0.939 -3.399 0)
			(layer "B.Fab")
			(effects
				(font
					(size 0.7 0.7)
					(thickness 0.15)
				)
				(justify left bottom mirror)
			)
		)
		(pad "1" smd roundrect
			(at -0.48 0 180)
			(size 0.59 0.64)
			(layers "B.Cu" "B.Mask" "B.Paste")
			(roundrect_rratio 0.25)
			(net 1 "GND")
			(pintype "passive")
		)
		(pad "2" smd roundrect
			(at 0.48 0 180)
			(size 0.59 0.64)
			(layers "B.Cu" "B.Mask" "B.Paste")
			(roundrect_rratio 0.25)
			(net 797 "+1V8")
			(pintype "passive")
		)
	)
	(footprint "antmicro-footprints:C_0402_1005Metric_EIA"
		(layer "B.Cu")
		(at 185.5 147)
		(descr "Capacitor SMD 0402 (1005 Metric), square (rectangular) end terminal, IPC_7351 nominal, (Body size source: IPC-SM-782 page 76, https://www.pcb-3d.com/wordpress/wp-content/uploads/ipc-sm-782a_amendment_1_and_2.pdf)")
		(tags "capacitor 0402")
		(property "Reference" "C27"
			(at -30.125 -10.3 180)
			(layer "B.SilkS")
			(effects
				(font
					(size 0.7 0.7)
					(thickness 0.15)
				)
				(justify left bottom mirror)
			)
		)
		(property "Value" "C_10u_10V_0402"
			(at 0 -1.169 180)
			(layer "B.Fab")
			(effects
				(font
					(size 0.7 0.7)
					(thickness 0.15)
				)
				(justify left bottom mirror)
			)
		)
		(property "Datasheet" "https://www.murata.com/products/productdetail?partno=GRM155R61A106ME11%23"
			(at 0 0 0)
			(layer "F.Fab")
			(hide yes)
			(effects
				(font
					(size 1.27 1.27)
					(thickness 0.15)
				)
			)
		)
		(property "MPN" "GRM155R61A106ME11D"
			(at 0 0 0)
			(unlocked yes)
			(layer "B.Fab")
			(hide yes)
			(effects
				(font
					(size 1 1)
					(thickness 0.15)
				)
				(justify mirror)
			)
		)
		(property "Manufacturer" "Murata"
			(at 0 0 0)
			(unlocked yes)
			(layer "B.Fab")
			(hide yes)
			(effects
				(font
					(size 1 1)
					(thickness 0.15)
				)
				(justify mirror)
			)
		)
		(property "License" "Apache-2.0"
			(at 0 0 0)
			(unlocked yes)
			(layer "B.Fab")
			(hide yes)
			(effects
				(font
					(size 1 1)
					(thickness 0.15)
				)
				(justify mirror)
			)
		)
		(property "Author" "Antmicro"
			(at 0 0 0)
			(unlocked yes)
			(layer "B.Fab")
			(hide yes)
			(effects
				(font
					(size 1 1)
					(thickness 0.15)
				)
				(justify mirror)
			)
		)
		(property "Val" "10u"
			(at 0 0 0)
			(unlocked yes)
			(layer "B.Fab")
			(hide yes)
			(effects
				(font
					(size 1 1)
					(thickness 0.15)
				)
				(justify mirror)
			)
		)
		(property "Voltage" "10V"
			(at 0 0 0)
			(unlocked yes)
			(layer "B.Fab")
			(hide yes)
			(effects
				(font
					(size 1 1)
					(thickness 0.15)
				)
				(justify mirror)
			)
		)
		(property "Dielectric" "X5R"
			(at 0 0 0)
			(unlocked yes)
			(layer "B.Fab")
			(hide yes)
			(effects
				(font
					(size 1 1)
					(thickness 0.15)
				)
				(justify mirror)
			)
		)
		(sheetname "/FPGA power/")
		(sheetfile "fpga-power.kicad_sch")
		(attr smd)
		(fp_rect
			(start -0.95 0.45)
			(end 0.95 -0.45)
			(stroke
				(width 0.05)
				(type default)
			)
			(fill no)
			(layer "B.CrtYd")
		)
		(fp_line
			(start -0.5 -0.248)
			(end -0.5 0.25)
			(stroke
				(width 0.15)
				(type solid)
			)
			(layer "B.Fab")
		)
		(fp_line
			(start -0.5 0.25)
			(end 0.498 0.25)
			(stroke
				(width 0.15)
				(type solid)
			)
			(layer "B.Fab")
		)
		(fp_line
			(start 0.498 -0.248)
			(end -0.5 -0.248)
			(stroke
				(width 0.15)
				(type solid)
			)
			(layer "B.Fab")
		)
		(fp_line
			(start 0.498 0.25)
			(end 0.498 -0.248)
			(stroke
				(width 0.15)
				(type solid)
			)
			(layer "B.Fab")
		)
		(fp_text user "Author: Antmicro"
			(at -0.9656 -5.569 180)
			(layer "B.Fab")
			(effects
				(font
					(size 0.7 0.7)
					(thickness 0.15)
				)
				(justify left bottom mirror)
			)
		)
		(fp_text user "${REFERENCE}"
			(at -0.9656 -3.169 180)
			(layer "B.Fab")
			(effects
				(font
					(size 0.7 0.7)
					(thickness 0.15)
				)
				(justify left bottom mirror)
			)
		)
		(fp_text user "License: Apache-2.0"
			(at -0.9656 -4.369 180)
			(layer "B.Fab")
			(effects
				(font
					(size 0.7 0.7)
					(thickness 0.15)
				)
				(justify left bottom mirror)
			)
		)
		(pad "1" smd roundrect
			(at -0.5 0 270)
			(size 0.6 0.6)
			(layers "B.Cu" "B.Mask" "B.Paste")
			(roundrect_rratio 0.25)
			(net 1 "GND")
			(pintype "passive")
		)
		(pad "2" smd roundrect
			(at 0.498 0)
			(size 0.6 0.6)
			(layers "B.Cu" "B.Mask" "B.Paste")
			(roundrect_rratio 0.25)
			(net 797 "+1V8")
			(pintype "passive")
		)
	)
	(footprint "antmicro-footprints:C_0402_1005Metric"
		(layer "B.Cu")
		(at 207.29 154.19 90)
		(descr "Capacitor SMD 0402")
		(tags "capacitor SMD 0402")
		(property "Reference" "C223"
			(at -4.22 0.47 90)
			(layer "B.SilkS")
			(effects
				(font
					(size 0.7 0.7)
					(thickness 0.15)
				)
				(justify right bottom mirror)
			)
		)
		(property "Value" "C_100n_0402"
			(at -1.022927 -2.155213 90)
			(layer "B.Fab")
			(effects
				(font
					(size 0.7 0.7)
					(thickness 0.15)
				)
				(justify right bottom mirror)
			)
		)
		(property "Datasheet" "https://www.murata.com/products/productdetail?partno=GRM155R61H104KE14%23"
			(at 0 0 90)
			(layer "F.Fab")
			(hide yes)
			(effects
				(font
					(size 1.27 1.27)
					(thickness 0.15)
				)
			)
		)
		(property "Manufacturer" "Murata"
			(at 0 0 90)
			(unlocked yes)
			(layer "B.Fab")
			(hide yes)
			(effects
				(font
					(size 1 1)
					(thickness 0.15)
				)
				(justify mirror)
			)
		)
		(property "MPN" "GRM155R61H104KE14D"
			(at 0 0 90)
			(unlocked yes)
			(layer "B.Fab")
			(hide yes)
			(effects
				(font
					(size 1 1)
					(thickness 0.15)
				)
				(justify mirror)
			)
		)
		(property "Val" "100n"
			(at 0 0 90)
			(unlocked yes)
			(layer "B.Fab")
			(hide yes)
			(effects
				(font
					(size 1 1)
					(thickness 0.15)
				)
				(justify mirror)
			)
		)
		(property "License" "Apache-2.0"
			(at 0 0 90)
			(unlocked yes)
			(layer "B.Fab")
			(hide yes)
			(effects
				(font
					(size 1 1)
					(thickness 0.15)
				)
				(justify mirror)
			)
		)
		(property "Author" "Antmicro"
			(at 0 0 90)
			(unlocked yes)
			(layer "B.Fab")
			(hide yes)
			(effects
				(font
					(size 1 1)
					(thickness 0.15)
				)
				(justify mirror)
			)
		)
		(property "Voltage" "50V"
			(at 0 0 90)
			(unlocked yes)
			(layer "B.Fab")
			(hide yes)
			(effects
				(font
					(size 1 1)
					(thickness 0.15)
				)
				(justify mirror)
			)
		)
		(property "Dielectric" "X5R"
			(at 0 0 90)
			(unlocked yes)
			(layer "B.Fab")
			(hide yes)
			(effects
				(font
					(size 1 1)
					(thickness 0.15)
				)
				(justify mirror)
			)
		)
		(sheetname "/FPGA Config/")
		(sheetfile "fpga-config.kicad_sch")
		(attr smd)
		(fp_rect
			(start -0.925 0.47)
			(end 0.925 -0.47)
			(stroke
				(width 0.05)
				(type default)
			)
			(fill no)
			(layer "B.CrtYd")
		)
		(fp_line
			(start 0.504 -0.248)
			(end -0.494 -0.248)
			(stroke
				(width 0.15)
				(type solid)
			)
			(layer "B.Fab")
		)
		(fp_line
			(start -0.494 -0.248)
			(end -0.494 0.25)
			(stroke
				(width 0.15)
				(type solid)
			)
			(layer "B.Fab")
		)
		(fp_line
			(start 0.504 0.25)
			(end 0.504 -0.248)
			(stroke
				(width 0.15)
				(type solid)
			)
			(layer "B.Fab")
		)
		(fp_line
			(start -0.494 0.25)
			(end 0.504 0.25)
			(stroke
				(width 0.15)
				(type solid)
			)
			(layer "B.Fab")
		)
		(fp_text user "License: Apache-2.0"
			(at -0.939 -5.799 270)
			(layer "B.Fab")
			(effects
				(font
					(size 0.7 0.7)
					(thickness 0.15)
				)
				(justify left bottom mirror)
			)
		)
		(fp_text user "Author: Antmicro"
			(at -0.939 -3.399 270)
			(layer "B.Fab")
			(effects
				(font
					(size 0.7 0.7)
					(thickness 0.15)
				)
				(justify left bottom mirror)
			)
		)
		(fp_text user "${REFERENCE}"
			(at -0.939 -4.599 270)
			(layer "B.Fab")
			(effects
				(font
					(size 0.7 0.7)
					(thickness 0.15)
				)
				(justify left bottom mirror)
			)
		)
		(pad "1" smd roundrect
			(at -0.48 0 90)
			(size 0.59 0.64)
			(layers "B.Cu" "B.Mask" "B.Paste")
			(roundrect_rratio 0.25)
			(net 1 "GND")
			(pintype "passive")
		)
		(pad "2" smd roundrect
			(at 0.48 0 90)
			(size 0.59 0.64)
			(layers "B.Cu" "B.Mask" "B.Paste")
			(roundrect_rratio 0.25)
			(net 151 "+3V3")
			(pintype "passive")
		)
	)
	(footprint "antmicro-footprints:R_0402_1005Metric"
		(layer "B.Cu")
		(at 243.05 101.6 180)
		(descr "Resistor SMD 0402")
		(tags "resistor SMD 0402")
		(property "Reference" "R246"
			(at 0.87 -0.38 0)
			(layer "B.SilkS")
			(effects
				(font
					(size 0.7 0.7)
					(thickness 0.15)
				)
				(justify left bottom mirror)
			)
		)
		(property "Value" "R_330R_0402"
			(at -1.011843 -1.772047 0)
			(layer "B.Fab")
			(effects
				(font
					(size 0.7 0.7)
					(thickness 0.15)
				)
				(justify left bottom mirror)
			)
		)
		(property "Datasheet" "https://www.bourns.com/docs/product-datasheets/cr.pdf"
			(at 0 0 0)
			(layer "F.Fab")
			(hide yes)
			(effects
				(font
					(size 1.27 1.27)
					(thickness 0.15)
				)
			)
		)
		(property "MPN" "CR0402-FX-3300GLF"
			(at 0 0 180)
			(unlocked yes)
			(layer "B.Fab")
			(hide yes)
			(effects
				(font
					(size 1 1)
					(thickness 0.15)
				)
				(justify mirror)
			)
		)
		(property "Manufacturer" "Bourns"
			(at 0 0 180)
			(unlocked yes)
			(layer "B.Fab")
			(hide yes)
			(effects
				(font
					(size 1 1)
					(thickness 0.15)
				)
				(justify mirror)
			)
		)
		(property "License" "Apache-2.0"
			(at 0 0 180)
			(unlocked yes)
			(layer "B.Fab")
			(hide yes)
			(effects
				(font
					(size 1 1)
					(thickness 0.15)
				)
				(justify mirror)
			)
		)
		(property "Author" "Antmicro"
			(at 0 0 180)
			(unlocked yes)
			(layer "B.Fab")
			(hide yes)
			(effects
				(font
					(size 1 1)
					(thickness 0.15)
				)
				(justify mirror)
			)
		)
		(property "Val" "330R"
			(at 0 0 180)
			(unlocked yes)
			(layer "B.Fab")
			(hide yes)
			(effects
				(font
					(size 1 1)
					(thickness 0.15)
				)
				(justify mirror)
			)
		)
		(property "Tolerance" "1%"
			(at 0 0 180)
			(unlocked yes)
			(layer "B.Fab")
			(hide yes)
			(effects
				(font
					(size 1 1)
					(thickness 0.15)
				)
				(justify mirror)
			)
		)
		(sheetname "/DDR5 RDIMM/")
		(sheetfile "ddr5-rdimm.kicad_sch")
		(attr smd)
		(fp_rect
			(start -0.925 0.47)
			(end 0.925 -0.47)
			(stroke
				(width 0.05)
				(type default)
			)
			(fill no)
			(layer "B.CrtYd")
		)
		(fp_rect
			(start -0.5 0.25)
			(end 0.5 -0.25)
			(stroke
				(width 0.15)
				(type solid)
			)
			(fill no)
			(layer "B.Fab")
		)
		(fp_text user "License: Apache-2.0"
			(at -0.95 -5.169 0)
			(layer "B.Fab")
			(effects
				(font
					(size 0.7 0.7)
					(thickness 0.15)
				)
				(justify left bottom mirror)
			)
		)
		(fp_text user "Author: Antmicro"
			(at -0.95 -4.169 0)
			(layer "B.Fab")
			(effects
				(font
					(size 0.7 0.7)
					(thickness 0.15)
				)
				(justify left bottom mirror)
			)
		)
		(fp_text user "${REFERENCE}"
			(at -0.95 -3.168 0)
			(layer "B.Fab")
			(effects
				(font
					(size 0.7 0.7)
					(thickness 0.15)
				)
				(justify left bottom mirror)
			)
		)
		(pad "1" smd roundrect
			(at -0.48 0 180)
			(size 0.59 0.64)
			(layers "B.Cu" "B.Mask" "B.Paste")
			(roundrect_rratio 0.25)
			(net 1 "GND")
			(pintype "passive")
		)
		(pad "2" smd roundrect
			(at 0.48 0 180)
			(size 0.59 0.64)
			(layers "B.Cu" "B.Mask" "B.Paste")
			(roundrect_rratio 0.25)
			(net 805 "Net-(D22-C)")
			(pintype "passive")
		)
	)
	(footprint "antmicro-footprints:R_0402_1005Metric"
		(layer "B.Cu")
		(at 231.685 182.995)
		(descr "Resistor SMD 0402")
		(tags "resistor SMD 0402")
		(property "Reference" "R195"
			(at -1.815 -1.555 0)
			(layer "B.SilkS")
			(effects
				(font
					(size 0.7 0.7)
					(thickness 0.15)
				)
				(justify right bottom mirror)
			)
		)
		(property "Value" "R_60k4_0402"
			(at -1.011843 -1.772047 0)
			(layer "B.Fab")
			(effects
				(font
					(size 0.7 0.7)
					(thickness 0.15)
				)
				(justify right bottom mirror)
			)
		)
		(property "Datasheet" "https://www.bourns.com/docs/product-datasheets/cr.pdf"
			(at 0 0 0)
			(layer "F.Fab")
			(hide yes)
			(effects
				(font
					(size 1.27 1.27)
					(thickness 0.15)
				)
			)
		)
		(property "MPN" "CR0402-FX-6042GLF"
			(at 0 0 0)
			(unlocked yes)
			(layer "B.Fab")
			(hide yes)
			(effects
				(font
					(size 1 1)
					(thickness 0.15)
				)
				(justify mirror)
			)
		)
		(property "Manufacturer" "Bourns"
			(at 0 0 0)
			(unlocked yes)
			(layer "B.Fab")
			(hide yes)
			(effects
				(font
					(size 1 1)
					(thickness 0.15)
				)
				(justify mirror)
			)
		)
		(property "License" "Apache-2.0"
			(at 0 0 0)
			(unlocked yes)
			(layer "B.Fab")
			(hide yes)
			(effects
				(font
					(size 1 1)
					(thickness 0.15)
				)
				(justify mirror)
			)
		)
		(property "Author" "Antmicro"
			(at 0 0 0)
			(unlocked yes)
			(layer "B.Fab")
			(hide yes)
			(effects
				(font
					(size 1 1)
					(thickness 0.15)
				)
				(justify mirror)
			)
		)
		(property "Val" "60k4"
			(at 0 0 0)
			(unlocked yes)
			(layer "B.Fab")
			(hide yes)
			(effects
				(font
					(size 1 1)
					(thickness 0.15)
				)
				(justify mirror)
			)
		)
		(property "Tolerance" "1%"
			(at 0 0 0)
			(unlocked yes)
			(layer "B.Fab")
			(hide yes)
			(effects
				(font
					(size 1 1)
					(thickness 0.15)
				)
				(justify mirror)
			)
		)
		(sheetname "/Supply/DC-DC VCCINT/")
		(sheetfile "dc-dc-vccint.kicad_sch")
		(attr smd)
		(fp_rect
			(start -0.925 0.47)
			(end 0.925 -0.47)
			(stroke
				(width 0.05)
				(type default)
			)
			(fill no)
			(layer "B.CrtYd")
		)
		(fp_rect
			(start -0.5 0.25)
			(end 0.5 -0.25)
			(stroke
				(width 0.15)
				(type solid)
			)
			(fill no)
			(layer "B.Fab")
		)
		(fp_text user "${REFERENCE}"
			(at -0.95 -3.168 180)
			(layer "B.Fab")
			(effects
				(font
					(size 0.7 0.7)
					(thickness 0.15)
				)
				(justify left bottom mirror)
			)
		)
		(fp_text user "License: Apache-2.0"
			(at -0.95 -5.169 180)
			(layer "B.Fab")
			(effects
				(font
					(size 0.7 0.7)
					(thickness 0.15)
				)
				(justify left bottom mirror)
			)
		)
		(fp_text user "Author: Antmicro"
			(at -0.95 -4.169 180)
			(layer "B.Fab")
			(effects
				(font
					(size 0.7 0.7)
					(thickness 0.15)
				)
				(justify left bottom mirror)
			)
		)
		(pad "1" smd roundrect
			(at -0.48 0)
			(size 0.59 0.64)
			(layers "B.Cu" "B.Mask" "B.Paste")
			(roundrect_rratio 0.25)
			(net 1 "GND")
			(pintype "passive")
		)
		(pad "2" smd roundrect
			(at 0.48 0)
			(size 0.59 0.64)
			(layers "B.Cu" "B.Mask" "B.Paste")
			(roundrect_rratio 0.25)
			(net 726 "Net-(U36-I_{REF})")
			(pintype "passive")
		)
	)
	(footprint "antmicro-footprints:C_0402_1005Metric"
		(layer "B.Cu")
		(at 122.95 148.61)
		(descr "Capacitor SMD 0402")
		(tags "capacitor SMD 0402")
		(property "Reference" "C302"
			(at 2.4 0.872 0)
			(layer "B.SilkS")
			(effects
				(font
					(size 0.7 0.7)
					(thickness 0.15)
				)
				(justify right bottom mirror)
			)
		)
		(property "Value" "C_100n_0402"
			(at -1.022927 -2.155213 0)
			(layer "B.Fab")
			(effects
				(font
					(size 0.7 0.7)
					(thickness 0.15)
				)
				(justify right bottom mirror)
			)
		)
		(property "Datasheet" "https://www.murata.com/products/productdetail?partno=GRM155R61H104KE14%23"
			(at 0 0 0)
			(layer "F.Fab")
			(hide yes)
			(effects
				(font
					(size 1.27 1.27)
					(thickness 0.15)
				)
			)
		)
		(property "Manufacturer" "Murata"
			(at 0 0 0)
			(unlocked yes)
			(layer "B.Fab")
			(hide yes)
			(effects
				(font
					(size 1 1)
					(thickness 0.15)
				)
				(justify mirror)
			)
		)
		(property "MPN" "GRM155R61H104KE14D"
			(at 0 0 0)
			(unlocked yes)
			(layer "B.Fab")
			(hide yes)
			(effects
				(font
					(size 1 1)
					(thickness 0.15)
				)
				(justify mirror)
			)
		)
		(property "Val" "100n"
			(at 0 0 0)
			(unlocked yes)
			(layer "B.Fab")
			(hide yes)
			(effects
				(font
					(size 1 1)
					(thickness 0.15)
				)
				(justify mirror)
			)
		)
		(property "License" "Apache-2.0"
			(at 0 0 0)
			(unlocked yes)
			(layer "B.Fab")
			(hide yes)
			(effects
				(font
					(size 1 1)
					(thickness 0.15)
				)
				(justify mirror)
			)
		)
		(property "Author" "Antmicro"
			(at 0 0 0)
			(unlocked yes)
			(layer "B.Fab")
			(hide yes)
			(effects
				(font
					(size 1 1)
					(thickness 0.15)
				)
				(justify mirror)
			)
		)
		(property "Voltage" "50V"
			(at 0 0 0)
			(unlocked yes)
			(layer "B.Fab")
			(hide yes)
			(effects
				(font
					(size 1 1)
					(thickness 0.15)
				)
				(justify mirror)
			)
		)
		(property "Dielectric" "X5R"
			(at 0 0 0)
			(unlocked yes)
			(layer "B.Fab")
			(hide yes)
			(effects
				(font
					(size 1 1)
					(thickness 0.15)
				)
				(justify mirror)
			)
		)
		(sheetname "/FPGA MGT Interface/")
		(sheetfile "fpga-mgt.kicad_sch")
		(attr smd)
		(fp_rect
			(start -0.925 0.47)
			(end 0.925 -0.47)
			(stroke
				(width 0.05)
				(type default)
			)
			(fill no)
			(layer "B.CrtYd")
		)
		(fp_line
			(start -0.494 -0.248)
			(end -0.494 0.25)
			(stroke
				(width 0.15)
				(type solid)
			)
			(layer "B.Fab")
		)
		(fp_line
			(start -0.494 0.25)
			(end 0.504 0.25)
			(stroke
				(width 0.15)
				(type solid)
			)
			(layer "B.Fab")
		)
		(fp_line
			(start 0.504 -0.248)
			(end -0.494 -0.248)
			(stroke
				(width 0.15)
				(type solid)
			)
			(layer "B.Fab")
		)
		(fp_line
			(start 0.504 0.25)
			(end 0.504 -0.248)
			(stroke
				(width 0.15)
				(type solid)
			)
			(layer "B.Fab")
		)
		(fp_text user "Author: Antmicro"
			(at -0.939 -3.399 180)
			(layer "B.Fab")
			(effects
				(font
					(size 0.7 0.7)
					(thickness 0.15)
				)
				(justify left bottom mirror)
			)
		)
		(fp_text user "${REFERENCE}"
			(at -0.939 -4.599 180)
			(layer "B.Fab")
			(effects
				(font
					(size 0.7 0.7)
					(thickness 0.15)
				)
				(justify left bottom mirror)
			)
		)
		(fp_text user "License: Apache-2.0"
			(at -0.939 -5.799 180)
			(layer "B.Fab")
			(effects
				(font
					(size 0.7 0.7)
					(thickness 0.15)
				)
				(justify left bottom mirror)
			)
		)
		(pad "1" smd roundrect
			(at -0.48 0)
			(size 0.59 0.64)
			(layers "B.Cu" "B.Mask" "B.Paste")
			(roundrect_rratio 0.25)
			(net 342 "/FPGA MGT Interface/HDMI_IN.D2_N")
			(pintype "passive")
		)
		(pad "2" smd roundrect
			(at 0.48 0)
			(size 0.59 0.64)
			(layers "B.Cu" "B.Mask" "B.Paste")
			(roundrect_rratio 0.25)
			(net 648 "/FPGA MGT Interface/HDMI_FPGA.RX2_N")
			(pintype "passive")
		)
	)
	(footprint "antmicro-footprints:R_0402_1005Metric"
		(layer "B.Cu")
		(at 102.6 102.1 -90)
		(descr "Resistor SMD 0402")
		(tags "resistor SMD 0402")
		(property "Reference" "R46"
			(at -1.122484 0.772697 90)
			(layer "B.SilkS")
			(effects
				(font
					(size 0.7 0.7)
					(thickness 0.15)
				)
				(justify left bottom mirror)
			)
		)
		(property "Value" "R_330R_0402"
			(at -1.011843 -1.772047 90)
			(layer "B.Fab")
			(effects
				(font
					(size 0.7 0.7)
					(thickness 0.15)
				)
				(justify left bottom mirror)
			)
		)
		(property "Datasheet" "https://www.bourns.com/docs/product-datasheets/cr.pdf"
			(at 0 0 270)
			(layer "F.Fab")
			(hide yes)
			(effects
				(font
					(size 1.27 1.27)
					(thickness 0.15)
				)
			)
		)
		(property "Manufacturer" "Bourns"
			(at 0 0 270)
			(unlocked yes)
			(layer "B.Fab")
			(hide yes)
			(effects
				(font
					(size 1 1)
					(thickness 0.15)
				)
				(justify mirror)
			)
		)
		(property "MPN" "CR0402-FX-3300GLF"
			(at 0 0 270)
			(unlocked yes)
			(layer "B.Fab")
			(hide yes)
			(effects
				(font
					(size 1 1)
					(thickness 0.15)
				)
				(justify mirror)
			)
		)
		(property "Val" "330R"
			(at 0 0 270)
			(unlocked yes)
			(layer "B.Fab")
			(hide yes)
			(effects
				(font
					(size 1 1)
					(thickness 0.15)
				)
				(justify mirror)
			)
		)
		(property "License" "Apache-2.0"
			(at 0 0 270)
			(unlocked yes)
			(layer "B.Fab")
			(hide yes)
			(effects
				(font
					(size 1 1)
					(thickness 0.15)
				)
				(justify mirror)
			)
		)
		(property "Author" "Antmicro"
			(at 0 0 270)
			(unlocked yes)
			(layer "B.Fab")
			(hide yes)
			(effects
				(font
					(size 1 1)
					(thickness 0.15)
				)
				(justify mirror)
			)
		)
		(property "Tolerance" "1%"
			(at 0 0 270)
			(unlocked yes)
			(layer "B.Fab")
			(hide yes)
			(effects
				(font
					(size 1 1)
					(thickness 0.15)
				)
				(justify mirror)
			)
		)
		(sheetname "/FPGA banks HD/")
		(sheetfile "fpga-hd-banks.kicad_sch")
		(attr smd)
		(fp_rect
			(start -0.925 0.47)
			(end 0.925 -0.47)
			(stroke
				(width 0.05)
				(type default)
			)
			(fill no)
			(layer "B.CrtYd")
		)
		(fp_rect
			(start -0.5 0.25)
			(end 0.5 -0.25)
			(stroke
				(width 0.15)
				(type solid)
			)
			(fill no)
			(layer "B.Fab")
		)
		(fp_text user "License: Apache-2.0"
			(at -0.95 -5.169 90)
			(layer "B.Fab")
			(effects
				(font
					(size 0.7 0.7)
					(thickness 0.15)
				)
				(justify left bottom mirror)
			)
		)
		(fp_text user "${REFERENCE}"
			(at -0.95 -3.168 90)
			(layer "B.Fab")
			(effects
				(font
					(size 0.7 0.7)
					(thickness 0.15)
				)
				(justify left bottom mirror)
			)
		)
		(fp_text user "Author: Antmicro"
			(at -0.95 -4.169 90)
			(layer "B.Fab")
			(effects
				(font
					(size 0.7 0.7)
					(thickness 0.15)
				)
				(justify left bottom mirror)
			)
		)
		(pad "1" smd roundrect
			(at -0.48 0 270)
			(size 0.59 0.64)
			(layers "B.Cu" "B.Mask" "B.Paste")
			(roundrect_rratio 0.25)
			(net 233 "Net-(D8-A)")
			(pintype "passive")
		)
		(pad "2" smd roundrect
			(at 0.48 0 270)
			(size 0.59 0.64)
			(layers "B.Cu" "B.Mask" "B.Paste")
			(roundrect_rratio 0.25)
			(net 276 "Net-(Q8-D)")
			(pintype "passive")
		)
	)
	(footprint "antmicro-footprints:C_0402_1005Metric_EIA"
		(layer "B.Cu")
		(at 192 148.5 90)
		(descr "Capacitor SMD 0402 (1005 Metric), square (rectangular) end terminal, IPC_7351 nominal, (Body size source: IPC-SM-782 page 76, https://www.pcb-3d.com/wordpress/wp-content/uploads/ipc-sm-782a_amendment_1_and_2.pdf)")
		(tags "capacitor 0402")
		(property "Reference" "C57"
			(at 10.2 -30.65 90)
			(layer "B.SilkS")
			(effects
				(font
					(size 0.7 0.7)
					(thickness 0.15)
				)
				(justify right bottom mirror)
			)
		)
		(property "Value" "C_1u_25V_0402"
			(at 0 -1.169 90)
			(layer "B.Fab")
			(effects
				(font
					(size 0.7 0.7)
					(thickness 0.15)
				)
				(justify right bottom mirror)
			)
		)
		(property "Datasheet" "https://www.murata.com/products/productdetail?partno=GRM155R61E105KE11%23"
			(at 0 0 90)
			(layer "F.Fab")
			(hide yes)
			(effects
				(font
					(size 1.27 1.27)
					(thickness 0.15)
				)
			)
		)
		(property "MPN" "GRM155R61E105KE11J"
			(at 0 0 90)
			(unlocked yes)
			(layer "B.Fab")
			(hide yes)
			(effects
				(font
					(size 1 1)
					(thickness 0.15)
				)
				(justify mirror)
			)
		)
		(property "Manufacturer" "Murata"
			(at 0 0 90)
			(unlocked yes)
			(layer "B.Fab")
			(hide yes)
			(effects
				(font
					(size 1 1)
					(thickness 0.15)
				)
				(justify mirror)
			)
		)
		(property "License" "Apache-2.0"
			(at 0 0 90)
			(unlocked yes)
			(layer "B.Fab")
			(hide yes)
			(effects
				(font
					(size 1 1)
					(thickness 0.15)
				)
				(justify mirror)
			)
		)
		(property "Author" "Antmicro"
			(at 0 0 90)
			(unlocked yes)
			(layer "B.Fab")
			(hide yes)
			(effects
				(font
					(size 1 1)
					(thickness 0.15)
				)
				(justify mirror)
			)
		)
		(property "Val" "1u"
			(at 0 0 90)
			(unlocked yes)
			(layer "B.Fab")
			(hide yes)
			(effects
				(font
					(size 1 1)
					(thickness 0.15)
				)
				(justify mirror)
			)
		)
		(property "Voltage" "25V"
			(at 0 0 90)
			(unlocked yes)
			(layer "B.Fab")
			(hide yes)
			(effects
				(font
					(size 1 1)
					(thickness 0.15)
				)
				(justify mirror)
			)
		)
		(property "Dielectric" "X5R"
			(at 0 0 90)
			(unlocked yes)
			(layer "B.Fab")
			(hide yes)
			(effects
				(font
					(size 1 1)
					(thickness 0.15)
				)
				(justify mirror)
			)
		)
		(sheetname "/FPGA power/")
		(sheetfile "fpga-power.kicad_sch")
		(attr smd)
		(fp_rect
			(start -0.95 0.45)
			(end 0.95 -0.45)
			(stroke
				(width 0.05)
				(type default)
			)
			(fill no)
			(layer "B.CrtYd")
		)
		(fp_line
			(start 0.498 -0.248)
			(end -0.5 -0.248)
			(stroke
				(width 0.15)
				(type solid)
			)
			(layer "B.Fab")
		)
		(fp_line
			(start -0.5 -0.248)
			(end -0.5 0.25)
			(stroke
				(width 0.15)
				(type solid)
			)
			(layer "B.Fab")
		)
		(fp_line
			(start 0.498 0.25)
			(end 0.498 -0.248)
			(stroke
				(width 0.15)
				(type solid)
			)
			(layer "B.Fab")
		)
		(fp_line
			(start -0.5 0.25)
			(end 0.498 0.25)
			(stroke
				(width 0.15)
				(type solid)
			)
			(layer "B.Fab")
		)
		(fp_text user "License: Apache-2.0"
			(at -0.9656 -4.369 270)
			(layer "B.Fab")
			(effects
				(font
					(size 0.7 0.7)
					(thickness 0.15)
				)
				(justify left bottom mirror)
			)
		)
		(fp_text user "Author: Antmicro"
			(at -0.9656 -5.569 270)
			(layer "B.Fab")
			(effects
				(font
					(size 0.7 0.7)
					(thickness 0.15)
				)
				(justify left bottom mirror)
			)
		)
		(fp_text user "${REFERENCE}"
			(at -0.9656 -3.169 270)
			(layer "B.Fab")
			(effects
				(font
					(size 0.7 0.7)
					(thickness 0.15)
				)
				(justify left bottom mirror)
			)
		)
		(pad "1" smd roundrect
			(at -0.5 0)
			(size 0.6 0.6)
			(layers "B.Cu" "B.Mask" "B.Paste")
			(roundrect_rratio 0.25)
			(net 1 "GND")
			(pintype "passive")
		)
		(pad "2" smd roundrect
			(at 0.498 0 90)
			(size 0.6 0.6)
			(layers "B.Cu" "B.Mask" "B.Paste")
			(roundrect_rratio 0.25)
			(net 553 "+0V85")
			(pintype "passive")
		)
	)
	(footprint "antmicro-footprints:R_0402_1005Metric"
		(layer "B.Cu")
		(at 105.3 102.1 -90)
		(descr "Resistor SMD 0402")
		(tags "resistor SMD 0402")
		(property "Reference" "R45"
			(at -1.122484 0.772697 90)
			(layer "B.SilkS")
			(effects
				(font
					(size 0.7 0.7)
					(thickness 0.15)
				)
				(justify left bottom mirror)
			)
		)
		(property "Value" "R_330R_0402"
			(at -1.011843 -1.772047 90)
			(layer "B.Fab")
			(effects
				(font
					(size 0.7 0.7)
					(thickness 0.15)
				)
				(justify left bottom mirror)
			)
		)
		(property "Datasheet" "https://www.bourns.com/docs/product-datasheets/cr.pdf"
			(at 0 0 270)
			(layer "F.Fab")
			(hide yes)
			(effects
				(font
					(size 1.27 1.27)
					(thickness 0.15)
				)
			)
		)
		(property "Manufacturer" "Bourns"
			(at 0 0 270)
			(unlocked yes)
			(layer "B.Fab")
			(hide yes)
			(effects
				(font
					(size 1 1)
					(thickness 0.15)
				)
				(justify mirror)
			)
		)
		(property "MPN" "CR0402-FX-3300GLF"
			(at 0 0 270)
			(unlocked yes)
			(layer "B.Fab")
			(hide yes)
			(effects
				(font
					(size 1 1)
					(thickness 0.15)
				)
				(justify mirror)
			)
		)
		(property "Val" "330R"
			(at 0 0 270)
			(unlocked yes)
			(layer "B.Fab")
			(hide yes)
			(effects
				(font
					(size 1 1)
					(thickness 0.15)
				)
				(justify mirror)
			)
		)
		(property "License" "Apache-2.0"
			(at 0 0 270)
			(unlocked yes)
			(layer "B.Fab")
			(hide yes)
			(effects
				(font
					(size 1 1)
					(thickness 0.15)
				)
				(justify mirror)
			)
		)
		(property "Author" "Antmicro"
			(at 0 0 270)
			(unlocked yes)
			(layer "B.Fab")
			(hide yes)
			(effects
				(font
					(size 1 1)
					(thickness 0.15)
				)
				(justify mirror)
			)
		)
		(property "Tolerance" "1%"
			(at 0 0 270)
			(unlocked yes)
			(layer "B.Fab")
			(hide yes)
			(effects
				(font
					(size 1 1)
					(thickness 0.15)
				)
				(justify mirror)
			)
		)
		(sheetname "/FPGA banks HD/")
		(sheetfile "fpga-hd-banks.kicad_sch")
		(attr smd)
		(fp_rect
			(start -0.925 0.47)
			(end 0.925 -0.47)
			(stroke
				(width 0.05)
				(type default)
			)
			(fill no)
			(layer "B.CrtYd")
		)
		(fp_rect
			(start -0.5 0.25)
			(end 0.5 -0.25)
			(stroke
				(width 0.15)
				(type solid)
			)
			(fill no)
			(layer "B.Fab")
		)
		(fp_text user "${REFERENCE}"
			(at -0.95 -3.168 90)
			(layer "B.Fab")
			(effects
				(font
					(size 0.7 0.7)
					(thickness 0.15)
				)
				(justify left bottom mirror)
			)
		)
		(fp_text user "License: Apache-2.0"
			(at -0.95 -5.169 90)
			(layer "B.Fab")
			(effects
				(font
					(size 0.7 0.7)
					(thickness 0.15)
				)
				(justify left bottom mirror)
			)
		)
		(fp_text user "Author: Antmicro"
			(at -0.95 -4.169 90)
			(layer "B.Fab")
			(effects
				(font
					(size 0.7 0.7)
					(thickness 0.15)
				)
				(justify left bottom mirror)
			)
		)
		(pad "1" smd roundrect
			(at -0.48 0 270)
			(size 0.59 0.64)
			(layers "B.Cu" "B.Mask" "B.Paste")
			(roundrect_rratio 0.25)
			(net 232 "Net-(D7-A)")
			(pintype "passive")
		)
		(pad "2" smd roundrect
			(at 0.48 0 270)
			(size 0.59 0.64)
			(layers "B.Cu" "B.Mask" "B.Paste")
			(roundrect_rratio 0.25)
			(net 275 "Net-(Q7-D)")
			(pintype "passive")
		)
	)
	(footprint "antmicro-footprints:C_0402_1005Metric"
		(layer "B.Cu")
		(at 254.174499 134.699 180)
		(descr "Capacitor SMD 0402")
		(tags "capacitor SMD 0402")
		(property "Reference" "C203"
			(at -4.125501 -0.401 0)
			(layer "B.SilkS")
			(effects
				(font
					(size 0.7 0.7)
					(thickness 0.15)
				)
				(justify left bottom mirror)
			)
		)
		(property "Value" "C_100n_0402"
			(at -1.022927 -2.155213 0)
			(layer "B.Fab")
			(effects
				(font
					(size 0.7 0.7)
					(thickness 0.15)
				)
				(justify left bottom mirror)
			)
		)
		(property "Datasheet" "https://www.murata.com/products/productdetail?partno=GRM155R61H104KE14%23"
			(at 0 0 180)
			(layer "F.Fab")
			(hide yes)
			(effects
				(font
					(size 1.27 1.27)
					(thickness 0.15)
				)
			)
		)
		(property "Manufacturer" "Murata"
			(at 0 0 180)
			(unlocked yes)
			(layer "B.Fab")
			(hide yes)
			(effects
				(font
					(size 1 1)
					(thickness 0.15)
				)
				(justify mirror)
			)
		)
		(property "MPN" "GRM155R61H104KE14D"
			(at 0 0 180)
			(unlocked yes)
			(layer "B.Fab")
			(hide yes)
			(effects
				(font
					(size 1 1)
					(thickness 0.15)
				)
				(justify mirror)
			)
		)
		(property "Val" "100n"
			(at 0 0 180)
			(unlocked yes)
			(layer "B.Fab")
			(hide yes)
			(effects
				(font
					(size 1 1)
					(thickness 0.15)
				)
				(justify mirror)
			)
		)
		(property "License" "Apache-2.0"
			(at 0 0 180)
			(unlocked yes)
			(layer "B.Fab")
			(hide yes)
			(effects
				(font
					(size 1 1)
					(thickness 0.15)
				)
				(justify mirror)
			)
		)
		(property "Author" "Antmicro"
			(at 0 0 180)
			(unlocked yes)
			(layer "B.Fab")
			(hide yes)
			(effects
				(font
					(size 1 1)
					(thickness 0.15)
				)
				(justify mirror)
			)
		)
		(property "Voltage" "50V"
			(at 0 0 180)
			(unlocked yes)
			(layer "B.Fab")
			(hide yes)
			(effects
				(font
					(size 1 1)
					(thickness 0.15)
				)
				(justify mirror)
			)
		)
		(property "Dielectric" "X5R"
			(at 0 0 180)
			(unlocked yes)
			(layer "B.Fab")
			(hide yes)
			(effects
				(font
					(size 1 1)
					(thickness 0.15)
				)
				(justify mirror)
			)
		)
		(sheetname "/Supply/")
		(sheetfile "supply.kicad_sch")
		(attr smd)
		(fp_rect
			(start -0.925 0.47)
			(end 0.925 -0.47)
			(stroke
				(width 0.05)
				(type default)
			)
			(fill no)
			(layer "B.CrtYd")
		)
		(fp_line
			(start 0.504 0.25)
			(end 0.504 -0.248)
			(stroke
				(width 0.15)
				(type solid)
			)
			(layer "B.Fab")
		)
		(fp_line
			(start 0.504 -0.248)
			(end -0.494 -0.248)
			(stroke
				(width 0.15)
				(type solid)
			)
			(layer "B.Fab")
		)
		(fp_line
			(start -0.494 0.25)
			(end 0.504 0.25)
			(stroke
				(width 0.15)
				(type solid)
			)
			(layer "B.Fab")
		)
		(fp_line
			(start -0.494 -0.248)
			(end -0.494 0.25)
			(stroke
				(width 0.15)
				(type solid)
			)
			(layer "B.Fab")
		)
		(fp_text user "${REFERENCE}"
			(at -0.939 -4.599 0)
			(layer "B.Fab")
			(effects
				(font
					(size 0.7 0.7)
					(thickness 0.15)
				)
				(justify left bottom mirror)
			)
		)
		(fp_text user "Author: Antmicro"
			(at -0.939 -3.399 0)
			(layer "B.Fab")
			(effects
				(font
					(size 0.7 0.7)
					(thickness 0.15)
				)
				(justify left bottom mirror)
			)
		)
		(fp_text user "License: Apache-2.0"
			(at -0.939 -5.799 0)
			(layer "B.Fab")
			(effects
				(font
					(size 0.7 0.7)
					(thickness 0.15)
				)
				(justify left bottom mirror)
			)
		)
		(pad "1" smd roundrect
			(at -0.48 0 180)
			(size 0.59 0.64)
			(layers "B.Cu" "B.Mask" "B.Paste")
			(roundrect_rratio 0.25)
			(net 38 "+3V3_AON")
			(pintype "passive")
		)
		(pad "2" smd roundrect
			(at 0.48 0 180)
			(size 0.59 0.64)
			(layers "B.Cu" "B.Mask" "B.Paste")
			(roundrect_rratio 0.25)
			(net 1 "GND")
			(pintype "passive")
		)
	)
	(footprint "antmicro-footprints:C_0402_1005Metric_EIA"
		(layer "B.Cu")
		(at 190 156.500001 90)
		(descr "Capacitor SMD 0402 (1005 Metric), square (rectangular) end terminal, IPC_7351 nominal, (Body size source: IPC-SM-782 page 76, https://www.pcb-3d.com/wordpress/wp-content/uploads/ipc-sm-782a_amendment_1_and_2.pdf)")
		(tags "capacitor 0402")
		(property "Reference" "C90"
			(at 9.650001 -30.65 90)
			(layer "B.SilkS")
			(effects
				(font
					(size 0.7 0.7)
					(thickness 0.15)
				)
				(justify right bottom mirror)
			)
		)
		(property "Value" "C_1u_25V_0402"
			(at 0 -1.169 90)
			(layer "B.Fab")
			(effects
				(font
					(size 0.7 0.7)
					(thickness 0.15)
				)
				(justify right bottom mirror)
			)
		)
		(property "Datasheet" "https://www.murata.com/products/productdetail?partno=GRM155R61E105KE11%23"
			(at 0 0 90)
			(layer "F.Fab")
			(hide yes)
			(effects
				(font
					(size 1.27 1.27)
					(thickness 0.15)
				)
			)
		)
		(property "MPN" "GRM155R61E105KE11J"
			(at 0 0 90)
			(unlocked yes)
			(layer "B.Fab")
			(hide yes)
			(effects
				(font
					(size 1 1)
					(thickness 0.15)
				)
				(justify mirror)
			)
		)
		(property "Manufacturer" "Murata"
			(at 0 0 90)
			(unlocked yes)
			(layer "B.Fab")
			(hide yes)
			(effects
				(font
					(size 1 1)
					(thickness 0.15)
				)
				(justify mirror)
			)
		)
		(property "License" "Apache-2.0"
			(at 0 0 90)
			(unlocked yes)
			(layer "B.Fab")
			(hide yes)
			(effects
				(font
					(size 1 1)
					(thickness 0.15)
				)
				(justify mirror)
			)
		)
		(property "Author" "Antmicro"
			(at 0 0 90)
			(unlocked yes)
			(layer "B.Fab")
			(hide yes)
			(effects
				(font
					(size 1 1)
					(thickness 0.15)
				)
				(justify mirror)
			)
		)
		(property "Val" "1u"
			(at 0 0 90)
			(unlocked yes)
			(layer "B.Fab")
			(hide yes)
			(effects
				(font
					(size 1 1)
					(thickness 0.15)
				)
				(justify mirror)
			)
		)
		(property "Voltage" "25V"
			(at 0 0 90)
			(unlocked yes)
			(layer "B.Fab")
			(hide yes)
			(effects
				(font
					(size 1 1)
					(thickness 0.15)
				)
				(justify mirror)
			)
		)
		(property "Dielectric" "X5R"
			(at 0 0 90)
			(unlocked yes)
			(layer "B.Fab")
			(hide yes)
			(effects
				(font
					(size 1 1)
					(thickness 0.15)
				)
				(justify mirror)
			)
		)
		(sheetname "/FPGA power/")
		(sheetfile "fpga-power.kicad_sch")
		(attr smd)
		(fp_rect
			(start -0.95 0.45)
			(end 0.95 -0.45)
			(stroke
				(width 0.05)
				(type default)
			)
			(fill no)
			(layer "B.CrtYd")
		)
		(fp_line
			(start 0.498 -0.248)
			(end -0.5 -0.248)
			(stroke
				(width 0.15)
				(type solid)
			)
			(layer "B.Fab")
		)
		(fp_line
			(start -0.5 -0.248)
			(end -0.5 0.25)
			(stroke
				(width 0.15)
				(type solid)
			)
			(layer "B.Fab")
		)
		(fp_line
			(start 0.498 0.25)
			(end 0.498 -0.248)
			(stroke
				(width 0.15)
				(type solid)
			)
			(layer "B.Fab")
		)
		(fp_line
			(start -0.5 0.25)
			(end 0.498 0.25)
			(stroke
				(width 0.15)
				(type solid)
			)
			(layer "B.Fab")
		)
		(fp_text user "Author: Antmicro"
			(at -0.9656 -5.569 270)
			(layer "B.Fab")
			(effects
				(font
					(size 0.7 0.7)
					(thickness 0.15)
				)
				(justify left bottom mirror)
			)
		)
		(fp_text user "${REFERENCE}"
			(at -0.9656 -3.169 270)
			(layer "B.Fab")
			(effects
				(font
					(size 0.7 0.7)
					(thickness 0.15)
				)
				(justify left bottom mirror)
			)
		)
		(fp_text user "License: Apache-2.0"
			(at -0.9656 -4.369 270)
			(layer "B.Fab")
			(effects
				(font
					(size 0.7 0.7)
					(thickness 0.15)
				)
				(justify left bottom mirror)
			)
		)
		(pad "1" smd roundrect
			(at -0.5 0)
			(size 0.6 0.6)
			(layers "B.Cu" "B.Mask" "B.Paste")
			(roundrect_rratio 0.25)
			(net 1 "GND")
			(pintype "passive")
		)
		(pad "2" smd roundrect
			(at 0.498 0 90)
			(size 0.6 0.6)
			(layers "B.Cu" "B.Mask" "B.Paste")
			(roundrect_rratio 0.25)
			(net 553 "+0V85")
			(pintype "passive")
		)
	)
	(footprint "antmicro-footprints:R_0402_1005Metric"
		(layer "B.Cu")
		(at 221.9 177.915 -90)
		(descr "Resistor SMD 0402")
		(tags "resistor SMD 0402")
		(property "Reference" "R200"
			(at -1.74 0.725 90)
			(layer "B.SilkS")
			(effects
				(font
					(size 0.7 0.7)
					(thickness 0.15)
				)
				(justify left bottom mirror)
			)
		)
		(property "Value" "R_0R_0402"
			(at -1.011843 -1.772047 90)
			(layer "B.Fab")
			(effects
				(font
					(size 0.7 0.7)
					(thickness 0.15)
				)
				(justify left bottom mirror)
			)
		)
		(property "Datasheet" "https://industrial.panasonic.com/cdbs/www-data/pdf/RDA0000/AOA0000C301.pdf"
			(at 0 0 270)
			(layer "F.Fab")
			(hide yes)
			(effects
				(font
					(size 1.27 1.27)
					(thickness 0.15)
				)
			)
		)
		(property "MPN" "ERJ2GE0R00X"
			(at 0 0 270)
			(unlocked yes)
			(layer "B.Fab")
			(hide yes)
			(effects
				(font
					(size 1 1)
					(thickness 0.15)
				)
				(justify mirror)
			)
		)
		(property "Manufacturer" "Panasonic"
			(at 0 0 270)
			(unlocked yes)
			(layer "B.Fab")
			(hide yes)
			(effects
				(font
					(size 1 1)
					(thickness 0.15)
				)
				(justify mirror)
			)
		)
		(property "License" "Apache-2.0"
			(at 0 0 270)
			(unlocked yes)
			(layer "B.Fab")
			(hide yes)
			(effects
				(font
					(size 1 1)
					(thickness 0.15)
				)
				(justify mirror)
			)
		)
		(property "Author" "Antmicro"
			(at 0 0 270)
			(unlocked yes)
			(layer "B.Fab")
			(hide yes)
			(effects
				(font
					(size 1 1)
					(thickness 0.15)
				)
				(justify mirror)
			)
		)
		(property "Val" "0R"
			(at 0 0 270)
			(unlocked yes)
			(layer "B.Fab")
			(hide yes)
			(effects
				(font
					(size 1 1)
					(thickness 0.15)
				)
				(justify mirror)
			)
		)
		(property "Tolerance" "~"
			(at 0 0 270)
			(unlocked yes)
			(layer "B.Fab")
			(hide yes)
			(effects
				(font
					(size 1 1)
					(thickness 0.15)
				)
				(justify mirror)
			)
		)
		(property "Current" "1A"
			(at 0 0 270)
			(unlocked yes)
			(layer "B.Fab")
			(hide yes)
			(effects
				(font
					(size 1 1)
					(thickness 0.15)
				)
				(justify mirror)
			)
		)
		(sheetname "/Supply/DC-DC VCCINT/")
		(sheetfile "dc-dc-vccint.kicad_sch")
		(attr smd)
		(fp_rect
			(start -0.925 0.47)
			(end 0.925 -0.47)
			(stroke
				(width 0.05)
				(type default)
			)
			(fill no)
			(layer "B.CrtYd")
		)
		(fp_rect
			(start -0.5 0.25)
			(end 0.5 -0.25)
			(stroke
				(width 0.15)
				(type solid)
			)
			(fill no)
			(layer "B.Fab")
		)
		(fp_text user "License: Apache-2.0"
			(at -0.95 -5.169 90)
			(layer "B.Fab")
			(effects
				(font
					(size 0.7 0.7)
					(thickness 0.15)
				)
				(justify left bottom mirror)
			)
		)
		(fp_text user "${REFERENCE}"
			(at -0.95 -3.168 90)
			(layer "B.Fab")
			(effects
				(font
					(size 0.7 0.7)
					(thickness 0.15)
				)
				(justify left bottom mirror)
			)
		)
		(fp_text user "Author: Antmicro"
			(at -0.95 -4.169 90)
			(layer "B.Fab")
			(effects
				(font
					(size 0.7 0.7)
					(thickness 0.15)
				)
				(justify left bottom mirror)
			)
		)
		(pad "1" smd roundrect
			(at -0.48 0 270)
			(size 0.59 0.64)
			(layers "B.Cu" "B.Mask" "B.Paste")
			(roundrect_rratio 0.25)
			(net 754 "/Supply/DC-DC VCCINT/VREF+")
			(pintype "passive")
		)
		(pad "2" smd roundrect
			(at 0.48 0 270)
			(size 0.59 0.64)
			(layers "B.Cu" "B.Mask" "B.Paste")
			(roundrect_rratio 0.25)
			(net 756 "Net-(C264-Pad2)")
			(pintype "passive")
		)
	)
	(footprint "antmicro-footprints:C_0603_1608Metric"
		(layer "B.Cu")
		(at 216.91 172.06 90)
		(descr "Capacitor SMD 0603")
		(tags "capacitor 0603")
		(property "Reference" "C269"
			(at -4.04 0.39 90)
			(layer "B.SilkS")
			(effects
				(font
					(size 0.7 0.7)
					(thickness 0.15)
				)
				(justify right bottom mirror)
			)
		)
		(property "Value" "C_22u_0603"
			(at -1.42757 -1.770288 90)
			(layer "B.Fab")
			(effects
				(font
					(size 0.7 0.7)
					(thickness 0.15)
				)
				(justify right bottom mirror)
			)
		)
		(property "Datasheet" "https://www.murata.com/products/productdetail?partno=GRM188R60J226MEA0%23"
			(at 0 0 90)
			(layer "F.Fab")
			(hide yes)
			(effects
				(font
					(size 1.27 1.27)
					(thickness 0.15)
				)
			)
		)
		(property "Manufacturer" "Murata"
			(at 0 0 90)
			(unlocked yes)
			(layer "B.Fab")
			(hide yes)
			(effects
				(font
					(size 1 1)
					(thickness 0.15)
				)
				(justify mirror)
			)
		)
		(property "MPN" "GRM188R60J226MEA0D"
			(at 0 0 90)
			(unlocked yes)
			(layer "B.Fab")
			(hide yes)
			(effects
				(font
					(size 1 1)
					(thickness 0.15)
				)
				(justify mirror)
			)
		)
		(property "Val" "22u"
			(at 0 0 90)
			(unlocked yes)
			(layer "B.Fab")
			(hide yes)
			(effects
				(font
					(size 1 1)
					(thickness 0.15)
				)
				(justify mirror)
			)
		)
		(property "License" "Apache-2.0"
			(at 0 0 90)
			(unlocked yes)
			(layer "B.Fab")
			(hide yes)
			(effects
				(font
					(size 1 1)
					(thickness 0.15)
				)
				(justify mirror)
			)
		)
		(property "Author" "Antmicro"
			(at 0 0 90)
			(unlocked yes)
			(layer "B.Fab")
			(hide yes)
			(effects
				(font
					(size 1 1)
					(thickness 0.15)
				)
				(justify mirror)
			)
		)
		(property "Voltage" ""
			(at 0 0 90)
			(unlocked yes)
			(layer "B.Fab")
			(hide yes)
			(effects
				(font
					(size 1 1)
					(thickness 0.15)
				)
				(justify mirror)
			)
		)
		(property "Dielectric" ""
			(at 0 0 90)
			(unlocked yes)
			(layer "B.Fab")
			(hide yes)
			(effects
				(font
					(size 1 1)
					(thickness 0.15)
				)
				(justify mirror)
			)
		)
		(sheetname "/Supply/DC-DC VCCINT/")
		(sheetfile "dc-dc-vccint.kicad_sch")
		(attr smd)
		(fp_line
			(start -0.15 -0.4)
			(end 0.15 -0.4)
			(stroke
				(width 0.15)
				(type solid)
			)
			(layer "B.SilkS")
		)
		(fp_line
			(start -0.15 0.4)
			(end 0.15 0.4)
			(stroke
				(width 0.15)
				(type solid)
			)
			(layer "B.SilkS")
		)
		(fp_rect
			(start -1.25 0.65)
			(end 1.25 -0.65)
			(stroke
				(width 0.05)
				(type solid)
			)
			(fill no)
			(layer "B.CrtYd")
		)
		(fp_rect
			(start -0.8 0.4)
			(end 0.8 -0.4)
			(stroke
				(width 0.15)
				(type solid)
			)
			(fill no)
			(layer "B.Fab")
		)
		(fp_text user "License: Apache-2.0"
			(at -1.682 -5.895 270)
			(layer "B.Fab")
			(effects
				(font
					(size 0.7 0.7)
					(thickness 0.15)
				)
				(justify left bottom mirror)
			)
		)
		(fp_text user "Author: Antmicro"
			(at -1.682 -4.894 270)
			(layer "B.Fab")
			(effects
				(font
					(size 0.7 0.7)
					(thickness 0.15)
				)
				(justify left bottom mirror)
			)
		)
		(fp_text user "${REFERENCE}"
			(at -1.682 -3.895 270)
			(layer "B.Fab")
			(effects
				(font
					(size 0.7 0.7)
					(thickness 0.15)
				)
				(justify left bottom mirror)
			)
		)
		(pad "1" smd roundrect
			(at -0.7 0 90)
			(size 0.8 1)
			(layers "B.Cu" "B.Mask" "B.Paste")
			(roundrect_rratio 0.2)
			(net 1 "GND")
			(pintype "passive")
		)
		(pad "2" smd roundrect
			(at 0.7 0 90)
			(size 0.8 1)
			(layers "B.Cu" "B.Mask" "B.Paste")
			(roundrect_rratio 0.2)
			(net 223 "/Supply/DC-DC VCCINT/0V85_REG0")
			(pintype "passive")
		)
	)
	(footprint "antmicro-footprints:R_0402_1005Metric"
		(layer "B.Cu")
		(at 225.32 183.755)
		(descr "Resistor SMD 0402")
		(tags "resistor SMD 0402")
		(property "Reference" "R181"
			(at 1.83 0.495 0)
			(layer "B.SilkS")
			(effects
				(font
					(size 0.7 0.7)
					(thickness 0.15)
				)
				(justify right bottom mirror)
			)
		)
		(property "Value" "R_0R_0402"
			(at -1.011843 -1.772047 0)
			(layer "B.Fab")
			(effects
				(font
					(size 0.7 0.7)
					(thickness 0.15)
				)
				(justify right bottom mirror)
			)
		)
		(property "Datasheet" "https://industrial.panasonic.com/cdbs/www-data/pdf/RDA0000/AOA0000C301.pdf"
			(at 0 0 0)
			(layer "F.Fab")
			(hide yes)
			(effects
				(font
					(size 1.27 1.27)
					(thickness 0.15)
				)
			)
		)
		(property "MPN" "ERJ2GE0R00X"
			(at 0 0 0)
			(unlocked yes)
			(layer "B.Fab")
			(hide yes)
			(effects
				(font
					(size 1 1)
					(thickness 0.15)
				)
				(justify mirror)
			)
		)
		(property "Manufacturer" "Panasonic"
			(at 0 0 0)
			(unlocked yes)
			(layer "B.Fab")
			(hide yes)
			(effects
				(font
					(size 1 1)
					(thickness 0.15)
				)
				(justify mirror)
			)
		)
		(property "License" "Apache-2.0"
			(at 0 0 0)
			(unlocked yes)
			(layer "B.Fab")
			(hide yes)
			(effects
				(font
					(size 1 1)
					(thickness 0.15)
				)
				(justify mirror)
			)
		)
		(property "Author" "Antmicro"
			(at 0 0 0)
			(unlocked yes)
			(layer "B.Fab")
			(hide yes)
			(effects
				(font
					(size 1 1)
					(thickness 0.15)
				)
				(justify mirror)
			)
		)
		(property "Val" "0R"
			(at 0 0 0)
			(unlocked yes)
			(layer "B.Fab")
			(hide yes)
			(effects
				(font
					(size 1 1)
					(thickness 0.15)
				)
				(justify mirror)
			)
		)
		(property "Tolerance" "~"
			(at 0 0 0)
			(unlocked yes)
			(layer "B.Fab")
			(hide yes)
			(effects
				(font
					(size 1 1)
					(thickness 0.15)
				)
				(justify mirror)
			)
		)
		(property "Current" "1A"
			(at 0 0 0)
			(unlocked yes)
			(layer "B.Fab")
			(hide yes)
			(effects
				(font
					(size 1 1)
					(thickness 0.15)
				)
				(justify mirror)
			)
		)
		(sheetname "/Supply/DC-DC VCCINT/")
		(sheetfile "dc-dc-vccint.kicad_sch")
		(attr smd)
		(fp_rect
			(start -0.925 0.47)
			(end 0.925 -0.47)
			(stroke
				(width 0.05)
				(type default)
			)
			(fill no)
			(layer "B.CrtYd")
		)
		(fp_rect
			(start -0.5 0.25)
			(end 0.5 -0.25)
			(stroke
				(width 0.15)
				(type solid)
			)
			(fill no)
			(layer "B.Fab")
		)
		(fp_text user "Author: Antmicro"
			(at -0.95 -4.169 180)
			(layer "B.Fab")
			(effects
				(font
					(size 0.7 0.7)
					(thickness 0.15)
				)
				(justify left bottom mirror)
			)
		)
		(fp_text user "License: Apache-2.0"
			(at -0.95 -5.169 180)
			(layer "B.Fab")
			(effects
				(font
					(size 0.7 0.7)
					(thickness 0.15)
				)
				(justify left bottom mirror)
			)
		)
		(fp_text user "${REFERENCE}"
			(at -0.95 -3.168 180)
			(layer "B.Fab")
			(effects
				(font
					(size 0.7 0.7)
					(thickness 0.15)
				)
				(justify left bottom mirror)
			)
		)
		(pad "1" smd roundrect
			(at -0.48 0)
			(size 0.59 0.64)
			(layers "B.Cu" "B.Mask" "B.Paste")
			(roundrect_rratio 0.25)
			(net 721 "/Supply/DC-DC VCCINT/PASS0")
			(pintype "passive")
		)
		(pad "2" smd roundrect
			(at 0.48 0)
			(size 0.59 0.64)
			(layers "B.Cu" "B.Mask" "B.Paste")
			(roundrect_rratio 0.25)
			(net 722 "/Supply/DC-DC VCCINT/TAKE1")
			(pintype "passive")
		)
	)
	(footprint "antmicro-footprints:C_0402_1005Metric_EIA"
		(layer "B.Cu")
		(at 191 154.5 90)
		(descr "Capacitor SMD 0402 (1005 Metric), square (rectangular) end terminal, IPC_7351 nominal, (Body size source: IPC-SM-782 page 76, https://www.pcb-3d.com/wordpress/wp-content/uploads/ipc-sm-782a_amendment_1_and_2.pdf)")
		(tags "capacitor 0402")
		(property "Reference" "C246"
			(at 10.25 -30.625 90)
			(layer "B.SilkS")
			(effects
				(font
					(size 0.7 0.7)
					(thickness 0.15)
				)
				(justify right bottom mirror)
			)
		)
		(property "Value" "C_1u_25V_0402"
			(at 0 -1.169 90)
			(layer "B.Fab")
			(effects
				(font
					(size 0.7 0.7)
					(thickness 0.15)
				)
				(justify right bottom mirror)
			)
		)
		(property "Datasheet" "https://www.murata.com/products/productdetail?partno=GRM155R61E105KE11%23"
			(at 0 0 90)
			(layer "F.Fab")
			(hide yes)
			(effects
				(font
					(size 1.27 1.27)
					(thickness 0.15)
				)
			)
		)
		(property "MPN" "GRM155R61E105KE11J"
			(at 0 0 90)
			(unlocked yes)
			(layer "B.Fab")
			(hide yes)
			(effects
				(font
					(size 1 1)
					(thickness 0.15)
				)
				(justify mirror)
			)
		)
		(property "Manufacturer" "Murata"
			(at 0 0 90)
			(unlocked yes)
			(layer "B.Fab")
			(hide yes)
			(effects
				(font
					(size 1 1)
					(thickness 0.15)
				)
				(justify mirror)
			)
		)
		(property "License" "Apache-2.0"
			(at 0 0 90)
			(unlocked yes)
			(layer "B.Fab")
			(hide yes)
			(effects
				(font
					(size 1 1)
					(thickness 0.15)
				)
				(justify mirror)
			)
		)
		(property "Author" "Antmicro"
			(at 0 0 90)
			(unlocked yes)
			(layer "B.Fab")
			(hide yes)
			(effects
				(font
					(size 1 1)
					(thickness 0.15)
				)
				(justify mirror)
			)
		)
		(property "Val" "1u"
			(at 0 0 90)
			(unlocked yes)
			(layer "B.Fab")
			(hide yes)
			(effects
				(font
					(size 1 1)
					(thickness 0.15)
				)
				(justify mirror)
			)
		)
		(property "Voltage" "25V"
			(at 0 0 90)
			(unlocked yes)
			(layer "B.Fab")
			(hide yes)
			(effects
				(font
					(size 1 1)
					(thickness 0.15)
				)
				(justify mirror)
			)
		)
		(property "Dielectric" "X5R"
			(at 0 0 90)
			(unlocked yes)
			(layer "B.Fab")
			(hide yes)
			(effects
				(font
					(size 1 1)
					(thickness 0.15)
				)
				(justify mirror)
			)
		)
		(sheetname "/FPGA power/")
		(sheetfile "fpga-power.kicad_sch")
		(attr smd)
		(fp_rect
			(start -0.95 0.45)
			(end 0.95 -0.45)
			(stroke
				(width 0.05)
				(type default)
			)
			(fill no)
			(layer "B.CrtYd")
		)
		(fp_line
			(start 0.498 -0.248)
			(end -0.5 -0.248)
			(stroke
				(width 0.15)
				(type solid)
			)
			(layer "B.Fab")
		)
		(fp_line
			(start -0.5 -0.248)
			(end -0.5 0.25)
			(stroke
				(width 0.15)
				(type solid)
			)
			(layer "B.Fab")
		)
		(fp_line
			(start 0.498 0.25)
			(end 0.498 -0.248)
			(stroke
				(width 0.15)
				(type solid)
			)
			(layer "B.Fab")
		)
		(fp_line
			(start -0.5 0.25)
			(end 0.498 0.25)
			(stroke
				(width 0.15)
				(type solid)
			)
			(layer "B.Fab")
		)
		(fp_text user "Author: Antmicro"
			(at -0.9656 -5.569 270)
			(layer "B.Fab")
			(effects
				(font
					(size 0.7 0.7)
					(thickness 0.15)
				)
				(justify left bottom mirror)
			)
		)
		(fp_text user "${REFERENCE}"
			(at -0.9656 -3.169 270)
			(layer "B.Fab")
			(effects
				(font
					(size 0.7 0.7)
					(thickness 0.15)
				)
				(justify left bottom mirror)
			)
		)
		(fp_text user "License: Apache-2.0"
			(at -0.9656 -4.369 270)
			(layer "B.Fab")
			(effects
				(font
					(size 0.7 0.7)
					(thickness 0.15)
				)
				(justify left bottom mirror)
			)
		)
		(pad "1" smd roundrect
			(at -0.5 0)
			(size 0.6 0.6)
			(layers "B.Cu" "B.Mask" "B.Paste")
			(roundrect_rratio 0.25)
			(net 1 "GND")
			(pintype "passive")
		)
		(pad "2" smd roundrect
			(at 0.498 0 90)
			(size 0.6 0.6)
			(layers "B.Cu" "B.Mask" "B.Paste")
			(roundrect_rratio 0.25)
			(net 553 "+0V85")
			(pintype "passive")
		)
	)
	(footprint "antmicro-footprints:C_0402_1005Metric_EIA"
		(layer "B.Cu")
		(at 178 149.5 90)
		(descr "Capacitor SMD 0402 (1005 Metric), square (rectangular) end terminal, IPC_7351 nominal, (Body size source: IPC-SM-782 page 76, https://www.pcb-3d.com/wordpress/wp-content/uploads/ipc-sm-782a_amendment_1_and_2.pdf)")
		(tags "capacitor 0402")
		(property "Reference" "C91"
			(at -1.125 -0.5 90)
			(layer "B.SilkS")
			(effects
				(font
					(size 0.7 0.7)
					(thickness 0.15)
				)
				(justify right bottom mirror)
			)
		)
		(property "Value" "C_100n_0402"
			(at 0 -1.169 90)
			(layer "B.Fab")
			(effects
				(font
					(size 0.7 0.7)
					(thickness 0.15)
				)
				(justify right bottom mirror)
			)
		)
		(property "Datasheet" "https://www.murata.com/products/productdetail?partno=GRM155R61H104KE14%23"
			(at 0 0 90)
			(layer "F.Fab")
			(hide yes)
			(effects
				(font
					(size 1.27 1.27)
					(thickness 0.15)
				)
			)
		)
		(property "MPN" "GRM155R61H104KE14D"
			(at 0 0 90)
			(unlocked yes)
			(layer "B.Fab")
			(hide yes)
			(effects
				(font
					(size 1 1)
					(thickness 0.15)
				)
				(justify mirror)
			)
		)
		(property "Manufacturer" "Murata"
			(at 0 0 90)
			(unlocked yes)
			(layer "B.Fab")
			(hide yes)
			(effects
				(font
					(size 1 1)
					(thickness 0.15)
				)
				(justify mirror)
			)
		)
		(property "License" "Apache-2.0"
			(at 0 0 90)
			(unlocked yes)
			(layer "B.Fab")
			(hide yes)
			(effects
				(font
					(size 1 1)
					(thickness 0.15)
				)
				(justify mirror)
			)
		)
		(property "Author" "Antmicro"
			(at 0 0 90)
			(unlocked yes)
			(layer "B.Fab")
			(hide yes)
			(effects
				(font
					(size 1 1)
					(thickness 0.15)
				)
				(justify mirror)
			)
		)
		(property "Val" "100n"
			(at 0 0 90)
			(unlocked yes)
			(layer "B.Fab")
			(hide yes)
			(effects
				(font
					(size 1 1)
					(thickness 0.15)
				)
				(justify mirror)
			)
		)
		(property "Voltage" "50V"
			(at 0 0 90)
			(unlocked yes)
			(layer "B.Fab")
			(hide yes)
			(effects
				(font
					(size 1 1)
					(thickness 0.15)
				)
				(justify mirror)
			)
		)
		(property "Dielectric" "X5R"
			(at 0 0 90)
			(unlocked yes)
			(layer "B.Fab")
			(hide yes)
			(effects
				(font
					(size 1 1)
					(thickness 0.15)
				)
				(justify mirror)
			)
		)
		(sheetname "/FPGA power/")
		(sheetfile "fpga-power.kicad_sch")
		(attr smd)
		(fp_rect
			(start -0.95 0.45)
			(end 0.95 -0.45)
			(stroke
				(width 0.05)
				(type default)
			)
			(fill no)
			(layer "B.CrtYd")
		)
		(fp_line
			(start 0.498 -0.248)
			(end -0.5 -0.248)
			(stroke
				(width 0.15)
				(type solid)
			)
			(layer "B.Fab")
		)
		(fp_line
			(start -0.5 -0.248)
			(end -0.5 0.25)
			(stroke
				(width 0.15)
				(type solid)
			)
			(layer "B.Fab")
		)
		(fp_line
			(start 0.498 0.25)
			(end 0.498 -0.248)
			(stroke
				(width 0.15)
				(type solid)
			)
			(layer "B.Fab")
		)
		(fp_line
			(start -0.5 0.25)
			(end 0.498 0.25)
			(stroke
				(width 0.15)
				(type solid)
			)
			(layer "B.Fab")
		)
		(fp_text user "${REFERENCE}"
			(at -0.9656 -3.169 270)
			(layer "B.Fab")
			(effects
				(font
					(size 0.7 0.7)
					(thickness 0.15)
				)
				(justify left bottom mirror)
			)
		)
		(fp_text user "License: Apache-2.0"
			(at -0.9656 -4.369 270)
			(layer "B.Fab")
			(effects
				(font
					(size 0.7 0.7)
					(thickness 0.15)
				)
				(justify left bottom mirror)
			)
		)
		(fp_text user "Author: Antmicro"
			(at -0.9656 -5.569 270)
			(layer "B.Fab")
			(effects
				(font
					(size 0.7 0.7)
					(thickness 0.15)
				)
				(justify left bottom mirror)
			)
		)
		(pad "1" smd roundrect
			(at -0.5 0)
			(size 0.6 0.6)
			(layers "B.Cu" "B.Mask" "B.Paste")
			(roundrect_rratio 0.25)
			(net 1 "GND")
			(pintype "passive")
		)
		(pad "2" smd roundrect
			(at 0.498 0 90)
			(size 0.6 0.6)
			(layers "B.Cu" "B.Mask" "B.Paste")
			(roundrect_rratio 0.25)
			(net 797 "+1V8")
			(pintype "passive")
		)
	)
	(footprint "antmicro-footprints:R_0402_1005Metric"
		(layer "B.Cu")
		(at 183 136.8 90)
		(descr "Resistor SMD 0402")
		(tags "resistor SMD 0402")
		(property "Reference" "R260"
			(at 2.3 0 270)
			(layer "B.SilkS")
			(effects
				(font
					(size 0.7 0.7)
					(thickness 0.15)
				)
				(justify mirror)
			)
		)
		(property "Value" "R_0R_0402"
			(at -1.011843 -1.772047 270)
			(layer "B.Fab")
			(effects
				(font
					(size 0.7 0.7)
					(thickness 0.15)
				)
				(justify left bottom mirror)
			)
		)
		(property "Datasheet" "https://industrial.panasonic.com/cdbs/www-data/pdf/RDA0000/AOA0000C301.pdf"
			(at 0 0 270)
			(layer "B.Fab")
			(hide yes)
			(effects
				(font
					(size 1.27 1.27)
					(thickness 0.15)
				)
				(justify mirror)
			)
		)
		(property "MPN" "ERJ2GE0R00X"
			(at 0 0 90)
			(unlocked yes)
			(layer "B.Fab")
			(hide yes)
			(effects
				(font
					(size 1 1)
					(thickness 0.15)
				)
				(justify mirror)
			)
		)
		(property "Manufacturer" "Panasonic"
			(at 0 0 90)
			(unlocked yes)
			(layer "B.Fab")
			(hide yes)
			(effects
				(font
					(size 1 1)
					(thickness 0.15)
				)
				(justify mirror)
			)
		)
		(property "License" "Apache-2.0"
			(at 0 0 90)
			(unlocked yes)
			(layer "B.Fab")
			(hide yes)
			(effects
				(font
					(size 1 1)
					(thickness 0.15)
				)
				(justify mirror)
			)
		)
		(property "Author" "Antmicro"
			(at 0 0 90)
			(unlocked yes)
			(layer "B.Fab")
			(hide yes)
			(effects
				(font
					(size 1 1)
					(thickness 0.15)
				)
				(justify mirror)
			)
		)
		(property "Val" "0R"
			(at 0 0 90)
			(unlocked yes)
			(layer "B.Fab")
			(hide yes)
			(effects
				(font
					(size 1 1)
					(thickness 0.15)
				)
				(justify mirror)
			)
		)
		(property "Tolerance" "~"
			(at 0 0 90)
			(unlocked yes)
			(layer "B.Fab")
			(hide yes)
			(effects
				(font
					(size 1 1)
					(thickness 0.15)
				)
				(justify mirror)
			)
		)
		(property "Current" "1A"
			(at 0 0 90)
			(unlocked yes)
			(layer "B.Fab")
			(hide yes)
			(effects
				(font
					(size 1 1)
					(thickness 0.15)
				)
				(justify mirror)
			)
		)
		(sheetname "/FPGA banks HP/")
		(sheetfile "fpga-hp-banks.kicad_sch")
		(attr smd)
		(fp_rect
			(start -0.925 0.47)
			(end 0.925 -0.47)
			(stroke
				(width 0.05)
				(type default)
			)
			(fill no)
			(layer "B.CrtYd")
		)
		(fp_rect
			(start -0.5 0.25)
			(end 0.5 -0.25)
			(stroke
				(width 0.15)
				(type solid)
			)
			(fill no)
			(layer "B.Fab")
		)
		(fp_text user "License: Apache-2.0"
			(at -0.95 -5.169 270)
			(layer "B.Fab")
			(effects
				(font
					(size 0.7 0.7)
					(thickness 0.15)
				)
				(justify left bottom mirror)
			)
		)
		(fp_text user "Author: Antmicro"
			(at -0.95 -4.169 270)
			(layer "B.Fab")
			(effects
				(font
					(size 0.7 0.7)
					(thickness 0.15)
				)
				(justify left bottom mirror)
			)
		)
		(fp_text user "${REFERENCE}"
			(at -0.95 -3.168 270)
			(layer "B.Fab")
			(effects
				(font
					(size 0.7 0.7)
					(thickness 0.15)
				)
				(justify left bottom mirror)
			)
		)
		(pad "1" smd roundrect
			(at -0.48 0 90)
			(size 0.59 0.64)
			(layers "B.Cu" "B.Mask" "B.Paste")
			(roundrect_rratio 0.25)
			(net 546 "/FPGA banks HP/VREF_67")
			(pintype "passive")
		)
		(pad "2" smd roundrect
			(at 0.48 0 90)
			(size 0.59 0.64)
			(layers "B.Cu" "B.Mask" "B.Paste")
			(roundrect_rratio 0.25)
			(net 826 "/FPGA banks HP/VREF")
			(pintype "passive")
		)
	)
	(footprint "antmicro-footprints:R_0402_1005Metric"
		(layer "B.Cu")
		(at 234.05 132.81 -90)
		(descr "Resistor SMD 0402")
		(tags "resistor SMD 0402")
		(property "Reference" "R126"
			(at -4.06 -0.25 90)
			(layer "B.SilkS")
			(effects
				(font
					(size 0.7 0.7)
					(thickness 0.15)
				)
				(justify left bottom mirror)
			)
		)
		(property "Value" "R_0R_0402"
			(at -1.011843 -1.772047 90)
			(layer "B.Fab")
			(effects
				(font
					(size 0.7 0.7)
					(thickness 0.15)
				)
				(justify left bottom mirror)
			)
		)
		(property "Datasheet" "https://industrial.panasonic.com/cdbs/www-data/pdf/RDA0000/AOA0000C301.pdf"
			(at 0 0 270)
			(layer "F.Fab")
			(hide yes)
			(effects
				(font
					(size 1.27 1.27)
					(thickness 0.15)
				)
			)
		)
		(property "MPN" "ERJ2GE0R00X"
			(at 0 0 270)
			(unlocked yes)
			(layer "B.Fab")
			(hide yes)
			(effects
				(font
					(size 1 1)
					(thickness 0.15)
				)
				(justify mirror)
			)
		)
		(property "Manufacturer" "Panasonic"
			(at 0 0 270)
			(unlocked yes)
			(layer "B.Fab")
			(hide yes)
			(effects
				(font
					(size 1 1)
					(thickness 0.15)
				)
				(justify mirror)
			)
		)
		(property "License" "Apache-2.0"
			(at 0 0 270)
			(unlocked yes)
			(layer "B.Fab")
			(hide yes)
			(effects
				(font
					(size 1 1)
					(thickness 0.15)
				)
				(justify mirror)
			)
		)
		(property "Author" "Antmicro"
			(at 0 0 270)
			(unlocked yes)
			(layer "B.Fab")
			(hide yes)
			(effects
				(font
					(size 1 1)
					(thickness 0.15)
				)
				(justify mirror)
			)
		)
		(property "Val" "0R"
			(at 0 0 270)
			(unlocked yes)
			(layer "B.Fab")
			(hide yes)
			(effects
				(font
					(size 1 1)
					(thickness 0.15)
				)
				(justify mirror)
			)
		)
		(property "Tolerance" "~"
			(at 0 0 270)
			(unlocked yes)
			(layer "B.Fab")
			(hide yes)
			(effects
				(font
					(size 1 1)
					(thickness 0.15)
				)
				(justify mirror)
			)
		)
		(property "Current" "1A"
			(at 0 0 270)
			(unlocked yes)
			(layer "B.Fab")
			(hide yes)
			(effects
				(font
					(size 1 1)
					(thickness 0.15)
				)
				(justify mirror)
			)
		)
		(sheetname "/I^{2}C + I3C/")
		(sheetfile "i2c.kicad_sch")
		(attr smd exclude_from_bom dnp)
		(fp_rect
			(start -0.925 0.47)
			(end 0.925 -0.47)
			(stroke
				(width 0.05)
				(type default)
			)
			(fill no)
			(layer "B.CrtYd")
		)
		(fp_rect
			(start -0.5 0.25)
			(end 0.5 -0.25)
			(stroke
				(width 0.15)
				(type solid)
			)
			(fill no)
			(layer "B.Fab")
		)
		(fp_text user "${REFERENCE}"
			(at -0.95 -3.168 90)
			(layer "B.Fab")
			(effects
				(font
					(size 0.7 0.7)
					(thickness 0.15)
				)
				(justify left bottom mirror)
			)
		)
		(fp_text user "License: Apache-2.0"
			(at -0.95 -5.169 90)
			(layer "B.Fab")
			(effects
				(font
					(size 0.7 0.7)
					(thickness 0.15)
				)
				(justify left bottom mirror)
			)
		)
		(fp_text user "Author: Antmicro"
			(at -0.95 -4.169 90)
			(layer "B.Fab")
			(effects
				(font
					(size 0.7 0.7)
					(thickness 0.15)
				)
				(justify left bottom mirror)
			)
		)
		(pad "1" smd roundrect
			(at -0.48 0 270)
			(size 0.59 0.64)
			(layers "B.Cu" "B.Mask" "B.Paste")
			(roundrect_rratio 0.25)
			(net 473 "Net-(R126-Pad1)")
			(pintype "passive")
		)
		(pad "2" smd roundrect
			(at 0.48 0 270)
			(size 0.59 0.64)
			(layers "B.Cu" "B.Mask" "B.Paste")
			(roundrect_rratio 0.25)
			(net 201 "VDDSPD")
			(pintype "passive")
		)
	)
	(footprint "antmicro-footprints:R_0402_1005Metric"
		(layer "B.Cu")
		(at 184 136.8 90)
		(descr "Resistor SMD 0402")
		(tags "resistor SMD 0402")
		(property "Reference" "R259"
			(at 2.3 0 270)
			(layer "B.SilkS")
			(effects
				(font
					(size 0.7 0.7)
					(thickness 0.15)
				)
				(justify mirror)
			)
		)
		(property "Value" "R_0R_0402"
			(at -1.011843 -1.772047 270)
			(layer "B.Fab")
			(effects
				(font
					(size 0.7 0.7)
					(thickness 0.15)
				)
				(justify left bottom mirror)
			)
		)
		(property "Datasheet" "https://industrial.panasonic.com/cdbs/www-data/pdf/RDA0000/AOA0000C301.pdf"
			(at 0 0 270)
			(layer "B.Fab")
			(hide yes)
			(effects
				(font
					(size 1.27 1.27)
					(thickness 0.15)
				)
				(justify mirror)
			)
		)
		(property "MPN" "ERJ2GE0R00X"
			(at 0 0 90)
			(unlocked yes)
			(layer "B.Fab")
			(hide yes)
			(effects
				(font
					(size 1 1)
					(thickness 0.15)
				)
				(justify mirror)
			)
		)
		(property "Manufacturer" "Panasonic"
			(at 0 0 90)
			(unlocked yes)
			(layer "B.Fab")
			(hide yes)
			(effects
				(font
					(size 1 1)
					(thickness 0.15)
				)
				(justify mirror)
			)
		)
		(property "License" "Apache-2.0"
			(at 0 0 90)
			(unlocked yes)
			(layer "B.Fab")
			(hide yes)
			(effects
				(font
					(size 1 1)
					(thickness 0.15)
				)
				(justify mirror)
			)
		)
		(property "Author" "Antmicro"
			(at 0 0 90)
			(unlocked yes)
			(layer "B.Fab")
			(hide yes)
			(effects
				(font
					(size 1 1)
					(thickness 0.15)
				)
				(justify mirror)
			)
		)
		(property "Val" "0R"
			(at 0 0 90)
			(unlocked yes)
			(layer "B.Fab")
			(hide yes)
			(effects
				(font
					(size 1 1)
					(thickness 0.15)
				)
				(justify mirror)
			)
		)
		(property "Tolerance" "~"
			(at 0 0 90)
			(unlocked yes)
			(layer "B.Fab")
			(hide yes)
			(effects
				(font
					(size 1 1)
					(thickness 0.15)
				)
				(justify mirror)
			)
		)
		(property "Current" "1A"
			(at 0 0 90)
			(unlocked yes)
			(layer "B.Fab")
			(hide yes)
			(effects
				(font
					(size 1 1)
					(thickness 0.15)
				)
				(justify mirror)
			)
		)
		(sheetname "/FPGA banks HP/")
		(sheetfile "fpga-hp-banks.kicad_sch")
		(attr smd)
		(fp_rect
			(start -0.925 0.47)
			(end 0.925 -0.47)
			(stroke
				(width 0.05)
				(type default)
			)
			(fill no)
			(layer "B.CrtYd")
		)
		(fp_rect
			(start -0.5 0.25)
			(end 0.5 -0.25)
			(stroke
				(width 0.15)
				(type solid)
			)
			(fill no)
			(layer "B.Fab")
		)
		(fp_text user "Author: Antmicro"
			(at -0.95 -4.169 270)
			(layer "B.Fab")
			(effects
				(font
					(size 0.7 0.7)
					(thickness 0.15)
				)
				(justify left bottom mirror)
			)
		)
		(fp_text user "License: Apache-2.0"
			(at -0.95 -5.169 270)
			(layer "B.Fab")
			(effects
				(font
					(size 0.7 0.7)
					(thickness 0.15)
				)
				(justify left bottom mirror)
			)
		)
		(fp_text user "${REFERENCE}"
			(at -0.95 -3.168 270)
			(layer "B.Fab")
			(effects
				(font
					(size 0.7 0.7)
					(thickness 0.15)
				)
				(justify left bottom mirror)
			)
		)
		(pad "1" smd roundrect
			(at -0.48 0 90)
			(size 0.59 0.64)
			(layers "B.Cu" "B.Mask" "B.Paste")
			(roundrect_rratio 0.25)
			(net 545 "/FPGA banks HP/VREF_66")
			(pintype "passive")
		)
		(pad "2" smd roundrect
			(at 0.48 0 90)
			(size 0.59 0.64)
			(layers "B.Cu" "B.Mask" "B.Paste")
			(roundrect_rratio 0.25)
			(net 826 "/FPGA banks HP/VREF")
			(pintype "passive")
		)
	)
	(footprint "antmicro-footprints:Coax_Conn_U.FL"
		(layer "B.Cu")
		(at 123.89 127.99 -90)
		(descr "https://media.digikey.com/pdf/Data%20Sheets/Hirose%20PDFs/UFL%20Series.pdf")
		(property "Reference" "J13"
			(at 3.11 -2.46 180)
			(layer "B.SilkS")
			(hide yes)
			(effects
				(font
					(size 0.7 0.7)
					(thickness 0.15)
				)
				(justify left bottom mirror)
			)
		)
		(property "Value" "U_FL-R-SMT-1"
			(at -4.13 -2.52 90)
			(layer "B.Fab")
			(effects
				(font
					(size 0.7 0.7)
					(thickness 0.15)
				)
				(justify left bottom mirror)
			)
		)
		(property "Datasheet" "https://media.digikey.com/pdf/Data%20Sheets/Hirose%20PDFs/UFL%20Series.pdf"
			(at 0 0 270)
			(layer "F.Fab")
			(hide yes)
			(effects
				(font
					(size 1.27 1.27)
					(thickness 0.15)
				)
			)
		)
		(property "MPN" "U.FL-R-SMT-1(10)"
			(at 0 0 270)
			(unlocked yes)
			(layer "B.Fab")
			(hide yes)
			(effects
				(font
					(size 1 1)
					(thickness 0.15)
				)
				(justify mirror)
			)
		)
		(property "Manufacturer" "Hirose Electric"
			(at 0 0 270)
			(unlocked yes)
			(layer "B.Fab")
			(hide yes)
			(effects
				(font
					(size 1 1)
					(thickness 0.15)
				)
				(justify mirror)
			)
		)
		(property "Author" "Antmicro"
			(at 0 0 270)
			(unlocked yes)
			(layer "B.Fab")
			(hide yes)
			(effects
				(font
					(size 1 1)
					(thickness 0.15)
				)
				(justify mirror)
			)
		)
		(property "License" "Apache-2.0"
			(at 0 0 270)
			(unlocked yes)
			(layer "B.Fab")
			(hide yes)
			(effects
				(font
					(size 1 1)
					(thickness 0.15)
				)
				(justify mirror)
			)
		)
		(sheetname "/Debug FTDI + VNA/")
		(sheetfile "debug-ftdi.kicad_sch")
		(attr smd)
		(fp_line
			(start -1.613 1.651)
			(end -1.113 1.651)
			(stroke
				(width 0.15)
				(type solid)
			)
			(layer "B.SilkS")
		)
		(fp_line
			(start -1.613 1.651)
			(end -1.613 1.325)
			(stroke
				(width 0.15)
				(type solid)
			)
			(layer "B.SilkS")
		)
		(fp_line
			(start 1.588 1.651)
			(end 1.088 1.651)
			(stroke
				(width 0.15)
				(type solid)
			)
			(layer "B.SilkS")
		)
		(fp_line
			(start 1.588 1.651)
			(end 1.588 1.325)
			(stroke
				(width 0.15)
				(type solid)
			)
			(layer "B.SilkS")
		)
		(fp_line
			(start -1.613 -1.648)
			(end -1.613 -1.325)
			(stroke
				(width 0.15)
				(type solid)
			)
			(layer "B.SilkS")
		)
		(fp_line
			(start -1.613 -1.648)
			(end -1.113 -1.648)
			(stroke
				(width 0.15)
				(type solid)
			)
			(layer "B.SilkS")
		)
		(fp_line
			(start 1.588 -1.648)
			(end 1.588 -1.325)
			(stroke
				(width 0.15)
				(type solid)
			)
			(layer "B.SilkS")
		)
		(fp_line
			(start 1.588 -1.648)
			(end 1.088 -1.648)
			(stroke
				(width 0.15)
				(type solid)
			)
			(layer "B.SilkS")
		)
		(fp_rect
			(start -2 2.051)
			(end 1.999 -2.05)
			(stroke
				(width 0.05)
				(type solid)
			)
			(fill no)
			(layer "B.CrtYd")
		)
		(fp_line
			(start -1.512 1.551)
			(end 1.487 1.551)
			(stroke
				(width 0.15)
				(type solid)
			)
			(layer "B.Fab")
		)
		(fp_line
			(start -1.512 -1.55)
			(end -1.512 1.551)
			(stroke
				(width 0.15)
				(type solid)
			)
			(layer "B.Fab")
		)
		(fp_line
			(start -1.512 -1.55)
			(end 1.487 -1.55)
			(stroke
				(width 0.15)
				(type solid)
			)
			(layer "B.Fab")
		)
		(fp_line
			(start 1.487 -1.55)
			(end 1.487 1.551)
			(stroke
				(width 0.15)
				(type solid)
			)
			(layer "B.Fab")
		)
		(fp_text user "${REFERENCE}"
			(at -4.13 -6.92 90)
			(layer "B.Fab")
			(effects
				(font
					(size 0.7 0.7)
					(thickness 0.15)
				)
				(justify left bottom mirror)
			)
		)
		(fp_text user "License: Apache-2.0"
			(at -4.13 -5.72 90)
			(layer "B.Fab")
			(effects
				(font
					(size 0.7 0.7)
					(thickness 0.15)
				)
				(justify left bottom mirror)
			)
		)
		(fp_text user "Author: Antmicro"
			(at -4.13 -4.52 90)
			(layer "B.Fab")
			(effects
				(font
					(size 0.7 0.7)
					(thickness 0.15)
				)
				(justify left bottom mirror)
			)
		)
		(pad "1" smd rect
			(at -0.012 -1.499 270)
			(size 1 1.05)
			(layers "B.Cu" "B.Mask" "B.Paste")
			(net 1 "GND")
			(pintype "passive")
		)
		(pad "SH1" smd rect
			(at 1.463 0 270)
			(size 1.05 2.2)
			(layers "B.Cu" "B.Mask" "B.Paste")
			(net 1 "GND")
			(pintype "passive")
		)
		(pad "SH2" smd rect
			(at -1.488 0 270)
			(size 1.05 2.2)
			(layers "B.Cu" "B.Mask" "B.Paste")
			(net 1 "GND")
			(pintype "passive")
		)
		(zone
			(net 0)
			(net_name "")
			(layer "B.Cu")
			(hatch edge 0.508)
			(connect_pads
				(clearance 0)
			)
			(min_thickness 0.254)
			(filled_areas_thickness no)
			(keepout
				(tracks not_allowed)
				(vias not_allowed)
				(pads not_allowed)
				(copperpour not_allowed)
				(footprints not_allowed)
			)
			(placement
				(enabled no)
				(sheetname "")
			)
			(fill
				(thermal_gap 0.508)
				(thermal_bridge_width 0.508)
			)
			(polygon
				(pts
					(xy 124.85 128.92) (xy 124.85 127.04) (xy 122.79 127.04) (xy 122.79 128.92)
				)
			)
		)
	)
	(footprint "antmicro-footprints:R_0402_1005Metric"
		(layer "B.Cu")
		(at 115.397499 119.149 180)
		(descr "Resistor SMD 0402")
		(tags "resistor SMD 0402")
		(property "Reference" "R193"
			(at -4.102501 -0.151 0)
			(layer "B.SilkS")
			(effects
				(font
					(size 0.7 0.7)
					(thickness 0.15)
				)
				(justify left bottom mirror)
			)
		)
		(property "Value" "R_330R_0402"
			(at -1.011843 -1.772047 0)
			(layer "B.Fab")
			(effects
				(font
					(size 0.7 0.7)
					(thickness 0.15)
				)
				(justify left bottom mirror)
			)
		)
		(property "Datasheet" "https://www.bourns.com/docs/product-datasheets/cr.pdf"
			(at 0 0 180)
			(layer "F.Fab")
			(hide yes)
			(effects
				(font
					(size 1.27 1.27)
					(thickness 0.15)
				)
			)
		)
		(property "Manufacturer" "Bourns"
			(at 0 0 180)
			(unlocked yes)
			(layer "B.Fab")
			(hide yes)
			(effects
				(font
					(size 1 1)
					(thickness 0.15)
				)
				(justify mirror)
			)
		)
		(property "MPN" "CR0402-FX-3300GLF"
			(at 0 0 180)
			(unlocked yes)
			(layer "B.Fab")
			(hide yes)
			(effects
				(font
					(size 1 1)
					(thickness 0.15)
				)
				(justify mirror)
			)
		)
		(property "Val" "330R"
			(at 0 0 180)
			(unlocked yes)
			(layer "B.Fab")
			(hide yes)
			(effects
				(font
					(size 1 1)
					(thickness 0.15)
				)
				(justify mirror)
			)
		)
		(property "License" "Apache-2.0"
			(at 0 0 180)
			(unlocked yes)
			(layer "B.Fab")
			(hide yes)
			(effects
				(font
					(size 1 1)
					(thickness 0.15)
				)
				(justify mirror)
			)
		)
		(property "Author" "Antmicro"
			(at 0 0 180)
			(unlocked yes)
			(layer "B.Fab")
			(hide yes)
			(effects
				(font
					(size 1 1)
					(thickness 0.15)
				)
				(justify mirror)
			)
		)
		(property "Tolerance" "1%"
			(at 0 0 180)
			(unlocked yes)
			(layer "B.Fab")
			(hide yes)
			(effects
				(font
					(size 1 1)
					(thickness 0.15)
				)
				(justify mirror)
			)
		)
		(sheetname "/Ethernet/")
		(sheetfile "ethernet.kicad_sch")
		(attr smd)
		(fp_rect
			(start -0.925 0.47)
			(end 0.925 -0.47)
			(stroke
				(width 0.05)
				(type default)
			)
			(fill no)
			(layer "B.CrtYd")
		)
		(fp_rect
			(start -0.5 0.25)
			(end 0.5 -0.25)
			(stroke
				(width 0.15)
				(type solid)
			)
			(fill no)
			(layer "B.Fab")
		)
		(fp_text user "License: Apache-2.0"
			(at -0.95 -5.169 0)
			(layer "B.Fab")
			(effects
				(font
					(size 0.7 0.7)
					(thickness 0.15)
				)
				(justify left bottom mirror)
			)
		)
		(fp_text user "Author: Antmicro"
			(at -0.95 -4.169 0)
			(layer "B.Fab")
			(effects
				(font
					(size 0.7 0.7)
					(thickness 0.15)
				)
				(justify left bottom mirror)
			)
		)
		(fp_text user "${REFERENCE}"
			(at -0.95 -3.168 0)
			(layer "B.Fab")
			(effects
				(font
					(size 0.7 0.7)
					(thickness 0.15)
				)
				(justify left bottom mirror)
			)
		)
		(pad "1" smd roundrect
			(at -0.48 0 180)
			(size 0.59 0.64)
			(layers "B.Cu" "B.Mask" "B.Paste")
			(roundrect_rratio 0.25)
			(net 1 "GND")
			(pintype "passive")
		)
		(pad "2" smd roundrect
			(at 0.48 0 180)
			(size 0.59 0.64)
			(layers "B.Cu" "B.Mask" "B.Paste")
			(roundrect_rratio 0.25)
			(net 31 "Net-(C234-Pad1)")
			(pintype "passive")
		)
	)
	(footprint "antmicro-footprints:NetTie-2_SMD_Pad0.127mm"
		(layer "B.Cu")
		(at 221.635 176.66 90)
		(descr "Net tie, 2 pin, 0.127mm  SMD pads")
		(tags "net tie")
		(property "Reference" "TP23"
			(at 1.11 -0.735 90)
			(layer "B.SilkS")
			(hide yes)
			(effects
				(font
					(size 0.7 0.7)
					(thickness 0.15)
				)
				(justify right bottom mirror)
			)
		)
		(property "Value" "Net-Tie_P0.127mm"
			(at 0 -1.199 90)
			(layer "B.Fab")
			(effects
				(font
					(size 0.7 0.7)
					(thickness 0.15)
				)
				(justify right bottom mirror)
			)
		)
		(property "MPN" ""
			(at 0 0 90)
			(unlocked yes)
			(layer "B.Fab")
			(hide yes)
			(effects
				(font
					(size 1 1)
					(thickness 0.15)
				)
				(justify mirror)
			)
		)
		(property "Manufacturer" ""
			(at 0 0 90)
			(unlocked yes)
			(layer "B.Fab")
			(hide yes)
			(effects
				(font
					(size 1 1)
					(thickness 0.15)
				)
				(justify mirror)
			)
		)
		(property "Author" "Antmicro"
			(at 0 0 90)
			(unlocked yes)
			(layer "B.Fab")
			(hide yes)
			(effects
				(font
					(size 1 1)
					(thickness 0.15)
				)
				(justify mirror)
			)
		)
		(property "License" "Apache-2.0"
			(at 0 0 90)
			(unlocked yes)
			(layer "B.Fab")
			(hide yes)
			(effects
				(font
					(size 1 1)
					(thickness 0.15)
				)
				(justify mirror)
			)
		)
		(property ki_fp_filters "Net*Tie*")
		(sheetname "/Supply/DC-DC VCCINT/")
		(sheetfile "dc-dc-vccint.kicad_sch")
		(attr through_hole exclude_from_pos_files exclude_from_bom)
		(net_tie_pad_groups "1, 2")
		(fp_poly
			(pts
				(xy -0.0635 0.0635) (xy 0.0625 0.0635) (xy 0.0625 -0.0635) (xy -0.0635 -0.0635)
			)
			(stroke
				(width 0)
				(type solid)
			)
			(fill yes)
			(layer "B.Cu")
		)
		(fp_poly
			(pts
				(xy 0.2 0.16) (xy 0.29 0.07) (xy 0.29 -0.07) (xy 0.2 -0.16) (xy -0.2 -0.16) (xy -0.29 -0.07) (xy -0.29 0.06)
				(xy -0.19 0.16)
			)
			(stroke
				(width 0.05)
				(type solid)
			)
			(fill no)
			(layer "B.CrtYd")
		)
		(fp_text user "Author: Antmicro"
			(at -0.128 -4.4 270)
			(layer "B.Fab")
			(effects
				(font
					(size 0.7 0.7)
					(thickness 0.15)
				)
				(justify left bottom mirror)
			)
		)
		(fp_text user "License: Apache-2.0"
			(at -0.128 -5.6 270)
			(layer "B.Fab")
			(effects
				(font
					(size 0.7 0.7)
					(thickness 0.15)
				)
				(justify left bottom mirror)
			)
		)
		(fp_text user "${REFERENCE}"
			(at -0.128 -3.2 270)
			(layer "B.Fab")
			(effects
				(font
					(size 0.7 0.7)
					(thickness 0.15)
				)
				(justify left bottom mirror)
			)
		)
		(pad "1" smd roundrect
			(at -0.127 0 270)
			(size 0.127 0.127)
			(layers "B.Cu")
			(roundrect_rratio 0.5)
			(chamfer_ratio 0)
			(chamfer top_left bottom_left)
			(net 755 "/Supply/DC-DC VCCINT/VREF-")
			(pinfunction "1")
			(pintype "passive")
		)
		(pad "2" smd roundrect
			(at 0.126 0 90)
			(size 0.127 0.127)
			(layers "B.Cu")
			(roundrect_rratio 0.5)
			(chamfer_ratio 0)
			(chamfer top_left bottom_left)
			(net 1 "GND")
			(pinfunction "2")
			(pintype "passive")
		)
	)
	(footprint "antmicro-footprints:R_0402_1005Metric"
		(layer "B.Cu")
		(at 253.039499 143.8)
		(descr "Resistor SMD 0402")
		(tags "resistor SMD 0402")
		(property "Reference" "R87"
			(at -1.139499 1.4 0)
			(layer "B.SilkS")
			(effects
				(font
					(size 0.7 0.7)
					(thickness 0.15)
				)
				(justify right bottom mirror)
			)
		)
		(property "Value" "R_330R_0402"
			(at -1.011843 -1.772047 0)
			(layer "B.Fab")
			(effects
				(font
					(size 0.7 0.7)
					(thickness 0.15)
				)
				(justify right bottom mirror)
			)
		)
		(property "Datasheet" "https://www.bourns.com/docs/product-datasheets/cr.pdf"
			(at 0 0 0)
			(layer "F.Fab")
			(hide yes)
			(effects
				(font
					(size 1.27 1.27)
					(thickness 0.15)
				)
			)
		)
		(property "MPN" "CR0402-FX-3300GLF"
			(at 0 0 0)
			(unlocked yes)
			(layer "B.Fab")
			(hide yes)
			(effects
				(font
					(size 1 1)
					(thickness 0.15)
				)
				(justify mirror)
			)
		)
		(property "Manufacturer" "Bourns"
			(at 0 0 0)
			(unlocked yes)
			(layer "B.Fab")
			(hide yes)
			(effects
				(font
					(size 1 1)
					(thickness 0.15)
				)
				(justify mirror)
			)
		)
		(property "License" "Apache-2.0"
			(at 0 0 0)
			(unlocked yes)
			(layer "B.Fab")
			(hide yes)
			(effects
				(font
					(size 1 1)
					(thickness 0.15)
				)
				(justify mirror)
			)
		)
		(property "Author" "Antmicro"
			(at 0 0 0)
			(unlocked yes)
			(layer "B.Fab")
			(hide yes)
			(effects
				(font
					(size 1 1)
					(thickness 0.15)
				)
				(justify mirror)
			)
		)
		(property "Val" "330R"
			(at 0 0 0)
			(unlocked yes)
			(layer "B.Fab")
			(hide yes)
			(effects
				(font
					(size 1 1)
					(thickness 0.15)
				)
				(justify mirror)
			)
		)
		(property "Tolerance" "1%"
			(at 0 0 0)
			(unlocked yes)
			(layer "B.Fab")
			(hide yes)
			(effects
				(font
					(size 1 1)
					(thickness 0.15)
				)
				(justify mirror)
			)
		)
		(sheetname "/Supply/")
		(sheetfile "supply.kicad_sch")
		(attr smd)
		(fp_rect
			(start -0.925 0.47)
			(end 0.925 -0.47)
			(stroke
				(width 0.05)
				(type default)
			)
			(fill no)
			(layer "B.CrtYd")
		)
		(fp_rect
			(start -0.5 0.25)
			(end 0.5 -0.25)
			(stroke
				(width 0.15)
				(type solid)
			)
			(fill no)
			(layer "B.Fab")
		)
		(fp_text user "${REFERENCE}"
			(at -0.95 -3.168 180)
			(layer "B.Fab")
			(effects
				(font
					(size 0.7 0.7)
					(thickness 0.15)
				)
				(justify left bottom mirror)
			)
		)
		(fp_text user "Author: Antmicro"
			(at -0.95 -4.169 180)
			(layer "B.Fab")
			(effects
				(font
					(size 0.7 0.7)
					(thickness 0.15)
				)
				(justify left bottom mirror)
			)
		)
		(fp_text user "License: Apache-2.0"
			(at -0.95 -5.169 180)
			(layer "B.Fab")
			(effects
				(font
					(size 0.7 0.7)
					(thickness 0.15)
				)
				(justify left bottom mirror)
			)
		)
		(pad "1" smd roundrect
			(at -0.48 0)
			(size 0.59 0.64)
			(layers "B.Cu" "B.Mask" "B.Paste")
			(roundrect_rratio 0.25)
			(net 486 "Net-(R87-Pad1)")
			(pintype "passive")
		)
		(pad "2" smd roundrect
			(at 0.48 0)
			(size 0.59 0.64)
			(layers "B.Cu" "B.Mask" "B.Paste")
			(roundrect_rratio 0.25)
			(net 151 "+3V3")
			(pintype "passive")
		)
	)
	(footprint "antmicro-footprints:C_0402_1005Metric_EIA"
		(layer "B.Cu")
		(at 184 158.5 90)
		(descr "Capacitor SMD 0402 (1005 Metric), square (rectangular) end terminal, IPC_7351 nominal, (Body size source: IPC-SM-782 page 76, https://www.pcb-3d.com/wordpress/wp-content/uploads/ipc-sm-782a_amendment_1_and_2.pdf)")
		(tags "capacitor 0402")
		(property "Reference" "C102"
			(at 9.025 -30.725 90)
			(layer "B.SilkS")
			(effects
				(font
					(size 0.7 0.7)
					(thickness 0.15)
				)
				(justify right bottom mirror)
			)
		)
		(property "Value" "C_4u7_0402"
			(at 0 -1.169 90)
			(layer "B.Fab")
			(effects
				(font
					(size 0.7 0.7)
					(thickness 0.15)
				)
				(justify right bottom mirror)
			)
		)
		(property "Datasheet" "https://www.murata.com/products/productdetail?partno=GRM155R61A475MEAA%23"
			(at 0 0 90)
			(layer "F.Fab")
			(hide yes)
			(effects
				(font
					(size 1.27 1.27)
					(thickness 0.15)
				)
			)
		)
		(property "Manufacturer" "Murata"
			(at 0 0 90)
			(unlocked yes)
			(layer "B.Fab")
			(hide yes)
			(effects
				(font
					(size 1 1)
					(thickness 0.15)
				)
				(justify mirror)
			)
		)
		(property "MPN" "GRM155R61A475MEAAD"
			(at 0 0 90)
			(unlocked yes)
			(layer "B.Fab")
			(hide yes)
			(effects
				(font
					(size 1 1)
					(thickness 0.15)
				)
				(justify mirror)
			)
		)
		(property "Val" "4u7"
			(at 0 0 90)
			(unlocked yes)
			(layer "B.Fab")
			(hide yes)
			(effects
				(font
					(size 1 1)
					(thickness 0.15)
				)
				(justify mirror)
			)
		)
		(property "License" "Apache-2.0"
			(at 0 0 90)
			(unlocked yes)
			(layer "B.Fab")
			(hide yes)
			(effects
				(font
					(size 1 1)
					(thickness 0.15)
				)
				(justify mirror)
			)
		)
		(property "Author" "Antmicro"
			(at 0 0 90)
			(unlocked yes)
			(layer "B.Fab")
			(hide yes)
			(effects
				(font
					(size 1 1)
					(thickness 0.15)
				)
				(justify mirror)
			)
		)
		(property "Voltage" ""
			(at 0 0 90)
			(unlocked yes)
			(layer "B.Fab")
			(hide yes)
			(effects
				(font
					(size 1 1)
					(thickness 0.15)
				)
				(justify mirror)
			)
		)
		(property "Dielectric" ""
			(at 0 0 90)
			(unlocked yes)
			(layer "B.Fab")
			(hide yes)
			(effects
				(font
					(size 1 1)
					(thickness 0.15)
				)
				(justify mirror)
			)
		)
		(sheetname "/FPGA power/")
		(sheetfile "fpga-power.kicad_sch")
		(attr smd)
		(fp_rect
			(start -0.95 0.45)
			(end 0.95 -0.45)
			(stroke
				(width 0.05)
				(type default)
			)
			(fill no)
			(layer "B.CrtYd")
		)
		(fp_line
			(start 0.498 -0.248)
			(end -0.5 -0.248)
			(stroke
				(width 0.15)
				(type solid)
			)
			(layer "B.Fab")
		)
		(fp_line
			(start -0.5 -0.248)
			(end -0.5 0.25)
			(stroke
				(width 0.15)
				(type solid)
			)
			(layer "B.Fab")
		)
		(fp_line
			(start 0.498 0.25)
			(end 0.498 -0.248)
			(stroke
				(width 0.15)
				(type solid)
			)
			(layer "B.Fab")
		)
		(fp_line
			(start -0.5 0.25)
			(end 0.498 0.25)
			(stroke
				(width 0.15)
				(type solid)
			)
			(layer "B.Fab")
		)
		(fp_text user "Author: Antmicro"
			(at -0.9656 -5.569 270)
			(layer "B.Fab")
			(effects
				(font
					(size 0.7 0.7)
					(thickness 0.15)
				)
				(justify left bottom mirror)
			)
		)
		(fp_text user "License: Apache-2.0"
			(at -0.9656 -4.369 270)
			(layer "B.Fab")
			(effects
				(font
					(size 0.7 0.7)
					(thickness 0.15)
				)
				(justify left bottom mirror)
			)
		)
		(fp_text user "${REFERENCE}"
			(at -0.9656 -3.169 270)
			(layer "B.Fab")
			(effects
				(font
					(size 0.7 0.7)
					(thickness 0.15)
				)
				(justify left bottom mirror)
			)
		)
		(pad "1" smd roundrect
			(at -0.5 0)
			(size 0.6 0.6)
			(layers "B.Cu" "B.Mask" "B.Paste")
			(roundrect_rratio 0.25)
			(net 820 "+0V9_MGTAVCC")
			(pintype "passive")
		)
		(pad "2" smd roundrect
			(at 0.498 0 90)
			(size 0.6 0.6)
			(layers "B.Cu" "B.Mask" "B.Paste")
			(roundrect_rratio 0.25)
			(net 1 "GND")
			(pintype "passive")
		)
	)
	(footprint "antmicro-footprints:Coax_Conn_U.FL"
		(layer "B.Cu")
		(at 123.9 102.65 -90)
		(descr "https://media.digikey.com/pdf/Data%20Sheets/Hirose%20PDFs/UFL%20Series.pdf")
		(property "Reference" "J14"
			(at -2.16 2.19 90)
			(layer "B.SilkS")
			(hide yes)
			(effects
				(font
					(size 0.7 0.7)
					(thickness 0.15)
				)
				(justify left bottom mirror)
			)
		)
		(property "Value" "U_FL-R-SMT-1"
			(at -4.13 -2.52 90)
			(layer "B.Fab")
			(effects
				(font
					(size 0.7 0.7)
					(thickness 0.15)
				)
				(justify left bottom mirror)
			)
		)
		(property "Datasheet" "https://media.digikey.com/pdf/Data%20Sheets/Hirose%20PDFs/UFL%20Series.pdf"
			(at 0 0 270)
			(layer "F.Fab")
			(hide yes)
			(effects
				(font
					(size 1.27 1.27)
					(thickness 0.15)
				)
			)
		)
		(property "MPN" "U.FL-R-SMT-1(10)"
			(at 0 0 270)
			(unlocked yes)
			(layer "B.Fab")
			(hide yes)
			(effects
				(font
					(size 1 1)
					(thickness 0.15)
				)
				(justify mirror)
			)
		)
		(property "Manufacturer" "Hirose Electric"
			(at 0 0 270)
			(unlocked yes)
			(layer "B.Fab")
			(hide yes)
			(effects
				(font
					(size 1 1)
					(thickness 0.15)
				)
				(justify mirror)
			)
		)
		(property "Author" "Antmicro"
			(at 0 0 270)
			(unlocked yes)
			(layer "B.Fab")
			(hide yes)
			(effects
				(font
					(size 1 1)
					(thickness 0.15)
				)
				(justify mirror)
			)
		)
		(property "License" "Apache-2.0"
			(at 0 0 270)
			(unlocked yes)
			(layer "B.Fab")
			(hide yes)
			(effects
				(font
					(size 1 1)
					(thickness 0.15)
				)
				(justify mirror)
			)
		)
		(sheetname "/Debug FTDI + VNA/")
		(sheetfile "debug-ftdi.kicad_sch")
		(attr smd)
		(fp_line
			(start -1.613 1.651)
			(end -1.113 1.651)
			(stroke
				(width 0.15)
				(type solid)
			)
			(layer "B.SilkS")
		)
		(fp_line
			(start -1.613 1.651)
			(end -1.613 1.325)
			(stroke
				(width 0.15)
				(type solid)
			)
			(layer "B.SilkS")
		)
		(fp_line
			(start 1.588 1.651)
			(end 1.088 1.651)
			(stroke
				(width 0.15)
				(type solid)
			)
			(layer "B.SilkS")
		)
		(fp_line
			(start 1.588 1.651)
			(end 1.588 1.325)
			(stroke
				(width 0.15)
				(type solid)
			)
			(layer "B.SilkS")
		)
		(fp_line
			(start -1.613 -1.648)
			(end -1.613 -1.325)
			(stroke
				(width 0.15)
				(type solid)
			)
			(layer "B.SilkS")
		)
		(fp_line
			(start -1.613 -1.648)
			(end -1.113 -1.648)
			(stroke
				(width 0.15)
				(type solid)
			)
			(layer "B.SilkS")
		)
		(fp_line
			(start 1.588 -1.648)
			(end 1.588 -1.325)
			(stroke
				(width 0.15)
				(type solid)
			)
			(layer "B.SilkS")
		)
		(fp_line
			(start 1.588 -1.648)
			(end 1.088 -1.648)
			(stroke
				(width 0.15)
				(type solid)
			)
			(layer "B.SilkS")
		)
		(fp_rect
			(start -2 2.051)
			(end 1.999 -2.05)
			(stroke
				(width 0.05)
				(type solid)
			)
			(fill no)
			(layer "B.CrtYd")
		)
		(fp_line
			(start -1.512 1.551)
			(end 1.487 1.551)
			(stroke
				(width 0.15)
				(type solid)
			)
			(layer "B.Fab")
		)
		(fp_line
			(start -1.512 -1.55)
			(end -1.512 1.551)
			(stroke
				(width 0.15)
				(type solid)
			)
			(layer "B.Fab")
		)
		(fp_line
			(start -1.512 -1.55)
			(end 1.487 -1.55)
			(stroke
				(width 0.15)
				(type solid)
			)
			(layer "B.Fab")
		)
		(fp_line
			(start 1.487 -1.55)
			(end 1.487 1.551)
			(stroke
				(width 0.15)
				(type solid)
			)
			(layer "B.Fab")
		)
		(fp_text user "${REFERENCE}"
			(at -4.13 -6.92 90)
			(layer "B.Fab")
			(effects
				(font
					(size 0.7 0.7)
					(thickness 0.15)
				)
				(justify left bottom mirror)
			)
		)
		(fp_text user "License: Apache-2.0"
			(at -4.13 -5.72 90)
			(layer "B.Fab")
			(effects
				(font
					(size 0.7 0.7)
					(thickness 0.15)
				)
				(justify left bottom mirror)
			)
		)
		(fp_text user "Author: Antmicro"
			(at -4.13 -4.52 90)
			(layer "B.Fab")
			(effects
				(font
					(size 0.7 0.7)
					(thickness 0.15)
				)
				(justify left bottom mirror)
			)
		)
		(pad "1" smd rect
			(at -0.012 -1.499 270)
			(size 1 1.05)
			(layers "B.Cu" "B.Mask" "B.Paste")
			(net 370 "Net-(J14-Pad1)")
			(pintype "passive")
		)
		(pad "SH1" smd rect
			(at 1.463 0 270)
			(size 1.05 2.2)
			(layers "B.Cu" "B.Mask" "B.Paste")
			(net 1 "GND")
			(pintype "passive")
		)
		(pad "SH2" smd rect
			(at -1.488 0 270)
			(size 1.05 2.2)
			(layers "B.Cu" "B.Mask" "B.Paste")
			(net 1 "GND")
			(pintype "passive")
		)
		(zone
			(net 0)
			(net_name "")
			(layer "B.Cu")
			(hatch edge 0.508)
			(connect_pads
				(clearance 0)
			)
			(min_thickness 0.254)
			(filled_areas_thickness no)
			(keepout
				(tracks not_allowed)
				(vias not_allowed)
				(pads not_allowed)
				(copperpour not_allowed)
				(footprints not_allowed)
			)
			(placement
				(enabled no)
				(sheetname "")
			)
			(fill
				(thermal_gap 0.508)
				(thermal_bridge_width 0.508)
			)
			(polygon
				(pts
					(xy 124.86 103.58) (xy 124.86 101.7) (xy 122.8 101.7) (xy 122.8 103.58)
				)
			)
		)
	)
	(footprint "antmicro-footprints:R_0402_1005Metric"
		(layer "B.Cu")
		(at 215.1 185.235 90)
		(descr "Resistor SMD 0402")
		(tags "resistor SMD 0402")
		(property "Reference" "R188"
			(at -1.765 -0.6 90)
			(layer "B.SilkS")
			(effects
				(font
					(size 0.7 0.7)
					(thickness 0.15)
				)
				(justify right bottom mirror)
			)
		)
		(property "Value" "R_47k_0402"
			(at -1.011843 -1.772047 90)
			(layer "B.Fab")
			(effects
				(font
					(size 0.7 0.7)
					(thickness 0.15)
				)
				(justify right bottom mirror)
			)
		)
		(property "Datasheet" "https://www.bourns.com/docs/product-datasheets/cr.pdf"
			(at 0 0 90)
			(layer "F.Fab")
			(hide yes)
			(effects
				(font
					(size 1.27 1.27)
					(thickness 0.15)
				)
			)
		)
		(property "MPN" "CR0402-FX-4702GLF"
			(at 0 0 90)
			(unlocked yes)
			(layer "B.Fab")
			(hide yes)
			(effects
				(font
					(size 1 1)
					(thickness 0.15)
				)
				(justify mirror)
			)
		)
		(property "Manufacturer" "Bourns"
			(at 0 0 90)
			(unlocked yes)
			(layer "B.Fab")
			(hide yes)
			(effects
				(font
					(size 1 1)
					(thickness 0.15)
				)
				(justify mirror)
			)
		)
		(property "License" "Apache-2.0"
			(at 0 0 90)
			(unlocked yes)
			(layer "B.Fab")
			(hide yes)
			(effects
				(font
					(size 1 1)
					(thickness 0.15)
				)
				(justify mirror)
			)
		)
		(property "Author" "Antmicro"
			(at 0 0 90)
			(unlocked yes)
			(layer "B.Fab")
			(hide yes)
			(effects
				(font
					(size 1 1)
					(thickness 0.15)
				)
				(justify mirror)
			)
		)
		(property "Val" "47k"
			(at 0 0 90)
			(unlocked yes)
			(layer "B.Fab")
			(hide yes)
			(effects
				(font
					(size 1 1)
					(thickness 0.15)
				)
				(justify mirror)
			)
		)
		(property "Tolerance" "1%"
			(at 0 0 90)
			(unlocked yes)
			(layer "B.Fab")
			(hide yes)
			(effects
				(font
					(size 1 1)
					(thickness 0.15)
				)
				(justify mirror)
			)
		)
		(sheetname "/Supply/DC-DC VCCINT/")
		(sheetfile "dc-dc-vccint.kicad_sch")
		(attr smd)
		(fp_rect
			(start -0.925 0.47)
			(end 0.925 -0.47)
			(stroke
				(width 0.05)
				(type default)
			)
			(fill no)
			(layer "B.CrtYd")
		)
		(fp_rect
			(start -0.5 0.25)
			(end 0.5 -0.25)
			(stroke
				(width 0.15)
				(type solid)
			)
			(fill no)
			(layer "B.Fab")
		)
		(fp_text user "${REFERENCE}"
			(at -0.95 -3.168 270)
			(layer "B.Fab")
			(effects
				(font
					(size 0.7 0.7)
					(thickness 0.15)
				)
				(justify left bottom mirror)
			)
		)
		(fp_text user "License: Apache-2.0"
			(at -0.95 -5.169 270)
			(layer "B.Fab")
			(effects
				(font
					(size 0.7 0.7)
					(thickness 0.15)
				)
				(justify left bottom mirror)
			)
		)
		(fp_text user "Author: Antmicro"
			(at -0.95 -4.169 270)
			(layer "B.Fab")
			(effects
				(font
					(size 0.7 0.7)
					(thickness 0.15)
				)
				(justify left bottom mirror)
			)
		)
		(pad "1" smd roundrect
			(at -0.48 0 90)
			(size 0.59 0.64)
			(layers "B.Cu" "B.Mask" "B.Paste")
			(roundrect_rratio 0.25)
			(net 163 "/Supply/DC-DC VCCINT/V_{CC}")
			(pintype "passive")
		)
		(pad "2" smd roundrect
			(at 0.48 0 90)
			(size 0.59 0.64)
			(layers "B.Cu" "B.Mask" "B.Paste")
			(roundrect_rratio 0.25)
			(net 724 "/Supply/DC-DC VCCINT/TAKE0")
			(pintype "passive")
		)
	)
	(footprint "antmicro-footprints:R_0402_1005Metric"
		(layer "B.Cu")
		(at 253.039499 139.3)
		(descr "Resistor SMD 0402")
		(tags "resistor SMD 0402")
		(property "Reference" "R190"
			(at -4.089499 0.4 0)
			(layer "B.SilkS")
			(effects
				(font
					(size 0.7 0.7)
					(thickness 0.15)
				)
				(justify right bottom mirror)
			)
		)
		(property "Value" "R_47k_0402"
			(at -1.011843 -1.772047 0)
			(layer "B.Fab")
			(effects
				(font
					(size 0.7 0.7)
					(thickness 0.15)
				)
				(justify right bottom mirror)
			)
		)
		(property "Datasheet" "https://www.bourns.com/docs/product-datasheets/cr.pdf"
			(at 0 0 0)
			(layer "F.Fab")
			(hide yes)
			(effects
				(font
					(size 1.27 1.27)
					(thickness 0.15)
				)
			)
		)
		(property "Manufacturer" "Bourns"
			(at 0 0 0)
			(unlocked yes)
			(layer "B.Fab")
			(hide yes)
			(effects
				(font
					(size 1 1)
					(thickness 0.15)
				)
				(justify mirror)
			)
		)
		(property "MPN" "CR0402-FX-4702GLF"
			(at 0 0 0)
			(unlocked yes)
			(layer "B.Fab")
			(hide yes)
			(effects
				(font
					(size 1 1)
					(thickness 0.15)
				)
				(justify mirror)
			)
		)
		(property "Val" "47k"
			(at 0 0 0)
			(unlocked yes)
			(layer "B.Fab")
			(hide yes)
			(effects
				(font
					(size 1 1)
					(thickness 0.15)
				)
				(justify mirror)
			)
		)
		(property "License" "Apache-2.0"
			(at 0 0 0)
			(unlocked yes)
			(layer "B.Fab")
			(hide yes)
			(effects
				(font
					(size 1 1)
					(thickness 0.15)
				)
				(justify mirror)
			)
		)
		(property "Author" "Antmicro"
			(at 0 0 0)
			(unlocked yes)
			(layer "B.Fab")
			(hide yes)
			(effects
				(font
					(size 1 1)
					(thickness 0.15)
				)
				(justify mirror)
			)
		)
		(property "Tolerance" "1%"
			(at 0 0 0)
			(unlocked yes)
			(layer "B.Fab")
			(hide yes)
			(effects
				(font
					(size 1 1)
					(thickness 0.15)
				)
				(justify mirror)
			)
		)
		(sheetname "/Supply/")
		(sheetfile "supply.kicad_sch")
		(attr smd)
		(fp_rect
			(start -0.925 0.47)
			(end 0.925 -0.47)
			(stroke
				(width 0.05)
				(type default)
			)
			(fill no)
			(layer "B.CrtYd")
		)
		(fp_rect
			(start -0.5 0.25)
			(end 0.5 -0.25)
			(stroke
				(width 0.15)
				(type solid)
			)
			(fill no)
			(layer "B.Fab")
		)
		(fp_text user "Author: Antmicro"
			(at -0.95 -4.169 180)
			(layer "B.Fab")
			(effects
				(font
					(size 0.7 0.7)
					(thickness 0.15)
				)
				(justify left bottom mirror)
			)
		)
		(fp_text user "License: Apache-2.0"
			(at -0.95 -5.169 180)
			(layer "B.Fab")
			(effects
				(font
					(size 0.7 0.7)
					(thickness 0.15)
				)
				(justify left bottom mirror)
			)
		)
		(fp_text user "${REFERENCE}"
			(at -0.95 -3.168 180)
			(layer "B.Fab")
			(effects
				(font
					(size 0.7 0.7)
					(thickness 0.15)
				)
				(justify left bottom mirror)
			)
		)
		(pad "1" smd roundrect
			(at -0.48 0)
			(size 0.59 0.64)
			(layers "B.Cu" "B.Mask" "B.Paste")
			(roundrect_rratio 0.25)
			(net 170 "/Supply/EN3")
			(pintype "passive")
		)
		(pad "2" smd roundrect
			(at 0.48 0)
			(size 0.59 0.64)
			(layers "B.Cu" "B.Mask" "B.Paste")
			(roundrect_rratio 0.25)
			(net 38 "+3V3_AON")
			(pintype "passive")
		)
	)
	(footprint "antmicro-footprints:R_0402_1005Metric"
		(layer "B.Cu")
		(at 222.385 181.21)
		(descr "Resistor SMD 0402")
		(tags "resistor SMD 0402")
		(property "Reference" "R202"
			(at -5.06 0.515 0)
			(layer "B.SilkS")
			(effects
				(font
					(size 0.7 0.7)
					(thickness 0.15)
				)
				(justify right bottom mirror)
			)
		)
		(property "Value" "R_8k16_0402"
			(at -1.011843 -1.772047 0)
			(layer "B.Fab")
			(effects
				(font
					(size 0.7 0.7)
					(thickness 0.15)
				)
				(justify right bottom mirror)
			)
		)
		(property "Datasheet" "https://www.yageo.com/upload/media/product/app/datasheet/rchip/pyu-rt_1-to-0.01_rohs_l.pdf"
			(at 0 0 0)
			(layer "F.Fab")
			(hide yes)
			(effects
				(font
					(size 1.27 1.27)
					(thickness 0.15)
				)
			)
		)
		(property "MPN" "RT0402BRE078K16L"
			(at 0 0 0)
			(unlocked yes)
			(layer "B.Fab")
			(hide yes)
			(effects
				(font
					(size 1 1)
					(thickness 0.15)
				)
				(justify mirror)
			)
		)
		(property "Manufacturer" "YAGEO"
			(at 0 0 0)
			(unlocked yes)
			(layer "B.Fab")
			(hide yes)
			(effects
				(font
					(size 1 1)
					(thickness 0.15)
				)
				(justify mirror)
			)
		)
		(property "License" "Apache-2.0"
			(at 0 0 0)
			(unlocked yes)
			(layer "B.Fab")
			(hide yes)
			(effects
				(font
					(size 1 1)
					(thickness 0.15)
				)
				(justify mirror)
			)
		)
		(property "Author" "Antmicro"
			(at 0 0 0)
			(unlocked yes)
			(layer "B.Fab")
			(hide yes)
			(effects
				(font
					(size 1 1)
					(thickness 0.15)
				)
				(justify mirror)
			)
		)
		(property "Val" "8k16"
			(at 0 0 0)
			(unlocked yes)
			(layer "B.Fab")
			(hide yes)
			(effects
				(font
					(size 1 1)
					(thickness 0.15)
				)
				(justify mirror)
			)
		)
		(property "Tolerance" "0.1%"
			(at 0 0 0)
			(unlocked yes)
			(layer "B.Fab")
			(hide yes)
			(effects
				(font
					(size 1 1)
					(thickness 0.15)
				)
				(justify mirror)
			)
		)
		(sheetname "/Supply/DC-DC VCCINT/")
		(sheetfile "dc-dc-vccint.kicad_sch")
		(attr smd)
		(fp_rect
			(start -0.925 0.47)
			(end 0.925 -0.47)
			(stroke
				(width 0.05)
				(type default)
			)
			(fill no)
			(layer "B.CrtYd")
		)
		(fp_rect
			(start -0.5 0.25)
			(end 0.5 -0.25)
			(stroke
				(width 0.15)
				(type solid)
			)
			(fill no)
			(layer "B.Fab")
		)
		(fp_text user "${REFERENCE}"
			(at -0.95 -3.168 180)
			(layer "B.Fab")
			(effects
				(font
					(size 0.7 0.7)
					(thickness 0.15)
				)
				(justify left bottom mirror)
			)
		)
		(fp_text user "Author: Antmicro"
			(at -0.95 -4.169 180)
			(layer "B.Fab")
			(effects
				(font
					(size 0.7 0.7)
					(thickness 0.15)
				)
				(justify left bottom mirror)
			)
		)
		(fp_text user "License: Apache-2.0"
			(at -0.95 -5.169 180)
			(layer "B.Fab")
			(effects
				(font
					(size 0.7 0.7)
					(thickness 0.15)
				)
				(justify left bottom mirror)
			)
		)
		(pad "1" smd roundrect
			(at -0.48 0)
			(size 0.59 0.64)
			(layers "B.Cu" "B.Mask" "B.Paste")
			(roundrect_rratio 0.25)
			(net 755 "/Supply/DC-DC VCCINT/VREF-")
			(pintype "passive")
		)
		(pad "2" smd roundrect
			(at 0.48 0)
			(size 0.59 0.64)
			(layers "B.Cu" "B.Mask" "B.Paste")
			(roundrect_rratio 0.25)
			(net 226 "/Supply/DC-DC VCCINT/V_{0SNS+}")
			(pintype "passive")
		)
	)
	(footprint "antmicro-footprints:C_0402_1005Metric"
		(layer "B.Cu")
		(at 184.510001 167.45 90)
		(descr "Capacitor SMD 0402")
		(tags "capacitor SMD 0402")
		(property "Reference" "C279"
			(at -4 0.401999 90)
			(layer "B.SilkS")
			(effects
				(font
					(size 0.7 0.7)
					(thickness 0.15)
				)
				(justify right bottom mirror)
			)
		)
		(property "Value" "C_100n_0402"
			(at -1.022927 -2.155213 90)
			(layer "B.Fab")
			(effects
				(font
					(size 0.7 0.7)
					(thickness 0.15)
				)
				(justify right bottom mirror)
			)
		)
		(property "Datasheet" "https://www.murata.com/products/productdetail?partno=GRM155R61H104KE14%23"
			(at 0 0 90)
			(layer "F.Fab")
			(hide yes)
			(effects
				(font
					(size 1.27 1.27)
					(thickness 0.15)
				)
			)
		)
		(property "Manufacturer" "Murata"
			(at 0 0 90)
			(unlocked yes)
			(layer "B.Fab")
			(hide yes)
			(effects
				(font
					(size 1 1)
					(thickness 0.15)
				)
				(justify mirror)
			)
		)
		(property "MPN" "GRM155R61H104KE14D"
			(at 0 0 90)
			(unlocked yes)
			(layer "B.Fab")
			(hide yes)
			(effects
				(font
					(size 1 1)
					(thickness 0.15)
				)
				(justify mirror)
			)
		)
		(property "Val" "100n"
			(at 0 0 90)
			(unlocked yes)
			(layer "B.Fab")
			(hide yes)
			(effects
				(font
					(size 1 1)
					(thickness 0.15)
				)
				(justify mirror)
			)
		)
		(property "License" "Apache-2.0"
			(at 0 0 90)
			(unlocked yes)
			(layer "B.Fab")
			(hide yes)
			(effects
				(font
					(size 1 1)
					(thickness 0.15)
				)
				(justify mirror)
			)
		)
		(property "Author" "Antmicro"
			(at 0 0 90)
			(unlocked yes)
			(layer "B.Fab")
			(hide yes)
			(effects
				(font
					(size 1 1)
					(thickness 0.15)
				)
				(justify mirror)
			)
		)
		(property "Voltage" "50V"
			(at 0 0 90)
			(unlocked yes)
			(layer "B.Fab")
			(hide yes)
			(effects
				(font
					(size 1 1)
					(thickness 0.15)
				)
				(justify mirror)
			)
		)
		(property "Dielectric" "X5R"
			(at 0 0 90)
			(unlocked yes)
			(layer "B.Fab")
			(hide yes)
			(effects
				(font
					(size 1 1)
					(thickness 0.15)
				)
				(justify mirror)
			)
		)
		(sheetname "/FPGA MGT Interface/")
		(sheetfile "fpga-mgt.kicad_sch")
		(attr smd)
		(fp_rect
			(start -0.925 0.47)
			(end 0.925 -0.47)
			(stroke
				(width 0.05)
				(type default)
			)
			(fill no)
			(layer "B.CrtYd")
		)
		(fp_line
			(start 0.504 -0.248)
			(end -0.494 -0.248)
			(stroke
				(width 0.15)
				(type solid)
			)
			(layer "B.Fab")
		)
		(fp_line
			(start -0.494 -0.248)
			(end -0.494 0.25)
			(stroke
				(width 0.15)
				(type solid)
			)
			(layer "B.Fab")
		)
		(fp_line
			(start 0.504 0.25)
			(end 0.504 -0.248)
			(stroke
				(width 0.15)
				(type solid)
			)
			(layer "B.Fab")
		)
		(fp_line
			(start -0.494 0.25)
			(end 0.504 0.25)
			(stroke
				(width 0.15)
				(type solid)
			)
			(layer "B.Fab")
		)
		(fp_text user "${REFERENCE}"
			(at -0.939 -4.599 270)
			(layer "B.Fab")
			(effects
				(font
					(size 0.7 0.7)
					(thickness 0.15)
				)
				(justify left bottom mirror)
			)
		)
		(fp_text user "Author: Antmicro"
			(at -0.939 -3.399 270)
			(layer "B.Fab")
			(effects
				(font
					(size 0.7 0.7)
					(thickness 0.15)
				)
				(justify left bottom mirror)
			)
		)
		(fp_text user "License: Apache-2.0"
			(at -0.939 -5.799 270)
			(layer "B.Fab")
			(effects
				(font
					(size 0.7 0.7)
					(thickness 0.15)
				)
				(justify left bottom mirror)
			)
		)
		(pad "1" smd roundrect
			(at -0.48 0 90)
			(size 0.59 0.64)
			(layers "B.Cu" "B.Mask" "B.Paste")
			(roundrect_rratio 0.25)
			(net 267 "/FPGA MGT Interface/HDMI_OUT.D1_P")
			(pintype "passive")
		)
		(pad "2" smd roundrect
			(at 0.48 0 90)
			(size 0.59 0.64)
			(layers "B.Cu" "B.Mask" "B.Paste")
			(roundrect_rratio 0.25)
			(net 630 "/FPGA MGT Interface/HDMI_FPGA.TX1_P")
			(pintype "passive")
		)
	)
	(footprint "antmicro-footprints:C_0402_1005Metric"
		(layer "B.Cu")
		(at 207.321 137.0045)
		(descr "Capacitor SMD 0402")
		(tags "capacitor SMD 0402")
		(property "Reference" "C330"
			(at 2.279 0 0)
			(layer "B.SilkS")
			(effects
				(font
					(size 0.7 0.7)
					(thickness 0.15)
				)
				(justify mirror)
			)
		)
		(property "Value" "C_100n_0402"
			(at -1.022927 -2.155213 0)
			(layer "B.Fab")
			(effects
				(font
					(size 0.7 0.7)
					(thickness 0.15)
				)
				(justify right top mirror)
			)
		)
		(property "Datasheet" "https://www.murata.com/products/productdetail?partno=GRM155R61H104KE14%23"
			(at 0 0 0)
			(layer "B.Fab")
			(hide yes)
			(effects
				(font
					(size 1.27 1.27)
					(thickness 0.15)
				)
				(justify mirror)
			)
		)
		(property "Manufacturer" "Murata"
			(at 0 0 180)
			(unlocked yes)
			(layer "B.Fab")
			(hide yes)
			(effects
				(font
					(size 1 1)
					(thickness 0.15)
				)
				(justify mirror)
			)
		)
		(property "MPN" "GRM155R61H104KE14D"
			(at 0 0 180)
			(unlocked yes)
			(layer "B.Fab")
			(hide yes)
			(effects
				(font
					(size 1 1)
					(thickness 0.15)
				)
				(justify mirror)
			)
		)
		(property "Val" "100n"
			(at 0 0 180)
			(unlocked yes)
			(layer "B.Fab")
			(hide yes)
			(effects
				(font
					(size 1 1)
					(thickness 0.15)
				)
				(justify mirror)
			)
		)
		(property "License" "Apache-2.0"
			(at 0 0 180)
			(unlocked yes)
			(layer "B.Fab")
			(hide yes)
			(effects
				(font
					(size 1 1)
					(thickness 0.15)
				)
				(justify mirror)
			)
		)
		(property "Author" "Antmicro"
			(at 0 0 180)
			(unlocked yes)
			(layer "B.Fab")
			(hide yes)
			(effects
				(font
					(size 1 1)
					(thickness 0.15)
				)
				(justify mirror)
			)
		)
		(property "Voltage" "50V"
			(at 0 0 180)
			(unlocked yes)
			(layer "B.Fab")
			(hide yes)
			(effects
				(font
					(size 1 1)
					(thickness 0.15)
				)
				(justify mirror)
			)
		)
		(property "Dielectric" "X5R"
			(at 0 0 180)
			(unlocked yes)
			(layer "B.Fab")
			(hide yes)
			(effects
				(font
					(size 1 1)
					(thickness 0.15)
				)
				(justify mirror)
			)
		)
		(sheetname "/Supply/")
		(sheetfile "supply.kicad_sch")
		(attr smd)
		(fp_rect
			(start -0.925 0.47)
			(end 0.925 -0.47)
			(stroke
				(width 0.05)
				(type default)
			)
			(fill no)
			(layer "B.CrtYd")
		)
		(fp_line
			(start -0.494 -0.248)
			(end -0.494 0.25)
			(stroke
				(width 0.15)
				(type solid)
			)
			(layer "B.Fab")
		)
		(fp_line
			(start -0.494 0.25)
			(end 0.504 0.25)
			(stroke
				(width 0.15)
				(type solid)
			)
			(layer "B.Fab")
		)
		(fp_line
			(start 0.504 -0.248)
			(end -0.494 -0.248)
			(stroke
				(width 0.15)
				(type solid)
			)
			(layer "B.Fab")
		)
		(fp_line
			(start 0.504 0.25)
			(end 0.504 -0.248)
			(stroke
				(width 0.15)
				(type solid)
			)
			(layer "B.Fab")
		)
		(fp_text user "License: Apache-2.0"
			(at -0.939 -5.799 0)
			(layer "B.Fab")
			(effects
				(font
					(size 0.7 0.7)
					(thickness 0.15)
				)
				(justify right top mirror)
			)
		)
		(fp_text user "Author: Antmicro"
			(at -0.939 -3.399 0)
			(layer "B.Fab")
			(effects
				(font
					(size 0.7 0.7)
					(thickness 0.15)
				)
				(justify right top mirror)
			)
		)
		(fp_text user "${REFERENCE}"
			(at -0.939 -4.599 0)
			(layer "B.Fab")
			(effects
				(font
					(size 0.7 0.7)
					(thickness 0.15)
				)
				(justify right top mirror)
			)
		)
		(pad "1" smd roundrect
			(at -0.48 0)
			(size 0.59 0.64)
			(layers "B.Cu" "B.Mask" "B.Paste")
			(roundrect_rratio 0.25)
			(net 1 "GND")
			(pintype "passive")
		)
		(pad "2" smd roundrect
			(at 0.48 0)
			(size 0.59 0.64)
			(layers "B.Cu" "B.Mask" "B.Paste")
			(roundrect_rratio 0.25)
			(net 687 "VDDQ")
			(pintype "passive")
		)
	)
	(footprint "antmicro-footprints:C_0603_1608Metric"
		(layer "B.Cu")
		(at 188.5 159.2 90)
		(descr "Capacitor SMD 0603")
		(tags "capacitor 0603")
		(property "Reference" "C63"
			(at 9.85 -30.75 90)
			(layer "B.SilkS")
			(effects
				(font
					(size 0.7 0.7)
					(thickness 0.15)
				)
				(justify right bottom mirror)
			)
		)
		(property "Value" "C_47u_0603"
			(at -1.42757 -1.770288 90)
			(layer "B.Fab")
			(effects
				(font
					(size 0.7 0.7)
					(thickness 0.15)
				)
				(justify right bottom mirror)
			)
		)
		(property "Datasheet" "https://www.murata.com/products/productdetail?partno=GRM188R60J476ME15%23"
			(at 0 0 90)
			(layer "F.Fab")
			(hide yes)
			(effects
				(font
					(size 1.27 1.27)
					(thickness 0.15)
				)
			)
		)
		(property "Manufacturer" "Murata"
			(at 0 0 90)
			(unlocked yes)
			(layer "B.Fab")
			(hide yes)
			(effects
				(font
					(size 1 1)
					(thickness 0.15)
				)
				(justify mirror)
			)
		)
		(property "MPN" "GRM188R60J476ME15D"
			(at 0 0 90)
			(unlocked yes)
			(layer "B.Fab")
			(hide yes)
			(effects
				(font
					(size 1 1)
					(thickness 0.15)
				)
				(justify mirror)
			)
		)
		(property "Val" "47u"
			(at 0 0 90)
			(unlocked yes)
			(layer "B.Fab")
			(hide yes)
			(effects
				(font
					(size 1 1)
					(thickness 0.15)
				)
				(justify mirror)
			)
		)
		(property "License" "Apache-2.0"
			(at 0 0 90)
			(unlocked yes)
			(layer "B.Fab")
			(hide yes)
			(effects
				(font
					(size 1 1)
					(thickness 0.15)
				)
				(justify mirror)
			)
		)
		(property "Author" "Antmicro"
			(at 0 0 90)
			(unlocked yes)
			(layer "B.Fab")
			(hide yes)
			(effects
				(font
					(size 1 1)
					(thickness 0.15)
				)
				(justify mirror)
			)
		)
		(property "Voltage" ""
			(at 0 0 90)
			(unlocked yes)
			(layer "B.Fab")
			(hide yes)
			(effects
				(font
					(size 1 1)
					(thickness 0.15)
				)
				(justify mirror)
			)
		)
		(property "Dielectric" ""
			(at 0 0 90)
			(unlocked yes)
			(layer "B.Fab")
			(hide yes)
			(effects
				(font
					(size 1 1)
					(thickness 0.15)
				)
				(justify mirror)
			)
		)
		(sheetname "/FPGA power/")
		(sheetfile "fpga-power.kicad_sch")
		(attr smd)
		(fp_line
			(start -0.15 -0.4)
			(end 0.15 -0.4)
			(stroke
				(width 0.15)
				(type solid)
			)
			(layer "B.SilkS")
		)
		(fp_line
			(start -0.15 0.4)
			(end 0.15 0.4)
			(stroke
				(width 0.15)
				(type solid)
			)
			(layer "B.SilkS")
		)
		(fp_rect
			(start -1.25 0.65)
			(end 1.25 -0.65)
			(stroke
				(width 0.05)
				(type solid)
			)
			(fill no)
			(layer "B.CrtYd")
		)
		(fp_rect
			(start -0.8 0.4)
			(end 0.8 -0.4)
			(stroke
				(width 0.15)
				(type solid)
			)
			(fill no)
			(layer "B.Fab")
		)
		(fp_text user "Author: Antmicro"
			(at -1.682 -4.894 270)
			(layer "B.Fab")
			(effects
				(font
					(size 0.7 0.7)
					(thickness 0.15)
				)
				(justify left bottom mirror)
			)
		)
		(fp_text user "${REFERENCE}"
			(at -1.682 -3.895 270)
			(layer "B.Fab")
			(effects
				(font
					(size 0.7 0.7)
					(thickness 0.15)
				)
				(justify left bottom mirror)
			)
		)
		(fp_text user "License: Apache-2.0"
			(at -1.682 -5.895 270)
			(layer "B.Fab")
			(effects
				(font
					(size 0.7 0.7)
					(thickness 0.15)
				)
				(justify left bottom mirror)
			)
		)
		(pad "1" smd roundrect
			(at -0.7 0 90)
			(size 0.8 1)
			(layers "B.Cu" "B.Mask" "B.Paste")
			(roundrect_rratio 0.2)
			(net 820 "+0V9_MGTAVCC")
			(pintype "passive")
		)
		(pad "2" smd roundrect
			(at 0.7 0 90)
			(size 0.8 1)
			(layers "B.Cu" "B.Mask" "B.Paste")
			(roundrect_rratio 0.2)
			(net 1 "GND")
			(pintype "passive")
		)
	)
	(footprint "antmicro-footprints:C_0402_1005Metric_EIA"
		(layer "B.Cu")
		(at 201 158.5 -90)
		(descr "Capacitor SMD 0402 (1005 Metric), square (rectangular) end terminal, IPC_7351 nominal, (Body size source: IPC-SM-782 page 76, https://www.pcb-3d.com/wordpress/wp-content/uploads/ipc-sm-782a_amendment_1_and_2.pdf)")
		(tags "capacitor 0402")
		(property "Reference" "C108"
			(at 1 -0.425 90)
			(layer "B.SilkS")
			(effects
				(font
					(size 0.7 0.7)
					(thickness 0.15)
				)
				(justify left bottom mirror)
			)
		)
		(property "Value" "C_100n_0402"
			(at 0 -1.169 90)
			(layer "B.Fab")
			(effects
				(font
					(size 0.7 0.7)
					(thickness 0.15)
				)
				(justify left bottom mirror)
			)
		)
		(property "Datasheet" "https://www.murata.com/products/productdetail?partno=GRM155R61H104KE14%23"
			(at 0 0 270)
			(layer "F.Fab")
			(hide yes)
			(effects
				(font
					(size 1.27 1.27)
					(thickness 0.15)
				)
			)
		)
		(property "MPN" "GRM155R61H104KE14D"
			(at 0 0 270)
			(unlocked yes)
			(layer "B.Fab")
			(hide yes)
			(effects
				(font
					(size 1 1)
					(thickness 0.15)
				)
				(justify mirror)
			)
		)
		(property "Manufacturer" "Murata"
			(at 0 0 270)
			(unlocked yes)
			(layer "B.Fab")
			(hide yes)
			(effects
				(font
					(size 1 1)
					(thickness 0.15)
				)
				(justify mirror)
			)
		)
		(property "License" "Apache-2.0"
			(at 0 0 270)
			(unlocked yes)
			(layer "B.Fab")
			(hide yes)
			(effects
				(font
					(size 1 1)
					(thickness 0.15)
				)
				(justify mirror)
			)
		)
		(property "Author" "Antmicro"
			(at 0 0 270)
			(unlocked yes)
			(layer "B.Fab")
			(hide yes)
			(effects
				(font
					(size 1 1)
					(thickness 0.15)
				)
				(justify mirror)
			)
		)
		(property "Val" "100n"
			(at 0 0 270)
			(unlocked yes)
			(layer "B.Fab")
			(hide yes)
			(effects
				(font
					(size 1 1)
					(thickness 0.15)
				)
				(justify mirror)
			)
		)
		(property "Voltage" "50V"
			(at 0 0 270)
			(unlocked yes)
			(layer "B.Fab")
			(hide yes)
			(effects
				(font
					(size 1 1)
					(thickness 0.15)
				)
				(justify mirror)
			)
		)
		(property "Dielectric" "X5R"
			(at 0 0 270)
			(unlocked yes)
			(layer "B.Fab")
			(hide yes)
			(effects
				(font
					(size 1 1)
					(thickness 0.15)
				)
				(justify mirror)
			)
		)
		(sheetname "/FPGA power/")
		(sheetfile "fpga-power.kicad_sch")
		(attr smd)
		(fp_rect
			(start -0.95 0.45)
			(end 0.95 -0.45)
			(stroke
				(width 0.05)
				(type default)
			)
			(fill no)
			(layer "B.CrtYd")
		)
		(fp_line
			(start -0.5 0.25)
			(end 0.498 0.25)
			(stroke
				(width 0.15)
				(type solid)
			)
			(layer "B.Fab")
		)
		(fp_line
			(start 0.498 0.25)
			(end 0.498 -0.248)
			(stroke
				(width 0.15)
				(type solid)
			)
			(layer "B.Fab")
		)
		(fp_line
			(start -0.5 -0.248)
			(end -0.5 0.25)
			(stroke
				(width 0.15)
				(type solid)
			)
			(layer "B.Fab")
		)
		(fp_line
			(start 0.498 -0.248)
			(end -0.5 -0.248)
			(stroke
				(width 0.15)
				(type solid)
			)
			(layer "B.Fab")
		)
		(fp_text user "${REFERENCE}"
			(at -0.9656 -3.169 90)
			(layer "B.Fab")
			(effects
				(font
					(size 0.7 0.7)
					(thickness 0.15)
				)
				(justify left bottom mirror)
			)
		)
		(fp_text user "License: Apache-2.0"
			(at -0.9656 -4.369 90)
			(layer "B.Fab")
			(effects
				(font
					(size 0.7 0.7)
					(thickness 0.15)
				)
				(justify left bottom mirror)
			)
		)
		(fp_text user "Author: Antmicro"
			(at -0.9656 -5.569 90)
			(layer "B.Fab")
			(effects
				(font
					(size 0.7 0.7)
					(thickness 0.15)
				)
				(justify left bottom mirror)
			)
		)
		(pad "1" smd roundrect
			(at -0.5 0 180)
			(size 0.6 0.6)
			(layers "B.Cu" "B.Mask" "B.Paste")
			(roundrect_rratio 0.25)
			(net 1 "GND")
			(pintype "passive")
		)
		(pad "2" smd roundrect
			(at 0.498 0 270)
			(size 0.6 0.6)
			(layers "B.Cu" "B.Mask" "B.Paste")
			(roundrect_rratio 0.25)
			(net 172 "+1V2_MGTAVTT")
			(pintype "passive")
		)
	)
	(footprint "antmicro-footprints:C_0402_1005Metric"
		(layer "B.Cu")
		(at 255.289499 139.25)
		(descr "Capacitor SMD 0402")
		(tags "capacitor SMD 0402")
		(property "Reference" "C209"
			(at 1.410501 0.45 0)
			(layer "B.SilkS")
			(effects
				(font
					(size 0.7 0.7)
					(thickness 0.15)
				)
				(justify right bottom mirror)
			)
		)
		(property "Value" "C_100n_0402"
			(at -1.022927 -2.155213 0)
			(layer "B.Fab")
			(effects
				(font
					(size 0.7 0.7)
					(thickness 0.15)
				)
				(justify right bottom mirror)
			)
		)
		(property "Datasheet" "https://www.murata.com/products/productdetail?partno=GRM155R61H104KE14%23"
			(at 0 0 0)
			(layer "F.Fab")
			(hide yes)
			(effects
				(font
					(size 1.27 1.27)
					(thickness 0.15)
				)
			)
		)
		(property "Manufacturer" "Murata"
			(at 0 0 0)
			(unlocked yes)
			(layer "B.Fab")
			(hide yes)
			(effects
				(font
					(size 1 1)
					(thickness 0.15)
				)
				(justify mirror)
			)
		)
		(property "MPN" "GRM155R61H104KE14D"
			(at 0 0 0)
			(unlocked yes)
			(layer "B.Fab")
			(hide yes)
			(effects
				(font
					(size 1 1)
					(thickness 0.15)
				)
				(justify mirror)
			)
		)
		(property "Val" "100n"
			(at 0 0 0)
			(unlocked yes)
			(layer "B.Fab")
			(hide yes)
			(effects
				(font
					(size 1 1)
					(thickness 0.15)
				)
				(justify mirror)
			)
		)
		(property "License" "Apache-2.0"
			(at 0 0 0)
			(unlocked yes)
			(layer "B.Fab")
			(hide yes)
			(effects
				(font
					(size 1 1)
					(thickness 0.15)
				)
				(justify mirror)
			)
		)
		(property "Author" "Antmicro"
			(at 0 0 0)
			(unlocked yes)
			(layer "B.Fab")
			(hide yes)
			(effects
				(font
					(size 1 1)
					(thickness 0.15)
				)
				(justify mirror)
			)
		)
		(property "Voltage" "50V"
			(at 0 0 0)
			(unlocked yes)
			(layer "B.Fab")
			(hide yes)
			(effects
				(font
					(size 1 1)
					(thickness 0.15)
				)
				(justify mirror)
			)
		)
		(property "Dielectric" "X5R"
			(at 0 0 0)
			(unlocked yes)
			(layer "B.Fab")
			(hide yes)
			(effects
				(font
					(size 1 1)
					(thickness 0.15)
				)
				(justify mirror)
			)
		)
		(sheetname "/Supply/")
		(sheetfile "supply.kicad_sch")
		(attr smd)
		(fp_rect
			(start -0.925 0.47)
			(end 0.925 -0.47)
			(stroke
				(width 0.05)
				(type default)
			)
			(fill no)
			(layer "B.CrtYd")
		)
		(fp_line
			(start -0.494 -0.248)
			(end -0.494 0.25)
			(stroke
				(width 0.15)
				(type solid)
			)
			(layer "B.Fab")
		)
		(fp_line
			(start -0.494 0.25)
			(end 0.504 0.25)
			(stroke
				(width 0.15)
				(type solid)
			)
			(layer "B.Fab")
		)
		(fp_line
			(start 0.504 -0.248)
			(end -0.494 -0.248)
			(stroke
				(width 0.15)
				(type solid)
			)
			(layer "B.Fab")
		)
		(fp_line
			(start 0.504 0.25)
			(end 0.504 -0.248)
			(stroke
				(width 0.15)
				(type solid)
			)
			(layer "B.Fab")
		)
		(fp_text user "License: Apache-2.0"
			(at -0.939 -5.799 180)
			(layer "B.Fab")
			(effects
				(font
					(size 0.7 0.7)
					(thickness 0.15)
				)
				(justify left bottom mirror)
			)
		)
		(fp_text user "Author: Antmicro"
			(at -0.939 -3.399 180)
			(layer "B.Fab")
			(effects
				(font
					(size 0.7 0.7)
					(thickness 0.15)
				)
				(justify left bottom mirror)
			)
		)
		(fp_text user "${REFERENCE}"
			(at -0.939 -4.599 180)
			(layer "B.Fab")
			(effects
				(font
					(size 0.7 0.7)
					(thickness 0.15)
				)
				(justify left bottom mirror)
			)
		)
		(pad "1" smd roundrect
			(at -0.48 0)
			(size 0.59 0.64)
			(layers "B.Cu" "B.Mask" "B.Paste")
			(roundrect_rratio 0.25)
			(net 1 "GND")
			(pintype "passive")
		)
		(pad "2" smd roundrect
			(at 0.48 0)
			(size 0.59 0.64)
			(layers "B.Cu" "B.Mask" "B.Paste")
			(roundrect_rratio 0.25)
			(net 625 "Net-(Q17-D)")
			(pintype "passive")
		)
	)
	(footprint "antmicro-footprints:C_0402_1005Metric_EIA"
		(layer "B.Cu")
		(at 184 154.500001 90)
		(descr "Capacitor SMD 0402 (1005 Metric), square (rectangular) end terminal, IPC_7351 nominal, (Body size source: IPC-SM-782 page 76, https://www.pcb-3d.com/wordpress/wp-content/uploads/ipc-sm-782a_amendment_1_and_2.pdf)")
		(tags "capacitor 0402")
		(property "Reference" "C26"
			(at 10.025001 -30.625 90)
			(layer "B.SilkS")
			(effects
				(font
					(size 0.7 0.7)
					(thickness 0.15)
				)
				(justify right bottom mirror)
			)
		)
		(property "Value" "C_100n_0402"
			(at 0 -1.169 90)
			(layer "B.Fab")
			(effects
				(font
					(size 0.7 0.7)
					(thickness 0.15)
				)
				(justify right bottom mirror)
			)
		)
		(property "Datasheet" "https://www.murata.com/products/productdetail?partno=GRM155R61H104KE14%23"
			(at 0 0 90)
			(layer "F.Fab")
			(hide yes)
			(effects
				(font
					(size 1.27 1.27)
					(thickness 0.15)
				)
			)
		)
		(property "MPN" "GRM155R61H104KE14D"
			(at 0 0 90)
			(unlocked yes)
			(layer "B.Fab")
			(hide yes)
			(effects
				(font
					(size 1 1)
					(thickness 0.15)
				)
				(justify mirror)
			)
		)
		(property "Manufacturer" "Murata"
			(at 0 0 90)
			(unlocked yes)
			(layer "B.Fab")
			(hide yes)
			(effects
				(font
					(size 1 1)
					(thickness 0.15)
				)
				(justify mirror)
			)
		)
		(property "License" "Apache-2.0"
			(at 0 0 90)
			(unlocked yes)
			(layer "B.Fab")
			(hide yes)
			(effects
				(font
					(size 1 1)
					(thickness 0.15)
				)
				(justify mirror)
			)
		)
		(property "Author" "Antmicro"
			(at 0 0 90)
			(unlocked yes)
			(layer "B.Fab")
			(hide yes)
			(effects
				(font
					(size 1 1)
					(thickness 0.15)
				)
				(justify mirror)
			)
		)
		(property "Val" "100n"
			(at 0 0 90)
			(unlocked yes)
			(layer "B.Fab")
			(hide yes)
			(effects
				(font
					(size 1 1)
					(thickness 0.15)
				)
				(justify mirror)
			)
		)
		(property "Voltage" "50V"
			(at 0 0 90)
			(unlocked yes)
			(layer "B.Fab")
			(hide yes)
			(effects
				(font
					(size 1 1)
					(thickness 0.15)
				)
				(justify mirror)
			)
		)
		(property "Dielectric" "X5R"
			(at 0 0 90)
			(unlocked yes)
			(layer "B.Fab")
			(hide yes)
			(effects
				(font
					(size 1 1)
					(thickness 0.15)
				)
				(justify mirror)
			)
		)
		(sheetname "/FPGA power/")
		(sheetfile "fpga-power.kicad_sch")
		(attr smd)
		(fp_rect
			(start -0.95 0.45)
			(end 0.95 -0.45)
			(stroke
				(width 0.05)
				(type default)
			)
			(fill no)
			(layer "B.CrtYd")
		)
		(fp_line
			(start 0.498 -0.248)
			(end -0.5 -0.248)
			(stroke
				(width 0.15)
				(type solid)
			)
			(layer "B.Fab")
		)
		(fp_line
			(start -0.5 -0.248)
			(end -0.5 0.25)
			(stroke
				(width 0.15)
				(type solid)
			)
			(layer "B.Fab")
		)
		(fp_line
			(start 0.498 0.25)
			(end 0.498 -0.248)
			(stroke
				(width 0.15)
				(type solid)
			)
			(layer "B.Fab")
		)
		(fp_line
			(start -0.5 0.25)
			(end 0.498 0.25)
			(stroke
				(width 0.15)
				(type solid)
			)
			(layer "B.Fab")
		)
		(fp_text user "${REFERENCE}"
			(at -0.9656 -3.169 270)
			(layer "B.Fab")
			(effects
				(font
					(size 0.7 0.7)
					(thickness 0.15)
				)
				(justify left bottom mirror)
			)
		)
		(fp_text user "Author: Antmicro"
			(at -0.9656 -5.569 270)
			(layer "B.Fab")
			(effects
				(font
					(size 0.7 0.7)
					(thickness 0.15)
				)
				(justify left bottom mirror)
			)
		)
		(fp_text user "License: Apache-2.0"
			(at -0.9656 -4.369 270)
			(layer "B.Fab")
			(effects
				(font
					(size 0.7 0.7)
					(thickness 0.15)
				)
				(justify left bottom mirror)
			)
		)
		(pad "1" smd roundrect
			(at -0.5 0)
			(size 0.6 0.6)
			(layers "B.Cu" "B.Mask" "B.Paste")
			(roundrect_rratio 0.25)
			(net 1 "GND")
			(pintype "passive")
		)
		(pad "2" smd roundrect
			(at 0.498 0 90)
			(size 0.6 0.6)
			(layers "B.Cu" "B.Mask" "B.Paste")
			(roundrect_rratio 0.25)
			(net 553 "+0V85")
			(pintype "passive")
		)
	)
	(footprint "antmicro-footprints:C_0402_1005Metric_EIA"
		(layer "B.Cu")
		(at 192 158.5 90)
		(descr "Capacitor SMD 0402 (1005 Metric), square (rectangular) end terminal, IPC_7351 nominal, (Body size source: IPC-SM-782 page 76, https://www.pcb-3d.com/wordpress/wp-content/uploads/ipc-sm-782a_amendment_1_and_2.pdf)")
		(tags "capacitor 0402")
		(property "Reference" "C79"
			(at 9.525 -30.65 90)
			(layer "B.SilkS")
			(effects
				(font
					(size 0.7 0.7)
					(thickness 0.15)
				)
				(justify right bottom mirror)
			)
		)
		(property "Value" "C_1u_25V_0402"
			(at 0 -1.169 90)
			(layer "B.Fab")
			(effects
				(font
					(size 0.7 0.7)
					(thickness 0.15)
				)
				(justify right bottom mirror)
			)
		)
		(property "Datasheet" "https://www.murata.com/products/productdetail?partno=GRM155R61E105KE11%23"
			(at 0 0 90)
			(layer "F.Fab")
			(hide yes)
			(effects
				(font
					(size 1.27 1.27)
					(thickness 0.15)
				)
			)
		)
		(property "MPN" "GRM155R61E105KE11J"
			(at 0 0 90)
			(unlocked yes)
			(layer "B.Fab")
			(hide yes)
			(effects
				(font
					(size 1 1)
					(thickness 0.15)
				)
				(justify mirror)
			)
		)
		(property "Manufacturer" "Murata"
			(at 0 0 90)
			(unlocked yes)
			(layer "B.Fab")
			(hide yes)
			(effects
				(font
					(size 1 1)
					(thickness 0.15)
				)
				(justify mirror)
			)
		)
		(property "License" "Apache-2.0"
			(at 0 0 90)
			(unlocked yes)
			(layer "B.Fab")
			(hide yes)
			(effects
				(font
					(size 1 1)
					(thickness 0.15)
				)
				(justify mirror)
			)
		)
		(property "Author" "Antmicro"
			(at 0 0 90)
			(unlocked yes)
			(layer "B.Fab")
			(hide yes)
			(effects
				(font
					(size 1 1)
					(thickness 0.15)
				)
				(justify mirror)
			)
		)
		(property "Val" "1u"
			(at 0 0 90)
			(unlocked yes)
			(layer "B.Fab")
			(hide yes)
			(effects
				(font
					(size 1 1)
					(thickness 0.15)
				)
				(justify mirror)
			)
		)
		(property "Voltage" "25V"
			(at 0 0 90)
			(unlocked yes)
			(layer "B.Fab")
			(hide yes)
			(effects
				(font
					(size 1 1)
					(thickness 0.15)
				)
				(justify mirror)
			)
		)
		(property "Dielectric" "X5R"
			(at 0 0 90)
			(unlocked yes)
			(layer "B.Fab")
			(hide yes)
			(effects
				(font
					(size 1 1)
					(thickness 0.15)
				)
				(justify mirror)
			)
		)
		(sheetname "/FPGA power/")
		(sheetfile "fpga-power.kicad_sch")
		(attr smd)
		(fp_rect
			(start -0.95 0.45)
			(end 0.95 -0.45)
			(stroke
				(width 0.05)
				(type default)
			)
			(fill no)
			(layer "B.CrtYd")
		)
		(fp_line
			(start 0.498 -0.248)
			(end -0.5 -0.248)
			(stroke
				(width 0.15)
				(type solid)
			)
			(layer "B.Fab")
		)
		(fp_line
			(start -0.5 -0.248)
			(end -0.5 0.25)
			(stroke
				(width 0.15)
				(type solid)
			)
			(layer "B.Fab")
		)
		(fp_line
			(start 0.498 0.25)
			(end 0.498 -0.248)
			(stroke
				(width 0.15)
				(type solid)
			)
			(layer "B.Fab")
		)
		(fp_line
			(start -0.5 0.25)
			(end 0.498 0.25)
			(stroke
				(width 0.15)
				(type solid)
			)
			(layer "B.Fab")
		)
		(fp_text user "${REFERENCE}"
			(at -0.9656 -3.169 270)
			(layer "B.Fab")
			(effects
				(font
					(size 0.7 0.7)
					(thickness 0.15)
				)
				(justify left bottom mirror)
			)
		)
		(fp_text user "License: Apache-2.0"
			(at -0.9656 -4.369 270)
			(layer "B.Fab")
			(effects
				(font
					(size 0.7 0.7)
					(thickness 0.15)
				)
				(justify left bottom mirror)
			)
		)
		(fp_text user "Author: Antmicro"
			(at -0.9656 -5.569 270)
			(layer "B.Fab")
			(effects
				(font
					(size 0.7 0.7)
					(thickness 0.15)
				)
				(justify left bottom mirror)
			)
		)
		(pad "1" smd roundrect
			(at -0.5 0)
			(size 0.6 0.6)
			(layers "B.Cu" "B.Mask" "B.Paste")
			(roundrect_rratio 0.25)
			(net 1 "GND")
			(pintype "passive")
		)
		(pad "2" smd roundrect
			(at 0.498 0 90)
			(size 0.6 0.6)
			(layers "B.Cu" "B.Mask" "B.Paste")
			(roundrect_rratio 0.25)
			(net 553 "+0V85")
			(pintype "passive")
		)
	)
	(footprint "antmicro-footprints:R_0402_1005Metric"
		(layer "B.Cu")
		(at 238.439499 166.235)
		(descr "Resistor SMD 0402")
		(tags "resistor SMD 0402")
		(property "Reference" "R135"
			(at 1.173001 0.475 0)
			(layer "B.SilkS")
			(effects
				(font
					(size 0.7 0.7)
					(thickness 0.15)
				)
				(justify right bottom mirror)
			)
		)
		(property "Value" "R_47k_0402"
			(at -1.011843 -1.772047 0)
			(layer "B.Fab")
			(effects
				(font
					(size 0.7 0.7)
					(thickness 0.15)
				)
				(justify right bottom mirror)
			)
		)
		(property "Datasheet" "https://www.bourns.com/docs/product-datasheets/cr.pdf"
			(at 0 0 0)
			(layer "F.Fab")
			(hide yes)
			(effects
				(font
					(size 1.27 1.27)
					(thickness 0.15)
				)
			)
		)
		(property "Manufacturer" "Bourns"
			(at 0 0 0)
			(unlocked yes)
			(layer "B.Fab")
			(hide yes)
			(effects
				(font
					(size 1 1)
					(thickness 0.15)
				)
				(justify mirror)
			)
		)
		(property "MPN" "CR0402-FX-4702GLF"
			(at 0 0 0)
			(unlocked yes)
			(layer "B.Fab")
			(hide yes)
			(effects
				(font
					(size 1 1)
					(thickness 0.15)
				)
				(justify mirror)
			)
		)
		(property "Val" "47k"
			(at 0 0 0)
			(unlocked yes)
			(layer "B.Fab")
			(hide yes)
			(effects
				(font
					(size 1 1)
					(thickness 0.15)
				)
				(justify mirror)
			)
		)
		(property "License" "Apache-2.0"
			(at 0 0 0)
			(unlocked yes)
			(layer "B.Fab")
			(hide yes)
			(effects
				(font
					(size 1 1)
					(thickness 0.15)
				)
				(justify mirror)
			)
		)
		(property "Author" "Antmicro"
			(at 0 0 0)
			(unlocked yes)
			(layer "B.Fab")
			(hide yes)
			(effects
				(font
					(size 1 1)
					(thickness 0.15)
				)
				(justify mirror)
			)
		)
		(property "Tolerance" "1%"
			(at 0 0 0)
			(unlocked yes)
			(layer "B.Fab")
			(hide yes)
			(effects
				(font
					(size 1 1)
					(thickness 0.15)
				)
				(justify mirror)
			)
		)
		(sheetname "/Supply/")
		(sheetfile "supply.kicad_sch")
		(attr smd)
		(fp_rect
			(start -0.925 0.47)
			(end 0.925 -0.47)
			(stroke
				(width 0.05)
				(type default)
			)
			(fill no)
			(layer "B.CrtYd")
		)
		(fp_rect
			(start -0.5 0.25)
			(end 0.5 -0.25)
			(stroke
				(width 0.15)
				(type solid)
			)
			(fill no)
			(layer "B.Fab")
		)
		(fp_text user "Author: Antmicro"
			(at -0.95 -4.169 180)
			(layer "B.Fab")
			(effects
				(font
					(size 0.7 0.7)
					(thickness 0.15)
				)
				(justify left bottom mirror)
			)
		)
		(fp_text user "License: Apache-2.0"
			(at -0.95 -5.169 180)
			(layer "B.Fab")
			(effects
				(font
					(size 0.7 0.7)
					(thickness 0.15)
				)
				(justify left bottom mirror)
			)
		)
		(fp_text user "${REFERENCE}"
			(at -0.95 -3.168 180)
			(layer "B.Fab")
			(effects
				(font
					(size 0.7 0.7)
					(thickness 0.15)
				)
				(justify left bottom mirror)
			)
		)
		(pad "1" smd roundrect
			(at -0.48 0)
			(size 0.59 0.64)
			(layers "B.Cu" "B.Mask" "B.Paste")
			(roundrect_rratio 0.25)
			(net 183 "POWER")
			(pintype "passive")
		)
		(pad "2" smd roundrect
			(at 0.48 0)
			(size 0.59 0.64)
			(layers "B.Cu" "B.Mask" "B.Paste")
			(roundrect_rratio 0.25)
			(net 38 "+3V3_AON")
			(pintype "passive")
		)
	)
	(footprint "antmicro-footprints:SC70-3"
		(layer "B.Cu")
		(at 115.17 166.86 90)
		(property "Reference" "Q19"
			(at -1.24 2.23 90)
			(layer "B.SilkS")
			(effects
				(font
					(size 0.7 0.7)
					(thickness 0.15)
				)
				(justify right bottom mirror)
			)
		)
		(property "Value" "BSS138PW"
			(at 0 -2.3 90)
			(layer "B.Fab")
			(effects
				(font
					(size 0.7 0.7)
					(thickness 0.15)
				)
				(justify right bottom mirror)
			)
		)
		(property "Datasheet" "https://assets.nexperia.com/documents/data-sheet/BSS138PW.pdf"
			(at 0 0 90)
			(layer "F.Fab")
			(hide yes)
			(effects
				(font
					(size 1.27 1.27)
					(thickness 0.15)
				)
			)
		)
		(property "MPN" "BSS138PW"
			(at 0 0 90)
			(unlocked yes)
			(layer "B.Fab")
			(hide yes)
			(effects
				(font
					(size 1 1)
					(thickness 0.15)
				)
				(justify mirror)
			)
		)
		(property "Manufacturer" "Nexperia"
			(at 0 0 90)
			(unlocked yes)
			(layer "B.Fab")
			(hide yes)
			(effects
				(font
					(size 1 1)
					(thickness 0.15)
				)
				(justify mirror)
			)
		)
		(property "Author" "Antmicro"
			(at 0 0 90)
			(unlocked yes)
			(layer "B.Fab")
			(hide yes)
			(effects
				(font
					(size 1 1)
					(thickness 0.15)
				)
				(justify mirror)
			)
		)
		(property "License" "Apache-2.0"
			(at 0 0 90)
			(unlocked yes)
			(layer "B.Fab")
			(hide yes)
			(effects
				(font
					(size 1 1)
					(thickness 0.15)
				)
				(justify mirror)
			)
		)
		(sheetname "/HDMI + SD Card/")
		(sheetfile "hdmi-sd-card.kicad_sch")
		(attr smd)
		(fp_line
			(start -0.3 -1)
			(end 0.627 -1.001)
			(stroke
				(width 0.15)
				(type solid)
			)
			(layer "B.SilkS")
		)
		(fp_line
			(start 0.627 -0.6)
			(end 0.627 -1.001)
			(stroke
				(width 0.15)
				(type solid)
			)
			(layer "B.SilkS")
		)
		(fp_line
			(start 0.627 0.6)
			(end 0.627 0.999)
			(stroke
				(width 0.15)
				(type solid)
			)
			(layer "B.SilkS")
		)
		(fp_line
			(start -0.3 1)
			(end 0.627 0.999)
			(stroke
				(width 0.15)
				(type solid)
			)
			(layer "B.SilkS")
		)
		(fp_line
			(start 0.9 -1.3)
			(end -0.9 -1.3)
			(stroke
				(width 0.05)
				(type solid)
			)
			(layer "B.CrtYd")
		)
		(fp_line
			(start -0.9 -1.3)
			(end -0.9 -1)
			(stroke
				(width 0.05)
				(type solid)
			)
			(layer "B.CrtYd")
		)
		(fp_line
			(start -0.9 -1)
			(end -1.4 -1)
			(stroke
				(width 0.05)
				(type solid)
			)
			(layer "B.CrtYd")
		)
		(fp_line
			(start -1.4 -1)
			(end -1.4 1)
			(stroke
				(width 0.05)
				(type solid)
			)
			(layer "B.CrtYd")
		)
		(fp_line
			(start 1.4 -0.4)
			(end 0.9 -0.4)
			(stroke
				(width 0.05)
				(type solid)
			)
			(layer "B.CrtYd")
		)
		(fp_line
			(start 0.9 -0.4)
			(end 0.9 -1.3)
			(stroke
				(width 0.05)
				(type solid)
			)
			(layer "B.CrtYd")
		)
		(fp_line
			(start 1.4 0.4)
			(end 1.4 -0.4)
			(stroke
				(width 0.05)
				(type solid)
			)
			(layer "B.CrtYd")
		)
		(fp_line
			(start 0.9 0.4)
			(end 1.4 0.4)
			(stroke
				(width 0.05)
				(type solid)
			)
			(layer "B.CrtYd")
		)
		(fp_line
			(start -0.9 1)
			(end -1.4 1)
			(stroke
				(width 0.05)
				(type solid)
			)
			(layer "B.CrtYd")
		)
		(fp_line
			(start 0.9 1.3)
			(end 0.9 0.4)
			(stroke
				(width 0.05)
				(type solid)
			)
			(layer "B.CrtYd")
		)
		(fp_line
			(start -0.9 1.3)
			(end -0.9 1)
			(stroke
				(width 0.05)
				(type solid)
			)
			(layer "B.CrtYd")
		)
		(fp_line
			(start -0.9 1.3)
			(end 0.9 1.3)
			(stroke
				(width 0.05)
				(type solid)
			)
			(layer "B.CrtYd")
		)
		(fp_rect
			(start -0.623 0.999)
			(end 0.627 -1.001)
			(stroke
				(width 0.15)
				(type solid)
			)
			(fill no)
			(layer "B.Fab")
		)
		(fp_text user "License: Apache-2.0"
			(at -1.45 -6.782 270)
			(layer "B.Fab")
			(effects
				(font
					(size 0.7 0.7)
					(thickness 0.15)
				)
				(justify left bottom mirror)
			)
		)
		(fp_text user "Author: Antmicro"
			(at -1.45 -5.782 270)
			(layer "B.Fab")
			(effects
				(font
					(size 0.7 0.7)
					(thickness 0.15)
				)
				(justify left bottom mirror)
			)
		)
		(fp_text user "${REFERENCE}"
			(at -1.45 -4.783 270)
			(layer "B.Fab")
			(effects
				(font
					(size 0.7 0.7)
					(thickness 0.15)
				)
				(justify left bottom mirror)
			)
		)
		(pad "1" smd rect
			(at -1.051 0.65)
			(size 0.6 0.6)
			(layers "B.Cu" "B.Mask" "B.Paste")
			(net 500 "HDMI_IN_HPD")
			(pinfunction "G")
			(pintype "passive")
		)
		(pad "2" smd rect
			(at -1.051 -0.65)
			(size 0.6 0.6)
			(layers "B.Cu" "B.Mask" "B.Paste")
			(net 1 "GND")
			(pinfunction "S")
			(pintype "passive")
		)
		(pad "3" smd rect
			(at 1.05 0)
			(size 0.6 0.6)
			(layers "B.Cu" "B.Mask" "B.Paste")
			(net 506 "Net-(Q18-G)")
			(pinfunction "D")
			(pintype "passive")
		)
	)
	(footprint "antmicro-footprints:C_0402_1005Metric_EIA"
		(layer "B.Cu")
		(at 184 148.5 90)
		(descr "Capacitor SMD 0402 (1005 Metric), square (rectangular) end terminal, IPC_7351 nominal, (Body size source: IPC-SM-782 page 76, https://www.pcb-3d.com/wordpress/wp-content/uploads/ipc-sm-782a_amendment_1_and_2.pdf)")
		(tags "capacitor 0402")
		(property "Reference" "C34"
			(at 11.925 -30.675 270)
			(layer "B.SilkS")
			(effects
				(font
					(size 0.7 0.7)
					(thickness 0.15)
				)
				(justify left bottom mirror)
			)
		)
		(property "Value" "C_1u_25V_0402"
			(at 0 -1.169 270)
			(layer "B.Fab")
			(effects
				(font
					(size 0.7 0.7)
					(thickness 0.15)
				)
				(justify left bottom mirror)
			)
		)
		(property "Datasheet" "https://www.murata.com/products/productdetail?partno=GRM155R61E105KE11%23"
			(at 0 0 90)
			(layer "F.Fab")
			(hide yes)
			(effects
				(font
					(size 1.27 1.27)
					(thickness 0.15)
				)
			)
		)
		(property "MPN" "GRM155R61E105KE11J"
			(at 0 0 90)
			(unlocked yes)
			(layer "B.Fab")
			(hide yes)
			(effects
				(font
					(size 1 1)
					(thickness 0.15)
				)
				(justify mirror)
			)
		)
		(property "Manufacturer" "Murata"
			(at 0 0 90)
			(unlocked yes)
			(layer "B.Fab")
			(hide yes)
			(effects
				(font
					(size 1 1)
					(thickness 0.15)
				)
				(justify mirror)
			)
		)
		(property "License" "Apache-2.0"
			(at 0 0 90)
			(unlocked yes)
			(layer "B.Fab")
			(hide yes)
			(effects
				(font
					(size 1 1)
					(thickness 0.15)
				)
				(justify mirror)
			)
		)
		(property "Author" "Antmicro"
			(at 0 0 90)
			(unlocked yes)
			(layer "B.Fab")
			(hide yes)
			(effects
				(font
					(size 1 1)
					(thickness 0.15)
				)
				(justify mirror)
			)
		)
		(property "Val" "1u"
			(at 0 0 90)
			(unlocked yes)
			(layer "B.Fab")
			(hide yes)
			(effects
				(font
					(size 1 1)
					(thickness 0.15)
				)
				(justify mirror)
			)
		)
		(property "Voltage" "25V"
			(at 0 0 90)
			(unlocked yes)
			(layer "B.Fab")
			(hide yes)
			(effects
				(font
					(size 1 1)
					(thickness 0.15)
				)
				(justify mirror)
			)
		)
		(property "Dielectric" "X5R"
			(at 0 0 90)
			(unlocked yes)
			(layer "B.Fab")
			(hide yes)
			(effects
				(font
					(size 1 1)
					(thickness 0.15)
				)
				(justify mirror)
			)
		)
		(sheetname "/FPGA power/")
		(sheetfile "fpga-power.kicad_sch")
		(attr smd)
		(fp_rect
			(start -0.95 0.45)
			(end 0.95 -0.45)
			(stroke
				(width 0.05)
				(type default)
			)
			(fill no)
			(layer "B.CrtYd")
		)
		(fp_line
			(start 0.498 -0.248)
			(end -0.5 -0.248)
			(stroke
				(width 0.15)
				(type solid)
			)
			(layer "B.Fab")
		)
		(fp_line
			(start -0.5 -0.248)
			(end -0.5 0.25)
			(stroke
				(width 0.15)
				(type solid)
			)
			(layer "B.Fab")
		)
		(fp_line
			(start 0.498 0.25)
			(end 0.498 -0.248)
			(stroke
				(width 0.15)
				(type solid)
			)
			(layer "B.Fab")
		)
		(fp_line
			(start -0.5 0.25)
			(end 0.498 0.25)
			(stroke
				(width 0.15)
				(type solid)
			)
			(layer "B.Fab")
		)
		(fp_text user "Author: Antmicro"
			(at -0.9656 -5.569 270)
			(layer "B.Fab")
			(effects
				(font
					(size 0.7 0.7)
					(thickness 0.15)
				)
				(justify left bottom mirror)
			)
		)
		(fp_text user "License: Apache-2.0"
			(at -0.9656 -4.369 270)
			(layer "B.Fab")
			(effects
				(font
					(size 0.7 0.7)
					(thickness 0.15)
				)
				(justify left bottom mirror)
			)
		)
		(fp_text user "${REFERENCE}"
			(at -0.9656 -3.169 270)
			(layer "B.Fab")
			(effects
				(font
					(size 0.7 0.7)
					(thickness 0.15)
				)
				(justify left bottom mirror)
			)
		)
		(pad "1" smd roundrect
			(at -0.5 0)
			(size 0.6 0.6)
			(layers "B.Cu" "B.Mask" "B.Paste")
			(roundrect_rratio 0.25)
			(net 1 "GND")
			(pintype "passive")
		)
		(pad "2" smd roundrect
			(at 0.498 0 90)
			(size 0.6 0.6)
			(layers "B.Cu" "B.Mask" "B.Paste")
			(roundrect_rratio 0.25)
			(net 553 "+0V85")
			(pintype "passive")
		)
	)
	(footprint "antmicro-footprints:R_0402_1005Metric"
		(layer "B.Cu")
		(at 250.03 117.11 180)
		(descr "Resistor SMD 0402")
		(tags "resistor SMD 0402")
		(property "Reference" "R238"
			(at -1.37 0.57 0)
			(layer "B.SilkS")
			(effects
				(font
					(size 0.7 0.7)
					(thickness 0.15)
				)
				(justify left bottom mirror)
			)
		)
		(property "Value" "R_47k_0402"
			(at -1.011843 -1.772047 0)
			(layer "B.Fab")
			(effects
				(font
					(size 0.7 0.7)
					(thickness 0.15)
				)
				(justify left bottom mirror)
			)
		)
		(property "Datasheet" "https://www.bourns.com/docs/product-datasheets/cr.pdf"
			(at 0 0 180)
			(layer "F.Fab")
			(hide yes)
			(effects
				(font
					(size 1.27 1.27)
					(thickness 0.15)
				)
			)
		)
		(property "MPN" "CR0402-FX-4702GLF"
			(at 0 0 180)
			(unlocked yes)
			(layer "B.Fab")
			(hide yes)
			(effects
				(font
					(size 1 1)
					(thickness 0.15)
				)
				(justify mirror)
			)
		)
		(property "Manufacturer" "Bourns"
			(at 0 0 180)
			(unlocked yes)
			(layer "B.Fab")
			(hide yes)
			(effects
				(font
					(size 1 1)
					(thickness 0.15)
				)
				(justify mirror)
			)
		)
		(property "License" "Apache-2.0"
			(at 0 0 180)
			(unlocked yes)
			(layer "B.Fab")
			(hide yes)
			(effects
				(font
					(size 1 1)
					(thickness 0.15)
				)
				(justify mirror)
			)
		)
		(property "Author" "Antmicro"
			(at 0 0 180)
			(unlocked yes)
			(layer "B.Fab")
			(hide yes)
			(effects
				(font
					(size 1 1)
					(thickness 0.15)
				)
				(justify mirror)
			)
		)
		(property "Val" "47k"
			(at 0 0 180)
			(unlocked yes)
			(layer "B.Fab")
			(hide yes)
			(effects
				(font
					(size 1 1)
					(thickness 0.15)
				)
				(justify mirror)
			)
		)
		(property "Tolerance" "1%"
			(at 0 0 180)
			(unlocked yes)
			(layer "B.Fab")
			(hide yes)
			(effects
				(font
					(size 1 1)
					(thickness 0.15)
				)
				(justify mirror)
			)
		)
		(sheetname "/DDR5 RDIMM/")
		(sheetfile "ddr5-rdimm.kicad_sch")
		(attr smd)
		(fp_rect
			(start -0.925 0.47)
			(end 0.925 -0.47)
			(stroke
				(width 0.05)
				(type default)
			)
			(fill no)
			(layer "B.CrtYd")
		)
		(fp_rect
			(start -0.5 0.25)
			(end 0.5 -0.25)
			(stroke
				(width 0.15)
				(type solid)
			)
			(fill no)
			(layer "B.Fab")
		)
		(fp_text user "Author: Antmicro"
			(at -0.95 -4.169 0)
			(layer "B.Fab")
			(effects
				(font
					(size 0.7 0.7)
					(thickness 0.15)
				)
				(justify left bottom mirror)
			)
		)
		(fp_text user "${REFERENCE}"
			(at -0.95 -3.168 0)
			(layer "B.Fab")
			(effects
				(font
					(size 0.7 0.7)
					(thickness 0.15)
				)
				(justify left bottom mirror)
			)
		)
		(fp_text user "License: Apache-2.0"
			(at -0.95 -5.169 0)
			(layer "B.Fab")
			(effects
				(font
					(size 0.7 0.7)
					(thickness 0.15)
				)
				(justify left bottom mirror)
			)
		)
		(pad "1" smd roundrect
			(at -0.48 0 180)
			(size 0.59 0.64)
			(layers "B.Cu" "B.Mask" "B.Paste")
			(roundrect_rratio 0.25)
			(net 806 "Net-(Q23-G)")
			(pintype "passive")
		)
		(pad "2" smd roundrect
			(at 0.48 0 180)
			(size 0.59 0.64)
			(layers "B.Cu" "B.Mask" "B.Paste")
			(roundrect_rratio 0.25)
			(net 35 "VDC")
			(pintype "passive")
		)
	)
	(footprint "antmicro-footprints:R_0402_1005Metric"
		(layer "B.Cu")
		(at 221.03 183.97)
		(descr "Resistor SMD 0402")
		(tags "resistor SMD 0402")
		(property "Reference" "R197"
			(at -3.83 0.505 0)
			(layer "B.SilkS")
			(effects
				(font
					(size 0.7 0.7)
					(thickness 0.15)
				)
				(justify right bottom mirror)
			)
		)
		(property "Value" "R_4k99_0402"
			(at -1.011843 -1.772047 0)
			(layer "B.Fab")
			(effects
				(font
					(size 0.7 0.7)
					(thickness 0.15)
				)
				(justify right bottom mirror)
			)
		)
		(property "Datasheet" "https://www.bourns.com/docs/product-datasheets/cr.pdf"
			(at 0 0 0)
			(layer "F.Fab")
			(hide yes)
			(effects
				(font
					(size 1.27 1.27)
					(thickness 0.15)
				)
			)
		)
		(property "MPN" "CR0402-FX-4991GLF"
			(at 0 0 0)
			(unlocked yes)
			(layer "B.Fab")
			(hide yes)
			(effects
				(font
					(size 1 1)
					(thickness 0.15)
				)
				(justify mirror)
			)
		)
		(property "Manufacturer" "Bourns"
			(at 0 0 0)
			(unlocked yes)
			(layer "B.Fab")
			(hide yes)
			(effects
				(font
					(size 1 1)
					(thickness 0.15)
				)
				(justify mirror)
			)
		)
		(property "License" "Apache-2.0"
			(at 0 0 0)
			(unlocked yes)
			(layer "B.Fab")
			(hide yes)
			(effects
				(font
					(size 1 1)
					(thickness 0.15)
				)
				(justify mirror)
			)
		)
		(property "Author" "Antmicro"
			(at 0 0 0)
			(unlocked yes)
			(layer "B.Fab")
			(hide yes)
			(effects
				(font
					(size 1 1)
					(thickness 0.15)
				)
				(justify mirror)
			)
		)
		(property "Val" "4k99"
			(at 0 0 0)
			(unlocked yes)
			(layer "B.Fab")
			(hide yes)
			(effects
				(font
					(size 1 1)
					(thickness 0.15)
				)
				(justify mirror)
			)
		)
		(property "Tolerance" "1%"
			(at 0 0 0)
			(unlocked yes)
			(layer "B.Fab")
			(hide yes)
			(effects
				(font
					(size 1 1)
					(thickness 0.15)
				)
				(justify mirror)
			)
		)
		(sheetname "/Supply/DC-DC VCCINT/")
		(sheetfile "dc-dc-vccint.kicad_sch")
		(attr smd)
		(fp_rect
			(start -0.925 0.47)
			(end 0.925 -0.47)
			(stroke
				(width 0.05)
				(type default)
			)
			(fill no)
			(layer "B.CrtYd")
		)
		(fp_rect
			(start -0.5 0.25)
			(end 0.5 -0.25)
			(stroke
				(width 0.15)
				(type solid)
			)
			(fill no)
			(layer "B.Fab")
		)
		(fp_text user "Author: Antmicro"
			(at -0.95 -4.169 180)
			(layer "B.Fab")
			(effects
				(font
					(size 0.7 0.7)
					(thickness 0.15)
				)
				(justify left bottom mirror)
			)
		)
		(fp_text user "License: Apache-2.0"
			(at -0.95 -5.169 180)
			(layer "B.Fab")
			(effects
				(font
					(size 0.7 0.7)
					(thickness 0.15)
				)
				(justify left bottom mirror)
			)
		)
		(fp_text user "${REFERENCE}"
			(at -0.95 -3.168 180)
			(layer "B.Fab")
			(effects
				(font
					(size 0.7 0.7)
					(thickness 0.15)
				)
				(justify left bottom mirror)
			)
		)
		(pad "1" smd roundrect
			(at -0.48 0)
			(size 0.59 0.64)
			(layers "B.Cu" "B.Mask" "B.Paste")
			(roundrect_rratio 0.25)
			(net 1 "GND")
			(pintype "passive")
		)
		(pad "2" smd roundrect
			(at 0.48 0)
			(size 0.59 0.64)
			(layers "B.Cu" "B.Mask" "B.Paste")
			(roundrect_rratio 0.25)
			(net 727 "Net-(U4-ADDR)")
			(pintype "passive")
		)
	)
	(footprint "antmicro-footprints:C_0402_1005Metric_EIA"
		(layer "B.Cu")
		(at 186 162.5 90)
		(descr "Capacitor SMD 0402 (1005 Metric), square (rectangular) end terminal, IPC_7351 nominal, (Body size source: IPC-SM-782 page 76, https://www.pcb-3d.com/wordpress/wp-content/uploads/ipc-sm-782a_amendment_1_and_2.pdf)")
		(tags "capacitor 0402")
		(property "Reference" "C107"
			(at -3.95 0.1 90)
			(layer "B.SilkS")
			(effects
				(font
					(size 0.7 0.7)
					(thickness 0.15)
				)
				(justify right bottom mirror)
			)
		)
		(property "Value" "C_100n_0402"
			(at 0 -1.169 90)
			(layer "B.Fab")
			(effects
				(font
					(size 0.7 0.7)
					(thickness 0.15)
				)
				(justify right bottom mirror)
			)
		)
		(property "Datasheet" "https://www.murata.com/products/productdetail?partno=GRM155R61H104KE14%23"
			(at 0 0 90)
			(layer "F.Fab")
			(hide yes)
			(effects
				(font
					(size 1.27 1.27)
					(thickness 0.15)
				)
			)
		)
		(property "MPN" "GRM155R61H104KE14D"
			(at 0 0 90)
			(unlocked yes)
			(layer "B.Fab")
			(hide yes)
			(effects
				(font
					(size 1 1)
					(thickness 0.15)
				)
				(justify mirror)
			)
		)
		(property "Manufacturer" "Murata"
			(at 0 0 90)
			(unlocked yes)
			(layer "B.Fab")
			(hide yes)
			(effects
				(font
					(size 1 1)
					(thickness 0.15)
				)
				(justify mirror)
			)
		)
		(property "License" "Apache-2.0"
			(at 0 0 90)
			(unlocked yes)
			(layer "B.Fab")
			(hide yes)
			(effects
				(font
					(size 1 1)
					(thickness 0.15)
				)
				(justify mirror)
			)
		)
		(property "Author" "Antmicro"
			(at 0 0 90)
			(unlocked yes)
			(layer "B.Fab")
			(hide yes)
			(effects
				(font
					(size 1 1)
					(thickness 0.15)
				)
				(justify mirror)
			)
		)
		(property "Val" "100n"
			(at 0 0 90)
			(unlocked yes)
			(layer "B.Fab")
			(hide yes)
			(effects
				(font
					(size 1 1)
					(thickness 0.15)
				)
				(justify mirror)
			)
		)
		(property "Voltage" "50V"
			(at 0 0 90)
			(unlocked yes)
			(layer "B.Fab")
			(hide yes)
			(effects
				(font
					(size 1 1)
					(thickness 0.15)
				)
				(justify mirror)
			)
		)
		(property "Dielectric" "X5R"
			(at 0 0 90)
			(unlocked yes)
			(layer "B.Fab")
			(hide yes)
			(effects
				(font
					(size 1 1)
					(thickness 0.15)
				)
				(justify mirror)
			)
		)
		(sheetname "/FPGA power/")
		(sheetfile "fpga-power.kicad_sch")
		(attr smd)
		(fp_rect
			(start -0.95 0.45)
			(end 0.95 -0.45)
			(stroke
				(width 0.05)
				(type default)
			)
			(fill no)
			(layer "B.CrtYd")
		)
		(fp_line
			(start 0.498 -0.248)
			(end -0.5 -0.248)
			(stroke
				(width 0.15)
				(type solid)
			)
			(layer "B.Fab")
		)
		(fp_line
			(start -0.5 -0.248)
			(end -0.5 0.25)
			(stroke
				(width 0.15)
				(type solid)
			)
			(layer "B.Fab")
		)
		(fp_line
			(start 0.498 0.25)
			(end 0.498 -0.248)
			(stroke
				(width 0.15)
				(type solid)
			)
			(layer "B.Fab")
		)
		(fp_line
			(start -0.5 0.25)
			(end 0.498 0.25)
			(stroke
				(width 0.15)
				(type solid)
			)
			(layer "B.Fab")
		)
		(fp_text user "Author: Antmicro"
			(at -0.9656 -5.569 270)
			(layer "B.Fab")
			(effects
				(font
					(size 0.7 0.7)
					(thickness 0.15)
				)
				(justify left bottom mirror)
			)
		)
		(fp_text user "License: Apache-2.0"
			(at -0.9656 -4.369 270)
			(layer "B.Fab")
			(effects
				(font
					(size 0.7 0.7)
					(thickness 0.15)
				)
				(justify left bottom mirror)
			)
		)
		(fp_text user "${REFERENCE}"
			(at -0.9656 -3.169 270)
			(layer "B.Fab")
			(effects
				(font
					(size 0.7 0.7)
					(thickness 0.15)
				)
				(justify left bottom mirror)
			)
		)
		(pad "1" smd roundrect
			(at -0.5 0)
			(size 0.6 0.6)
			(layers "B.Cu" "B.Mask" "B.Paste")
			(roundrect_rratio 0.25)
			(net 1 "GND")
			(pintype "passive")
		)
		(pad "2" smd roundrect
			(at 0.498 0 90)
			(size 0.6 0.6)
			(layers "B.Cu" "B.Mask" "B.Paste")
			(roundrect_rratio 0.25)
			(net 172 "+1V2_MGTAVTT")
			(pintype "passive")
		)
	)
	(footprint "antmicro-footprints:C_0603_1608Metric"
		(layer "B.Cu")
		(at 188.5 153.75 90)
		(descr "Capacitor SMD 0603")
		(tags "capacitor 0603")
		(property "Reference" "C62"
			(at 9.725 -30.7 90)
			(layer "B.SilkS")
			(effects
				(font
					(size 0.7 0.7)
					(thickness 0.15)
				)
				(justify right bottom mirror)
			)
		)
		(property "Value" "C_47u_0603"
			(at -1.42757 -1.770288 90)
			(layer "B.Fab")
			(effects
				(font
					(size 0.7 0.7)
					(thickness 0.15)
				)
				(justify right bottom mirror)
			)
		)
		(property "Datasheet" "https://www.murata.com/products/productdetail?partno=GRM188R60J476ME15%23"
			(at 0 0 90)
			(layer "F.Fab")
			(hide yes)
			(effects
				(font
					(size 1.27 1.27)
					(thickness 0.15)
				)
			)
		)
		(property "Manufacturer" "Murata"
			(at 0 0 90)
			(unlocked yes)
			(layer "B.Fab")
			(hide yes)
			(effects
				(font
					(size 1 1)
					(thickness 0.15)
				)
				(justify mirror)
			)
		)
		(property "MPN" "GRM188R60J476ME15D"
			(at 0 0 90)
			(unlocked yes)
			(layer "B.Fab")
			(hide yes)
			(effects
				(font
					(size 1 1)
					(thickness 0.15)
				)
				(justify mirror)
			)
		)
		(property "Val" "47u"
			(at 0 0 90)
			(unlocked yes)
			(layer "B.Fab")
			(hide yes)
			(effects
				(font
					(size 1 1)
					(thickness 0.15)
				)
				(justify mirror)
			)
		)
		(property "License" "Apache-2.0"
			(at 0 0 90)
			(unlocked yes)
			(layer "B.Fab")
			(hide yes)
			(effects
				(font
					(size 1 1)
					(thickness 0.15)
				)
				(justify mirror)
			)
		)
		(property "Author" "Antmicro"
			(at 0 0 90)
			(unlocked yes)
			(layer "B.Fab")
			(hide yes)
			(effects
				(font
					(size 1 1)
					(thickness 0.15)
				)
				(justify mirror)
			)
		)
		(property "Voltage" ""
			(at 0 0 90)
			(unlocked yes)
			(layer "B.Fab")
			(hide yes)
			(effects
				(font
					(size 1 1)
					(thickness 0.15)
				)
				(justify mirror)
			)
		)
		(property "Dielectric" ""
			(at 0 0 90)
			(unlocked yes)
			(layer "B.Fab")
			(hide yes)
			(effects
				(font
					(size 1 1)
					(thickness 0.15)
				)
				(justify mirror)
			)
		)
		(sheetname "/FPGA power/")
		(sheetfile "fpga-power.kicad_sch")
		(attr smd)
		(fp_line
			(start -0.15 -0.4)
			(end 0.15 -0.4)
			(stroke
				(width 0.15)
				(type solid)
			)
			(layer "B.SilkS")
		)
		(fp_line
			(start -0.15 0.4)
			(end 0.15 0.4)
			(stroke
				(width 0.15)
				(type solid)
			)
			(layer "B.SilkS")
		)
		(fp_rect
			(start -1.25 0.65)
			(end 1.25 -0.65)
			(stroke
				(width 0.05)
				(type solid)
			)
			(fill no)
			(layer "B.CrtYd")
		)
		(fp_rect
			(start -0.8 0.4)
			(end 0.8 -0.4)
			(stroke
				(width 0.15)
				(type solid)
			)
			(fill no)
			(layer "B.Fab")
		)
		(fp_text user "${REFERENCE}"
			(at -1.682 -3.895 270)
			(layer "B.Fab")
			(effects
				(font
					(size 0.7 0.7)
					(thickness 0.15)
				)
				(justify left bottom mirror)
			)
		)
		(fp_text user "License: Apache-2.0"
			(at -1.682 -5.895 270)
			(layer "B.Fab")
			(effects
				(font
					(size 0.7 0.7)
					(thickness 0.15)
				)
				(justify left bottom mirror)
			)
		)
		(fp_text user "Author: Antmicro"
			(at -1.682 -4.894 270)
			(layer "B.Fab")
			(effects
				(font
					(size 0.7 0.7)
					(thickness 0.15)
				)
				(justify left bottom mirror)
			)
		)
		(pad "1" smd roundrect
			(at -0.7 0 90)
			(size 0.8 1)
			(layers "B.Cu" "B.Mask" "B.Paste")
			(roundrect_rratio 0.2)
			(net 553 "+0V85")
			(pintype "passive")
		)
		(pad "2" smd roundrect
			(at 0.7 0 90)
			(size 0.8 1)
			(layers "B.Cu" "B.Mask" "B.Paste")
			(roundrect_rratio 0.2)
			(net 1 "GND")
			(pintype "passive")
		)
	)
	(footprint "antmicro-footprints:R_0402_1005Metric"
		(layer "B.Cu")
		(at 217.89 151.85 180)
		(descr "Resistor SMD 0402")
		(tags "resistor SMD 0402")
		(property "Reference" "R8"
			(at 1.16 -0.47 0)
			(layer "B.SilkS")
			(effects
				(font
					(size 0.7 0.7)
					(thickness 0.15)
				)
				(justify left bottom mirror)
			)
		)
		(property "Value" "R_22R_0402"
			(at -1.011843 -1.772047 0)
			(layer "B.Fab")
			(effects
				(font
					(size 0.7 0.7)
					(thickness 0.15)
				)
				(justify left bottom mirror)
			)
		)
		(property "Datasheet" "https://www.bourns.com/docs/product-datasheets/cr.pdf"
			(at 0 0 180)
			(layer "F.Fab")
			(hide yes)
			(effects
				(font
					(size 1.27 1.27)
					(thickness 0.15)
				)
			)
		)
		(property "Manufacturer" "Bourns"
			(at 0 0 180)
			(unlocked yes)
			(layer "B.Fab")
			(hide yes)
			(effects
				(font
					(size 1 1)
					(thickness 0.15)
				)
				(justify mirror)
			)
		)
		(property "MPN" "CR0402-FX-22R0GLF"
			(at 0 0 180)
			(unlocked yes)
			(layer "B.Fab")
			(hide yes)
			(effects
				(font
					(size 1 1)
					(thickness 0.15)
				)
				(justify mirror)
			)
		)
		(property "Val" "22R"
			(at 0 0 180)
			(unlocked yes)
			(layer "B.Fab")
			(hide yes)
			(effects
				(font
					(size 1 1)
					(thickness 0.15)
				)
				(justify mirror)
			)
		)
		(property "License" "Apache-2.0"
			(at 0 0 180)
			(unlocked yes)
			(layer "B.Fab")
			(hide yes)
			(effects
				(font
					(size 1 1)
					(thickness 0.15)
				)
				(justify mirror)
			)
		)
		(property "Author" "Antmicro"
			(at 0 0 180)
			(unlocked yes)
			(layer "B.Fab")
			(hide yes)
			(effects
				(font
					(size 1 1)
					(thickness 0.15)
				)
				(justify mirror)
			)
		)
		(property "Tolerance" "1%"
			(at 0 0 180)
			(unlocked yes)
			(layer "B.Fab")
			(hide yes)
			(effects
				(font
					(size 1 1)
					(thickness 0.15)
				)
				(justify mirror)
			)
		)
		(sheetname "/HyperRAM + QSPI Flash/")
		(sheetfile "hyperram-flash.kicad_sch")
		(attr smd)
		(fp_rect
			(start -0.925 0.47)
			(end 0.925 -0.47)
			(stroke
				(width 0.05)
				(type default)
			)
			(fill no)
			(layer "B.CrtYd")
		)
		(fp_rect
			(start -0.5 0.25)
			(end 0.5 -0.25)
			(stroke
				(width 0.15)
				(type solid)
			)
			(fill no)
			(layer "B.Fab")
		)
		(fp_text user "${REFERENCE}"
			(at -0.95 -3.168 0)
			(layer "B.Fab")
			(effects
				(font
					(size 0.7 0.7)
					(thickness 0.15)
				)
				(justify left bottom mirror)
			)
		)
		(fp_text user "Author: Antmicro"
			(at -0.95 -4.169 0)
			(layer "B.Fab")
			(effects
				(font
					(size 0.7 0.7)
					(thickness 0.15)
				)
				(justify left bottom mirror)
			)
		)
		(fp_text user "License: Apache-2.0"
			(at -0.95 -5.169 0)
			(layer "B.Fab")
			(effects
				(font
					(size 0.7 0.7)
					(thickness 0.15)
				)
				(justify left bottom mirror)
			)
		)
		(pad "1" smd roundrect
			(at -0.48 0 180)
			(size 0.59 0.64)
			(layers "B.Cu" "B.Mask" "B.Paste")
			(roundrect_rratio 0.25)
			(net 280 "/HyperRAM + QSPI Flash/IO2")
			(pintype "passive")
		)
		(pad "2" smd roundrect
			(at 0.48 0 180)
			(size 0.59 0.64)
			(layers "B.Cu" "B.Mask" "B.Paste")
			(roundrect_rratio 0.25)
			(net 353 "/FPGA Config/FLASH.IO2")
			(pintype "passive")
		)
	)
	(footprint "antmicro-footprints:R_0402_1005Metric_EIA"
		(layer "B.Cu")
		(at 197.5 154)
		(descr "Resistor SMD 0402 (1005 Metric), square (rectangular) end terminal, IPC_7351 nominal, (Body size source: IPC-SM-782 page 76, https://www.pcb-3d.com/wordpress/wp-content/uploads/ipc-sm-782a_amendment_1_and_2.pdf)")
		(tags "resistor 0402")
		(property "Reference" "R194"
			(at -31.925 -10.3 0)
			(layer "B.SilkS")
			(effects
				(font
					(size 0.7 0.7)
					(thickness 0.15)
				)
				(justify right bottom mirror)
			)
		)
		(property "Value" "R_100R_0402"
			(at 0 -1.169 0)
			(layer "B.Fab")
			(effects
				(font
					(size 0.7 0.7)
					(thickness 0.15)
				)
				(justify right bottom mirror)
			)
		)
		(property "Datasheet" "https://www.bourns.com/docs/product-datasheets/cr.pdf"
			(at 0 0 0)
			(layer "F.Fab")
			(hide yes)
			(effects
				(font
					(size 1.27 1.27)
					(thickness 0.15)
				)
			)
		)
		(property "Manufacturer" "Bourns"
			(at 0 0 0)
			(unlocked yes)
			(layer "B.Fab")
			(hide yes)
			(effects
				(font
					(size 1 1)
					(thickness 0.15)
				)
				(justify mirror)
			)
		)
		(property "MPN" "CR0402-FX-1000GLF"
			(at 0 0 0)
			(unlocked yes)
			(layer "B.Fab")
			(hide yes)
			(effects
				(font
					(size 1 1)
					(thickness 0.15)
				)
				(justify mirror)
			)
		)
		(property "Val" "100R"
			(at 0 0 0)
			(unlocked yes)
			(layer "B.Fab")
			(hide yes)
			(effects
				(font
					(size 1 1)
					(thickness 0.15)
				)
				(justify mirror)
			)
		)
		(property "License" "Apache-2.0"
			(at 0 0 0)
			(unlocked yes)
			(layer "B.Fab")
			(hide yes)
			(effects
				(font
					(size 1 1)
					(thickness 0.15)
				)
				(justify mirror)
			)
		)
		(property "Author" "Antmicro"
			(at 0 0 0)
			(unlocked yes)
			(layer "B.Fab")
			(hide yes)
			(effects
				(font
					(size 1 1)
					(thickness 0.15)
				)
				(justify mirror)
			)
		)
		(property "Tolerance" "1%"
			(at 0 0 0)
			(unlocked yes)
			(layer "B.Fab")
			(hide yes)
			(effects
				(font
					(size 1 1)
					(thickness 0.15)
				)
				(justify mirror)
			)
		)
		(sheetname "/FPGA Config/")
		(sheetfile "fpga-config.kicad_sch")
		(attr smd)
		(fp_rect
			(start -0.95 0.45)
			(end 0.95 -0.45)
			(stroke
				(width 0.05)
				(type default)
			)
			(fill no)
			(layer "B.CrtYd")
		)
		(fp_line
			(start -0.5 -0.249)
			(end -0.5 0.25)
			(stroke
				(width 0.15)
				(type solid)
			)
			(layer "B.Fab")
		)
		(fp_line
			(start -0.5 0.25)
			(end 0.499 0.25)
			(stroke
				(width 0.15)
				(type solid)
			)
			(layer "B.Fab")
		)
		(fp_line
			(start 0.499 -0.249)
			(end -0.5 -0.249)
			(stroke
				(width 0.15)
				(type solid)
			)
			(layer "B.Fab")
		)
		(fp_line
			(start 0.499 0.25)
			(end 0.499 -0.249)
			(stroke
				(width 0.15)
				(type solid)
			)
			(layer "B.Fab")
		)
		(fp_text user "${REFERENCE}"
			(at -0.95 -3.169 180)
			(layer "B.Fab")
			(effects
				(font
					(size 0.7 0.7)
					(thickness 0.15)
				)
				(justify left bottom mirror)
			)
		)
		(fp_text user "Author: Antmicro"
			(at -0.95 -5.569 180)
			(layer "B.Fab")
			(effects
				(font
					(size 0.7 0.7)
					(thickness 0.15)
				)
				(justify left bottom mirror)
			)
		)
		(fp_text user "License: Apache-2.0"
			(at -0.95 -4.369 180)
			(layer "B.Fab")
			(effects
				(font
					(size 0.7 0.7)
					(thickness 0.15)
				)
				(justify left bottom mirror)
			)
		)
		(pad "1" smd roundrect
			(at -0.5 0 270)
			(size 0.6 0.6)
			(layers "B.Cu" "B.Mask" "B.Paste")
			(roundrect_rratio 0.25)
			(net 462 "/FPGA Config/POR_OVERRIDE")
			(pintype "passive")
		)
		(pad "2" smd roundrect
			(at 0.499 0)
			(size 0.6 0.6)
			(layers "B.Cu" "B.Mask" "B.Paste")
			(roundrect_rratio 0.25)
			(net 1 "GND")
			(pintype "passive")
		)
	)
	(footprint "antmicro-footprints:USON-10_2.5x1mm_P0.5mm"
		(layer "B.Cu")
		(at 107.804 163.868 180)
		(descr "USON-10 2.5x1mm_ Pitch 0.5mm")
		(tags "USON-10 2.5x1mm Pitch 0.5mm")
		(property "Reference" "U47"
			(at -2.174 -0.782 90)
			(layer "B.SilkS")
			(effects
				(font
					(size 0.7 0.7)
					(thickness 0.15)
				)
				(justify right bottom mirror)
			)
		)
		(property "Value" "TPD4E05U06QDQARQ1"
			(at 0.018 -2.499 0)
			(layer "B.Fab")
			(effects
				(font
					(size 0.7 0.7)
					(thickness 0.15)
				)
				(justify left bottom mirror)
			)
		)
		(property "Datasheet" "https://www.ti.com/lit/ds/symlink/tpd4e05u06-q1.pdf?HQS=dis-mous-null-mousermode-dsf-pf-null-wwe&ts=1663591265741&ref_url=https%253A%252F%252Fwww.mouser.com%252F"
			(at 0 0 180)
			(layer "F.Fab")
			(hide yes)
			(effects
				(font
					(size 1.27 1.27)
					(thickness 0.15)
				)
			)
		)
		(property "Manufacturer" "Texas Instruments"
			(at 0 0 180)
			(unlocked yes)
			(layer "B.Fab")
			(hide yes)
			(effects
				(font
					(size 1 1)
					(thickness 0.15)
				)
				(justify mirror)
			)
		)
		(property "MPN" "TPD4E05U06QDQARQ1"
			(at 0 0 180)
			(unlocked yes)
			(layer "B.Fab")
			(hide yes)
			(effects
				(font
					(size 1 1)
					(thickness 0.15)
				)
				(justify mirror)
			)
		)
		(property "Author" "Antmicro"
			(at 0 0 180)
			(unlocked yes)
			(layer "B.Fab")
			(hide yes)
			(effects
				(font
					(size 1 1)
					(thickness 0.15)
				)
				(justify mirror)
			)
		)
		(property "License" "Apache-2.0"
			(at 0 0 180)
			(unlocked yes)
			(layer "B.Fab")
			(hide yes)
			(effects
				(font
					(size 1 1)
					(thickness 0.15)
				)
				(justify mirror)
			)
		)
		(sheetname "/HDMI + SD Card/")
		(sheetfile "hdmi-sd-card.kicad_sch")
		(attr smd)
		(fp_line
			(start 0.498 1.401)
			(end -0.5 1.401)
			(stroke
				(width 0.15)
				(type solid)
			)
			(layer "B.SilkS")
		)
		(fp_line
			(start 0.498 -1.398)
			(end -0.5 -1.398)
			(stroke
				(width 0.15)
				(type solid)
			)
			(layer "B.SilkS")
		)
		(fp_circle
			(center -0.68 1.27)
			(end -0.63 1.27)
			(stroke
				(width 0.15)
				(type solid)
			)
			(fill yes)
			(layer "B.SilkS")
		)
		(fp_rect
			(start -0.8 1.5)
			(end 0.8 -1.499)
			(stroke
				(width 0.05)
				(type solid)
			)
			(fill no)
			(layer "B.CrtYd")
		)
		(fp_line
			(start 0.498 1.25)
			(end 0.498 -1.249)
			(stroke
				(width 0.15)
				(type solid)
			)
			(layer "B.Fab")
		)
		(fp_line
			(start 0.498 1.25)
			(end -0.25 1.25)
			(stroke
				(width 0.15)
				(type solid)
			)
			(layer "B.Fab")
		)
		(fp_line
			(start -0.25 1.25)
			(end -0.5 1)
			(stroke
				(width 0.15)
				(type solid)
			)
			(layer "B.Fab")
		)
		(fp_line
			(start -0.5 1)
			(end -0.5 -1.249)
			(stroke
				(width 0.15)
				(type solid)
			)
			(layer "B.Fab")
		)
		(fp_line
			(start -0.5 -1.249)
			(end 0.498 -1.249)
			(stroke
				(width 0.15)
				(type solid)
			)
			(layer "B.Fab")
		)
		(fp_text user "${REFERENCE}"
			(at -0.802 -4.498 0)
			(layer "B.Fab")
			(effects
				(font
					(size 0.7 0.7)
					(thickness 0.15)
				)
				(justify left bottom mirror)
			)
		)
		(fp_text user "Author: Antmicro"
			(at -0.802 -5.7 0)
			(layer "B.Fab")
			(effects
				(font
					(size 0.7 0.7)
					(thickness 0.15)
				)
				(justify left bottom mirror)
			)
		)
		(fp_text user "License: Apache-2.0"
			(at -0.802 -6.9 0)
			(layer "B.Fab")
			(effects
				(font
					(size 0.7 0.7)
					(thickness 0.15)
				)
				(justify left bottom mirror)
			)
		)
		(pad "1" smd roundrect
			(at -0.387 1 270)
			(size 0.25 0.55)
			(layers "B.Cu" "B.Mask" "B.Paste")
			(roundrect_rratio 0.25)
			(net 480 "/HDMI + SD Card/HDMI_IN_5V.SDA")
			(pintype "passive")
		)
		(pad "2" smd roundrect
			(at -0.387 0.5 270)
			(size 0.25 0.55)
			(layers "B.Cu" "B.Mask" "B.Paste")
			(roundrect_rratio 0.25)
			(net 499 "/HDMI + SD Card/HDMI_IN_5V.SCL")
			(pintype "passive")
		)
		(pad "3" smd roundrect
			(at -0.387 0 270)
			(size 0.4 0.55)
			(layers "B.Cu" "B.Mask" "B.Paste")
			(roundrect_rratio 0.25)
			(net 1 "GND")
			(pintype "power_in")
		)
		(pad "4" smd roundrect
			(at -0.387 -0.498 270)
			(size 0.25 0.55)
			(layers "B.Cu" "B.Mask" "B.Paste")
			(roundrect_rratio 0.25)
			(net 297 "/HDMI + SD Card/HDMI_IN_5V")
			(pintype "passive")
		)
		(pad "5" smd roundrect
			(at -0.387 -0.998 270)
			(size 0.25 0.55)
			(layers "B.Cu" "B.Mask" "B.Paste")
			(roundrect_rratio 0.25)
			(net 604 "/HDMI + SD Card/HDMI_IN_HPD_CONN")
			(pintype "passive")
		)
		(pad "6" smd roundrect
			(at 0.385 -0.998 270)
			(size 0.25 0.55)
			(layers "B.Cu" "B.Mask" "B.Paste")
			(roundrect_rratio 0.25)
			(net 604 "/HDMI + SD Card/HDMI_IN_HPD_CONN")
			(pintype "passive")
		)
		(pad "7" smd roundrect
			(at 0.385 -0.498 270)
			(size 0.25 0.55)
			(layers "B.Cu" "B.Mask" "B.Paste")
			(roundrect_rratio 0.25)
			(net 297 "/HDMI + SD Card/HDMI_IN_5V")
			(pintype "passive")
		)
		(pad "8" smd roundrect
			(at 0.385 0 270)
			(size 0.4 0.55)
			(layers "B.Cu" "B.Mask" "B.Paste")
			(roundrect_rratio 0.25)
			(net 1 "GND")
			(pintype "passive")
		)
		(pad "9" smd roundrect
			(at 0.385 0.5 270)
			(size 0.25 0.55)
			(layers "B.Cu" "B.Mask" "B.Paste")
			(roundrect_rratio 0.25)
			(net 499 "/HDMI + SD Card/HDMI_IN_5V.SCL")
			(pintype "passive")
		)
		(pad "10" smd roundrect
			(at 0.385 1 270)
			(size 0.25 0.55)
			(layers "B.Cu" "B.Mask" "B.Paste")
			(roundrect_rratio 0.25)
			(net 480 "/HDMI + SD Card/HDMI_IN_5V.SDA")
			(pintype "passive")
		)
	)
	(footprint "antmicro-footprints:R_0402_1005Metric_EIA"
		(layer "B.Cu")
		(at 195.5 157 180)
		(descr "Resistor SMD 0402 (1005 Metric), square (rectangular) end terminal, IPC_7351 nominal, (Body size source: IPC-SM-782 page 76, https://www.pcb-3d.com/wordpress/wp-content/uploads/ipc-sm-782a_amendment_1_and_2.pdf)")
		(tags "resistor 0402")
		(property "Reference" "R21"
			(at 30.05 10.4 0)
			(layer "B.SilkS")
			(effects
				(font
					(size 0.7 0.7)
					(thickness 0.15)
				)
				(justify left bottom mirror)
			)
		)
		(property "Value" "R_100R_0402"
			(at 0 -1.169 0)
			(layer "B.Fab")
			(effects
				(font
					(size 0.7 0.7)
					(thickness 0.15)
				)
				(justify left bottom mirror)
			)
		)
		(property "Datasheet" "https://www.bourns.com/docs/product-datasheets/cr.pdf"
			(at 0 0 180)
			(layer "F.Fab")
			(hide yes)
			(effects
				(font
					(size 1.27 1.27)
					(thickness 0.15)
				)
			)
		)
		(property "Manufacturer" "Bourns"
			(at 0 0 180)
			(unlocked yes)
			(layer "B.Fab")
			(hide yes)
			(effects
				(font
					(size 1 1)
					(thickness 0.15)
				)
				(justify mirror)
			)
		)
		(property "MPN" "CR0402-FX-1000GLF"
			(at 0 0 180)
			(unlocked yes)
			(layer "B.Fab")
			(hide yes)
			(effects
				(font
					(size 1 1)
					(thickness 0.15)
				)
				(justify mirror)
			)
		)
		(property "Val" "100R"
			(at 0 0 180)
			(unlocked yes)
			(layer "B.Fab")
			(hide yes)
			(effects
				(font
					(size 1 1)
					(thickness 0.15)
				)
				(justify mirror)
			)
		)
		(property "License" "Apache-2.0"
			(at 0 0 180)
			(unlocked yes)
			(layer "B.Fab")
			(hide yes)
			(effects
				(font
					(size 1 1)
					(thickness 0.15)
				)
				(justify mirror)
			)
		)
		(property "Author" "Antmicro"
			(at 0 0 180)
			(unlocked yes)
			(layer "B.Fab")
			(hide yes)
			(effects
				(font
					(size 1 1)
					(thickness 0.15)
				)
				(justify mirror)
			)
		)
		(property "Tolerance" "1%"
			(at 0 0 180)
			(unlocked yes)
			(layer "B.Fab")
			(hide yes)
			(effects
				(font
					(size 1 1)
					(thickness 0.15)
				)
				(justify mirror)
			)
		)
		(sheetname "/FPGA Config/")
		(sheetfile "fpga-config.kicad_sch")
		(attr smd)
		(fp_rect
			(start -0.95 0.45)
			(end 0.95 -0.45)
			(stroke
				(width 0.05)
				(type default)
			)
			(fill no)
			(layer "B.CrtYd")
		)
		(fp_line
			(start 0.499 0.25)
			(end 0.499 -0.249)
			(stroke
				(width 0.15)
				(type solid)
			)
			(layer "B.Fab")
		)
		(fp_line
			(start 0.499 -0.249)
			(end -0.5 -0.249)
			(stroke
				(width 0.15)
				(type solid)
			)
			(layer "B.Fab")
		)
		(fp_line
			(start -0.5 0.25)
			(end 0.499 0.25)
			(stroke
				(width 0.15)
				(type solid)
			)
			(layer "B.Fab")
		)
		(fp_line
			(start -0.5 -0.249)
			(end -0.5 0.25)
			(stroke
				(width 0.15)
				(type solid)
			)
			(layer "B.Fab")
		)
		(fp_text user "${REFERENCE}"
			(at -0.95 -3.169 0)
			(layer "B.Fab")
			(effects
				(font
					(size 0.7 0.7)
					(thickness 0.15)
				)
				(justify left bottom mirror)
			)
		)
		(fp_text user "License: Apache-2.0"
			(at -0.95 -4.369 0)
			(layer "B.Fab")
			(effects
				(font
					(size 0.7 0.7)
					(thickness 0.15)
				)
				(justify left bottom mirror)
			)
		)
		(fp_text user "Author: Antmicro"
			(at -0.95 -5.569 0)
			(layer "B.Fab")
			(effects
				(font
					(size 0.7 0.7)
					(thickness 0.15)
				)
				(justify left bottom mirror)
			)
		)
		(pad "1" smd roundrect
			(at -0.5 0 90)
			(size 0.6 0.6)
			(layers "B.Cu" "B.Mask" "B.Paste")
			(roundrect_rratio 0.25)
			(net 797 "+1V8")
			(pintype "passive")
		)
		(pad "2" smd roundrect
			(at 0.499 0 180)
			(size 0.6 0.6)
			(layers "B.Cu" "B.Mask" "B.Paste")
			(roundrect_rratio 0.25)
			(net 40 "/FPGA Config/PUDC_B")
			(pintype "passive")
		)
	)
	(footprint "antmicro-footprints:C_0402_1005Metric"
		(layer "B.Cu")
		(at 252.5 104.325 90)
		(descr "Capacitor SMD 0402")
		(tags "capacitor SMD 0402")
		(property "Reference" "C317"
			(at -1.25 -0.425 90)
			(layer "B.SilkS")
			(effects
				(font
					(size 0.7 0.7)
					(thickness 0.15)
				)
				(justify left top mirror)
			)
		)
		(property "Value" "C_100n_0402"
			(at -1.022927 -2.155213 90)
			(layer "B.Fab")
			(effects
				(font
					(size 0.7 0.7)
					(thickness 0.15)
				)
				(justify right bottom mirror)
			)
		)
		(property "Datasheet" "https://www.murata.com/products/productdetail?partno=GRM155R61H104KE14%23"
			(at 0 0 90)
			(layer "B.Fab")
			(hide yes)
			(effects
				(font
					(size 1.27 1.27)
					(thickness 0.15)
				)
				(justify mirror)
			)
		)
		(property "MPN" "GRM155R61H104KE14D"
			(at 0 0 90)
			(unlocked yes)
			(layer "B.Fab")
			(hide yes)
			(effects
				(font
					(size 1 1)
					(thickness 0.15)
				)
				(justify mirror)
			)
		)
		(property "Manufacturer" "Murata"
			(at 0 0 90)
			(unlocked yes)
			(layer "B.Fab")
			(hide yes)
			(effects
				(font
					(size 1 1)
					(thickness 0.15)
				)
				(justify mirror)
			)
		)
		(property "License" "Apache-2.0"
			(at 0 0 90)
			(unlocked yes)
			(layer "B.Fab")
			(hide yes)
			(effects
				(font
					(size 1 1)
					(thickness 0.15)
				)
				(justify mirror)
			)
		)
		(property "Author" "Antmicro"
			(at 0 0 90)
			(unlocked yes)
			(layer "B.Fab")
			(hide yes)
			(effects
				(font
					(size 1 1)
					(thickness 0.15)
				)
				(justify mirror)
			)
		)
		(property "Val" "100n"
			(at 0 0 90)
			(unlocked yes)
			(layer "B.Fab")
			(hide yes)
			(effects
				(font
					(size 1 1)
					(thickness 0.15)
				)
				(justify mirror)
			)
		)
		(property "Voltage" "50V"
			(at 0 0 90)
			(unlocked yes)
			(layer "B.Fab")
			(hide yes)
			(effects
				(font
					(size 1 1)
					(thickness 0.15)
				)
				(justify mirror)
			)
		)
		(property "Dielectric" "X5R"
			(at 0 0 90)
			(unlocked yes)
			(layer "B.Fab")
			(hide yes)
			(effects
				(font
					(size 1 1)
					(thickness 0.15)
				)
				(justify mirror)
			)
		)
		(sheetname "/DDR5 RDIMM/")
		(sheetfile "ddr5-rdimm.kicad_sch")
		(attr smd)
		(fp_rect
			(start -0.925 0.47)
			(end 0.925 -0.47)
			(stroke
				(width 0.05)
				(type default)
			)
			(fill no)
			(layer "B.CrtYd")
		)
		(fp_line
			(start 0.504 -0.248)
			(end -0.494 -0.248)
			(stroke
				(width 0.15)
				(type solid)
			)
			(layer "B.Fab")
		)
		(fp_line
			(start -0.494 -0.248)
			(end -0.494 0.25)
			(stroke
				(width 0.15)
				(type solid)
			)
			(layer "B.Fab")
		)
		(fp_line
			(start 0.504 0.25)
			(end 0.504 -0.248)
			(stroke
				(width 0.15)
				(type solid)
			)
			(layer "B.Fab")
		)
		(fp_line
			(start -0.494 0.25)
			(end 0.504 0.25)
			(stroke
				(width 0.15)
				(type solid)
			)
			(layer "B.Fab")
		)
		(fp_text user "License: Apache-2.0"
			(at -0.939 -5.799 270)
			(layer "B.Fab")
			(effects
				(font
					(size 0.7 0.7)
					(thickness 0.15)
				)
				(justify left bottom mirror)
			)
		)
		(fp_text user "${REFERENCE}"
			(at -0.939 -4.599 270)
			(layer "B.Fab")
			(effects
				(font
					(size 0.7 0.7)
					(thickness 0.15)
				)
				(justify left bottom mirror)
			)
		)
		(fp_text user "Author: Antmicro"
			(at -0.939 -3.399 270)
			(layer "B.Fab")
			(effects
				(font
					(size 0.7 0.7)
					(thickness 0.15)
				)
				(justify left bottom mirror)
			)
		)
		(pad "1" smd roundrect
			(at -0.48 0 90)
			(size 0.59 0.64)
			(layers "B.Cu" "B.Mask" "B.Paste")
			(roundrect_rratio 0.25)
			(net 1 "GND")
			(pintype "passive")
		)
		(pad "2" smd roundrect
			(at 0.48 0 90)
			(size 0.59 0.64)
			(layers "B.Cu" "B.Mask" "B.Paste")
			(roundrect_rratio 0.25)
			(net 803 "/DDR5 RDIMM/VIN_MGMT")
			(pintype "passive")
		)
	)
	(footprint "antmicro-footprints:R_0402_1005Metric_EIA"
		(layer "B.Cu")
		(at 194 156.499 90)
		(descr "Resistor SMD 0402 (1005 Metric), square (rectangular) end terminal, IPC_7351 nominal, (Body size source: IPC-SM-782 page 76, https://www.pcb-3d.com/wordpress/wp-content/uploads/ipc-sm-782a_amendment_1_and_2.pdf)")
		(tags "resistor 0402")
		(property "Reference" "R22"
			(at 9.724 -30.65 90)
			(layer "B.SilkS")
			(effects
				(font
					(size 0.7 0.7)
					(thickness 0.15)
				)
				(justify right bottom mirror)
			)
		)
		(property "Value" "R_100R_0402"
			(at 0 -1.169 90)
			(layer "B.Fab")
			(effects
				(font
					(size 0.7 0.7)
					(thickness 0.15)
				)
				(justify right bottom mirror)
			)
		)
		(property "Datasheet" "https://www.bourns.com/docs/product-datasheets/cr.pdf"
			(at 0 0 90)
			(layer "F.Fab")
			(hide yes)
			(effects
				(font
					(size 1.27 1.27)
					(thickness 0.15)
				)
			)
		)
		(property "Manufacturer" "Bourns"
			(at 0 0 90)
			(unlocked yes)
			(layer "B.Fab")
			(hide yes)
			(effects
				(font
					(size 1 1)
					(thickness 0.15)
				)
				(justify mirror)
			)
		)
		(property "MPN" "CR0402-FX-1000GLF"
			(at 0 0 90)
			(unlocked yes)
			(layer "B.Fab")
			(hide yes)
			(effects
				(font
					(size 1 1)
					(thickness 0.15)
				)
				(justify mirror)
			)
		)
		(property "Val" "100R"
			(at 0 0 90)
			(unlocked yes)
			(layer "B.Fab")
			(hide yes)
			(effects
				(font
					(size 1 1)
					(thickness 0.15)
				)
				(justify mirror)
			)
		)
		(property "License" "Apache-2.0"
			(at 0 0 90)
			(unlocked yes)
			(layer "B.Fab")
			(hide yes)
			(effects
				(font
					(size 1 1)
					(thickness 0.15)
				)
				(justify mirror)
			)
		)
		(property "Author" "Antmicro"
			(at 0 0 90)
			(unlocked yes)
			(layer "B.Fab")
			(hide yes)
			(effects
				(font
					(size 1 1)
					(thickness 0.15)
				)
				(justify mirror)
			)
		)
		(property "Tolerance" "1%"
			(at 0 0 90)
			(unlocked yes)
			(layer "B.Fab")
			(hide yes)
			(effects
				(font
					(size 1 1)
					(thickness 0.15)
				)
				(justify mirror)
			)
		)
		(sheetname "/FPGA Config/")
		(sheetfile "fpga-config.kicad_sch")
		(attr smd exclude_from_bom dnp)
		(fp_rect
			(start -0.95 0.45)
			(end 0.95 -0.45)
			(stroke
				(width 0.05)
				(type default)
			)
			(fill no)
			(layer "B.CrtYd")
		)
		(fp_line
			(start 0.499 -0.249)
			(end -0.5 -0.249)
			(stroke
				(width 0.15)
				(type solid)
			)
			(layer "B.Fab")
		)
		(fp_line
			(start -0.5 -0.249)
			(end -0.5 0.25)
			(stroke
				(width 0.15)
				(type solid)
			)
			(layer "B.Fab")
		)
		(fp_line
			(start 0.499 0.25)
			(end 0.499 -0.249)
			(stroke
				(width 0.15)
				(type solid)
			)
			(layer "B.Fab")
		)
		(fp_line
			(start -0.5 0.25)
			(end 0.499 0.25)
			(stroke
				(width 0.15)
				(type solid)
			)
			(layer "B.Fab")
		)
		(fp_text user "Author: Antmicro"
			(at -0.95 -5.569 270)
			(layer "B.Fab")
			(effects
				(font
					(size 0.7 0.7)
					(thickness 0.15)
				)
				(justify left bottom mirror)
			)
		)
		(fp_text user "License: Apache-2.0"
			(at -0.95 -4.369 270)
			(layer "B.Fab")
			(effects
				(font
					(size 0.7 0.7)
					(thickness 0.15)
				)
				(justify left bottom mirror)
			)
		)
		(fp_text user "${REFERENCE}"
			(at -0.95 -3.169 270)
			(layer "B.Fab")
			(effects
				(font
					(size 0.7 0.7)
					(thickness 0.15)
				)
				(justify left bottom mirror)
			)
		)
		(pad "1" smd roundrect
			(at -0.5 0)
			(size 0.6 0.6)
			(layers "B.Cu" "B.Mask" "B.Paste")
			(roundrect_rratio 0.25)
			(net 40 "/FPGA Config/PUDC_B")
			(pintype "passive")
		)
		(pad "2" smd roundrect
			(at 0.499 0 90)
			(size 0.6 0.6)
			(layers "B.Cu" "B.Mask" "B.Paste")
			(roundrect_rratio 0.25)
			(net 1 "GND")
			(pintype "passive")
		)
	)
	(footprint "antmicro-footprints:R_0402_1005Metric"
		(layer "B.Cu")
		(at 253.039499 140.3)
		(descr "Resistor SMD 0402")
		(tags "resistor SMD 0402")
		(property "Reference" "R187"
			(at -4.089499 0.4 0)
			(layer "B.SilkS")
			(effects
				(font
					(size 0.7 0.7)
					(thickness 0.15)
				)
				(justify right bottom mirror)
			)
		)
		(property "Value" "R_47k_0402"
			(at -1.011843 -1.772047 0)
			(layer "B.Fab")
			(effects
				(font
					(size 0.7 0.7)
					(thickness 0.15)
				)
				(justify right bottom mirror)
			)
		)
		(property "Datasheet" "https://www.bourns.com/docs/product-datasheets/cr.pdf"
			(at 0 0 0)
			(layer "F.Fab")
			(hide yes)
			(effects
				(font
					(size 1.27 1.27)
					(thickness 0.15)
				)
			)
		)
		(property "Manufacturer" "Bourns"
			(at 0 0 0)
			(unlocked yes)
			(layer "B.Fab")
			(hide yes)
			(effects
				(font
					(size 1 1)
					(thickness 0.15)
				)
				(justify mirror)
			)
		)
		(property "MPN" "CR0402-FX-4702GLF"
			(at 0 0 0)
			(unlocked yes)
			(layer "B.Fab")
			(hide yes)
			(effects
				(font
					(size 1 1)
					(thickness 0.15)
				)
				(justify mirror)
			)
		)
		(property "Val" "47k"
			(at 0 0 0)
			(unlocked yes)
			(layer "B.Fab")
			(hide yes)
			(effects
				(font
					(size 1 1)
					(thickness 0.15)
				)
				(justify mirror)
			)
		)
		(property "License" "Apache-2.0"
			(at 0 0 0)
			(unlocked yes)
			(layer "B.Fab")
			(hide yes)
			(effects
				(font
					(size 1 1)
					(thickness 0.15)
				)
				(justify mirror)
			)
		)
		(property "Author" "Antmicro"
			(at 0 0 0)
			(unlocked yes)
			(layer "B.Fab")
			(hide yes)
			(effects
				(font
					(size 1 1)
					(thickness 0.15)
				)
				(justify mirror)
			)
		)
		(property "Tolerance" "1%"
			(at 0 0 0)
			(unlocked yes)
			(layer "B.Fab")
			(hide yes)
			(effects
				(font
					(size 1 1)
					(thickness 0.15)
				)
				(justify mirror)
			)
		)
		(sheetname "/Supply/")
		(sheetfile "supply.kicad_sch")
		(attr smd)
		(fp_rect
			(start -0.925 0.47)
			(end 0.925 -0.47)
			(stroke
				(width 0.05)
				(type default)
			)
			(fill no)
			(layer "B.CrtYd")
		)
		(fp_rect
			(start -0.5 0.25)
			(end 0.5 -0.25)
			(stroke
				(width 0.15)
				(type solid)
			)
			(fill no)
			(layer "B.Fab")
		)
		(fp_text user "License: Apache-2.0"
			(at -0.95 -5.169 180)
			(layer "B.Fab")
			(effects
				(font
					(size 0.7 0.7)
					(thickness 0.15)
				)
				(justify left bottom mirror)
			)
		)
		(fp_text user "${REFERENCE}"
			(at -0.95 -3.168 180)
			(layer "B.Fab")
			(effects
				(font
					(size 0.7 0.7)
					(thickness 0.15)
				)
				(justify left bottom mirror)
			)
		)
		(fp_text user "Author: Antmicro"
			(at -0.95 -4.169 180)
			(layer "B.Fab")
			(effects
				(font
					(size 0.7 0.7)
					(thickness 0.15)
				)
				(justify left bottom mirror)
			)
		)
		(pad "1" smd roundrect
			(at -0.48 0)
			(size 0.59 0.64)
			(layers "B.Cu" "B.Mask" "B.Paste")
			(roundrect_rratio 0.25)
			(net 169 "/Supply/EN2")
			(pintype "passive")
		)
		(pad "2" smd roundrect
			(at 0.48 0)
			(size 0.59 0.64)
			(layers "B.Cu" "B.Mask" "B.Paste")
			(roundrect_rratio 0.25)
			(net 38 "+3V3_AON")
			(pintype "passive")
		)
	)
	(footprint "antmicro-footprints:R_0402_1005Metric"
		(layer "B.Cu")
		(at 195.5 136.8 90)
		(descr "Resistor SMD 0402")
		(tags "resistor SMD 0402")
		(property "Reference" "R258"
			(at 2.3 0 270)
			(layer "B.SilkS")
			(effects
				(font
					(size 0.7 0.7)
					(thickness 0.15)
				)
				(justify mirror)
			)
		)
		(property "Value" "R_0R_0402"
			(at -1.011843 -1.772047 270)
			(layer "B.Fab")
			(effects
				(font
					(size 0.7 0.7)
					(thickness 0.15)
				)
				(justify left bottom mirror)
			)
		)
		(property "Datasheet" "https://industrial.panasonic.com/cdbs/www-data/pdf/RDA0000/AOA0000C301.pdf"
			(at 0 0 270)
			(layer "B.Fab")
			(hide yes)
			(effects
				(font
					(size 1.27 1.27)
					(thickness 0.15)
				)
				(justify mirror)
			)
		)
		(property "MPN" "ERJ2GE0R00X"
			(at 0 0 90)
			(unlocked yes)
			(layer "B.Fab")
			(hide yes)
			(effects
				(font
					(size 1 1)
					(thickness 0.15)
				)
				(justify mirror)
			)
		)
		(property "Manufacturer" "Panasonic"
			(at 0 0 90)
			(unlocked yes)
			(layer "B.Fab")
			(hide yes)
			(effects
				(font
					(size 1 1)
					(thickness 0.15)
				)
				(justify mirror)
			)
		)
		(property "License" "Apache-2.0"
			(at 0 0 90)
			(unlocked yes)
			(layer "B.Fab")
			(hide yes)
			(effects
				(font
					(size 1 1)
					(thickness 0.15)
				)
				(justify mirror)
			)
		)
		(property "Author" "Antmicro"
			(at 0 0 90)
			(unlocked yes)
			(layer "B.Fab")
			(hide yes)
			(effects
				(font
					(size 1 1)
					(thickness 0.15)
				)
				(justify mirror)
			)
		)
		(property "Val" "0R"
			(at 0 0 90)
			(unlocked yes)
			(layer "B.Fab")
			(hide yes)
			(effects
				(font
					(size 1 1)
					(thickness 0.15)
				)
				(justify mirror)
			)
		)
		(property "Tolerance" "~"
			(at 0 0 90)
			(unlocked yes)
			(layer "B.Fab")
			(hide yes)
			(effects
				(font
					(size 1 1)
					(thickness 0.15)
				)
				(justify mirror)
			)
		)
		(property "Current" "1A"
			(at 0 0 90)
			(unlocked yes)
			(layer "B.Fab")
			(hide yes)
			(effects
				(font
					(size 1 1)
					(thickness 0.15)
				)
				(justify mirror)
			)
		)
		(sheetname "/FPGA banks HP/")
		(sheetfile "fpga-hp-banks.kicad_sch")
		(attr smd)
		(fp_rect
			(start -0.925 0.47)
			(end 0.925 -0.47)
			(stroke
				(width 0.05)
				(type default)
			)
			(fill no)
			(layer "B.CrtYd")
		)
		(fp_rect
			(start -0.5 0.25)
			(end 0.5 -0.25)
			(stroke
				(width 0.15)
				(type solid)
			)
			(fill no)
			(layer "B.Fab")
		)
		(fp_text user "${REFERENCE}"
			(at -0.95 -3.168 270)
			(layer "B.Fab")
			(effects
				(font
					(size 0.7 0.7)
					(thickness 0.15)
				)
				(justify left bottom mirror)
			)
		)
		(fp_text user "Author: Antmicro"
			(at -0.95 -4.169 270)
			(layer "B.Fab")
			(effects
				(font
					(size 0.7 0.7)
					(thickness 0.15)
				)
				(justify left bottom mirror)
			)
		)
		(fp_text user "License: Apache-2.0"
			(at -0.95 -5.169 270)
			(layer "B.Fab")
			(effects
				(font
					(size 0.7 0.7)
					(thickness 0.15)
				)
				(justify left bottom mirror)
			)
		)
		(pad "1" smd roundrect
			(at -0.48 0 90)
			(size 0.59 0.64)
			(layers "B.Cu" "B.Mask" "B.Paste")
			(roundrect_rratio 0.25)
			(net 536 "/FPGA banks HP/VREF_65")
			(pintype "passive")
		)
		(pad "2" smd roundrect
			(at 0.48 0 90)
			(size 0.59 0.64)
			(layers "B.Cu" "B.Mask" "B.Paste")
			(roundrect_rratio 0.25)
			(net 826 "/FPGA banks HP/VREF")
			(pintype "passive")
		)
	)
	(footprint "antmicro-footprints:C_0402_1005Metric"
		(layer "B.Cu")
		(at 148.074499 160.437 90)
		(descr "Capacitor SMD 0402")
		(tags "capacitor SMD 0402")
		(property "Reference" "C237"
			(at 1.433 0.515501 90)
			(layer "B.SilkS")
			(effects
				(font
					(size 0.7 0.7)
					(thickness 0.15)
				)
				(justify right bottom mirror)
			)
		)
		(property "Value" "C_100n_0402"
			(at -1.022927 -2.155213 90)
			(layer "B.Fab")
			(effects
				(font
					(size 0.7 0.7)
					(thickness 0.15)
				)
				(justify right bottom mirror)
			)
		)
		(property "Datasheet" "https://www.murata.com/products/productdetail?partno=GRM155R61H104KE14%23"
			(at 0 0 90)
			(layer "F.Fab")
			(hide yes)
			(effects
				(font
					(size 1.27 1.27)
					(thickness 0.15)
				)
			)
		)
		(property "MPN" "GRM155R61H104KE14D"
			(at 0 0 90)
			(unlocked yes)
			(layer "B.Fab")
			(hide yes)
			(effects
				(font
					(size 1 1)
					(thickness 0.15)
				)
				(justify mirror)
			)
		)
		(property "Manufacturer" "Murata"
			(at 0 0 90)
			(unlocked yes)
			(layer "B.Fab")
			(hide yes)
			(effects
				(font
					(size 1 1)
					(thickness 0.15)
				)
				(justify mirror)
			)
		)
		(property "License" "Apache-2.0"
			(at 0 0 90)
			(unlocked yes)
			(layer "B.Fab")
			(hide yes)
			(effects
				(font
					(size 1 1)
					(thickness 0.15)
				)
				(justify mirror)
			)
		)
		(property "Author" "Antmicro"
			(at 0 0 90)
			(unlocked yes)
			(layer "B.Fab")
			(hide yes)
			(effects
				(font
					(size 1 1)
					(thickness 0.15)
				)
				(justify mirror)
			)
		)
		(property "Val" "100n"
			(at 0 0 90)
			(unlocked yes)
			(layer "B.Fab")
			(hide yes)
			(effects
				(font
					(size 1 1)
					(thickness 0.15)
				)
				(justify mirror)
			)
		)
		(property "Voltage" "50V"
			(at 0 0 90)
			(unlocked yes)
			(layer "B.Fab")
			(hide yes)
			(effects
				(font
					(size 1 1)
					(thickness 0.15)
				)
				(justify mirror)
			)
		)
		(property "Dielectric" "X5R"
			(at 0 0 90)
			(unlocked yes)
			(layer "B.Fab")
			(hide yes)
			(effects
				(font
					(size 1 1)
					(thickness 0.15)
				)
				(justify mirror)
			)
		)
		(sheetname "/Debug FTDI + VNA/")
		(sheetfile "debug-ftdi.kicad_sch")
		(attr smd)
		(fp_rect
			(start -0.925 0.47)
			(end 0.925 -0.47)
			(stroke
				(width 0.05)
				(type default)
			)
			(fill no)
			(layer "B.CrtYd")
		)
		(fp_line
			(start 0.504 -0.248)
			(end -0.494 -0.248)
			(stroke
				(width 0.15)
				(type solid)
			)
			(layer "B.Fab")
		)
		(fp_line
			(start -0.494 -0.248)
			(end -0.494 0.25)
			(stroke
				(width 0.15)
				(type solid)
			)
			(layer "B.Fab")
		)
		(fp_line
			(start 0.504 0.25)
			(end 0.504 -0.248)
			(stroke
				(width 0.15)
				(type solid)
			)
			(layer "B.Fab")
		)
		(fp_line
			(start -0.494 0.25)
			(end 0.504 0.25)
			(stroke
				(width 0.15)
				(type solid)
			)
			(layer "B.Fab")
		)
		(fp_text user "${REFERENCE}"
			(at -0.939 -4.599 270)
			(layer "B.Fab")
			(effects
				(font
					(size 0.7 0.7)
					(thickness 0.15)
				)
				(justify left bottom mirror)
			)
		)
		(fp_text user "Author: Antmicro"
			(at -0.939 -3.399 270)
			(layer "B.Fab")
			(effects
				(font
					(size 0.7 0.7)
					(thickness 0.15)
				)
				(justify left bottom mirror)
			)
		)
		(fp_text user "License: Apache-2.0"
			(at -0.939 -5.799 270)
			(layer "B.Fab")
			(effects
				(font
					(size 0.7 0.7)
					(thickness 0.15)
				)
				(justify left bottom mirror)
			)
		)
		(pad "1" smd roundrect
			(at -0.48 0 90)
			(size 0.59 0.64)
			(layers "B.Cu" "B.Mask" "B.Paste")
			(roundrect_rratio 0.25)
			(net 1 "GND")
			(pintype "passive")
		)
		(pad "2" smd roundrect
			(at 0.48 0 90)
			(size 0.59 0.64)
			(layers "B.Cu" "B.Mask" "B.Paste")
			(roundrect_rratio 0.25)
			(net 6 "/Debug FTDI + VNA/FTDI_3V3")
			(pintype "passive")
		)
	)
	(footprint "antmicro-footprints:C_0402_1005Metric_EIA"
		(layer "B.Cu")
		(at 200.5 144 180)
		(descr "Capacitor SMD 0402 (1005 Metric), square (rectangular) end terminal, IPC_7351 nominal, (Body size source: IPC-SM-782 page 76, https://www.pcb-3d.com/wordpress/wp-content/uploads/ipc-sm-782a_amendment_1_and_2.pdf)")
		(tags "capacitor 0402")
		(property "Reference" "C37"
			(at -3.275 -0.45 0)
			(layer "B.SilkS")
			(effects
				(font
					(size 0.7 0.7)
					(thickness 0.15)
				)
				(justify left bottom mirror)
			)
		)
		(property "Value" "C_10u_10V_0402"
			(at 0 -1.169 0)
			(layer "B.Fab")
			(effects
				(font
					(size 0.7 0.7)
					(thickness 0.15)
				)
				(justify left bottom mirror)
			)
		)
		(property "Datasheet" "https://www.murata.com/products/productdetail?partno=GRM155R61A106ME11%23"
			(at 0 0 180)
			(layer "F.Fab")
			(hide yes)
			(effects
				(font
					(size 1.27 1.27)
					(thickness 0.15)
				)
			)
		)
		(property "MPN" "GRM155R61A106ME11D"
			(at 0 0 180)
			(unlocked yes)
			(layer "B.Fab")
			(hide yes)
			(effects
				(font
					(size 1 1)
					(thickness 0.15)
				)
				(justify mirror)
			)
		)
		(property "Manufacturer" "Murata"
			(at 0 0 180)
			(unlocked yes)
			(layer "B.Fab")
			(hide yes)
			(effects
				(font
					(size 1 1)
					(thickness 0.15)
				)
				(justify mirror)
			)
		)
		(property "License" "Apache-2.0"
			(at 0 0 180)
			(unlocked yes)
			(layer "B.Fab")
			(hide yes)
			(effects
				(font
					(size 1 1)
					(thickness 0.15)
				)
				(justify mirror)
			)
		)
		(property "Author" "Antmicro"
			(at 0 0 180)
			(unlocked yes)
			(layer "B.Fab")
			(hide yes)
			(effects
				(font
					(size 1 1)
					(thickness 0.15)
				)
				(justify mirror)
			)
		)
		(property "Val" "10u"
			(at 0 0 180)
			(unlocked yes)
			(layer "B.Fab")
			(hide yes)
			(effects
				(font
					(size 1 1)
					(thickness 0.15)
				)
				(justify mirror)
			)
		)
		(property "Voltage" "10V"
			(at 0 0 180)
			(unlocked yes)
			(layer "B.Fab")
			(hide yes)
			(effects
				(font
					(size 1 1)
					(thickness 0.15)
				)
				(justify mirror)
			)
		)
		(property "Dielectric" "X5R"
			(at 0 0 180)
			(unlocked yes)
			(layer "B.Fab")
			(hide yes)
			(effects
				(font
					(size 1 1)
					(thickness 0.15)
				)
				(justify mirror)
			)
		)
		(sheetname "/FPGA power/")
		(sheetfile "fpga-power.kicad_sch")
		(attr smd)
		(fp_rect
			(start -0.95 0.45)
			(end 0.95 -0.45)
			(stroke
				(width 0.05)
				(type default)
			)
			(fill no)
			(layer "B.CrtYd")
		)
		(fp_line
			(start 0.498 0.25)
			(end 0.498 -0.248)
			(stroke
				(width 0.15)
				(type solid)
			)
			(layer "B.Fab")
		)
		(fp_line
			(start 0.498 -0.248)
			(end -0.5 -0.248)
			(stroke
				(width 0.15)
				(type solid)
			)
			(layer "B.Fab")
		)
		(fp_line
			(start -0.5 0.25)
			(end 0.498 0.25)
			(stroke
				(width 0.15)
				(type solid)
			)
			(layer "B.Fab")
		)
		(fp_line
			(start -0.5 -0.248)
			(end -0.5 0.25)
			(stroke
				(width 0.15)
				(type solid)
			)
			(layer "B.Fab")
		)
		(fp_text user "License: Apache-2.0"
			(at -0.9656 -4.369 0)
			(layer "B.Fab")
			(effects
				(font
					(size 0.7 0.7)
					(thickness 0.15)
				)
				(justify left bottom mirror)
			)
		)
		(fp_text user "${REFERENCE}"
			(at -0.9656 -3.169 0)
			(layer "B.Fab")
			(effects
				(font
					(size 0.7 0.7)
					(thickness 0.15)
				)
				(justify left bottom mirror)
			)
		)
		(fp_text user "Author: Antmicro"
			(at -0.9656 -5.569 0)
			(layer "B.Fab")
			(effects
				(font
					(size 0.7 0.7)
					(thickness 0.15)
				)
				(justify left bottom mirror)
			)
		)
		(pad "1" smd roundrect
			(at -0.5 0 90)
			(size 0.6 0.6)
			(layers "B.Cu" "B.Mask" "B.Paste")
			(roundrect_rratio 0.25)
			(net 1 "GND")
			(pintype "passive")
		)
		(pad "2" smd roundrect
			(at 0.498 0 180)
			(size 0.6 0.6)
			(layers "B.Cu" "B.Mask" "B.Paste")
			(roundrect_rratio 0.25)
			(net 687 "VDDQ")
			(pintype "passive")
		)
	)
	(footprint "antmicro-footprints:R_0402_1005Metric"
		(layer "B.Cu")
		(at 168.1 155.55)
		(descr "Resistor SMD 0402")
		(tags "resistor SMD 0402")
		(property "Reference" "R2"
			(at 0.9 0.4 0)
			(layer "B.SilkS")
			(effects
				(font
					(size 0.7 0.7)
					(thickness 0.15)
				)
				(justify right bottom mirror)
			)
		)
		(property "Value" "R_10k_0402"
			(at -1.011843 -1.772047 0)
			(layer "B.Fab")
			(effects
				(font
					(size 0.7 0.7)
					(thickness 0.15)
				)
				(justify right bottom mirror)
			)
		)
		(property "Datasheet" "https://www.bourns.com/docs/product-datasheets/cr.pdf"
			(at 0 0 0)
			(layer "F.Fab")
			(hide yes)
			(effects
				(font
					(size 1.27 1.27)
					(thickness 0.15)
				)
			)
		)
		(property "Manufacturer" "Bourns"
			(at 0 0 0)
			(unlocked yes)
			(layer "B.Fab")
			(hide yes)
			(effects
				(font
					(size 1 1)
					(thickness 0.15)
				)
				(justify mirror)
			)
		)
		(property "MPN" "CR0402-FX-1002GLF"
			(at 0 0 0)
			(unlocked yes)
			(layer "B.Fab")
			(hide yes)
			(effects
				(font
					(size 1 1)
					(thickness 0.15)
				)
				(justify mirror)
			)
		)
		(property "Val" "10k"
			(at 0 0 0)
			(unlocked yes)
			(layer "B.Fab")
			(hide yes)
			(effects
				(font
					(size 1 1)
					(thickness 0.15)
				)
				(justify mirror)
			)
		)
		(property "License" "Apache-2.0"
			(at 0 0 0)
			(unlocked yes)
			(layer "B.Fab")
			(hide yes)
			(effects
				(font
					(size 1 1)
					(thickness 0.15)
				)
				(justify mirror)
			)
		)
		(property "Author" "Antmicro"
			(at 0 0 0)
			(unlocked yes)
			(layer "B.Fab")
			(hide yes)
			(effects
				(font
					(size 1 1)
					(thickness 0.15)
				)
				(justify mirror)
			)
		)
		(property "Tolerance" "1%"
			(at 0 0 0)
			(unlocked yes)
			(layer "B.Fab")
			(hide yes)
			(effects
				(font
					(size 1 1)
					(thickness 0.15)
				)
				(justify mirror)
			)
		)
		(sheetname "/HyperRAM + QSPI Flash/")
		(sheetfile "hyperram-flash.kicad_sch")
		(attr smd)
		(fp_rect
			(start -0.925 0.47)
			(end 0.925 -0.47)
			(stroke
				(width 0.05)
				(type default)
			)
			(fill no)
			(layer "B.CrtYd")
		)
		(fp_rect
			(start -0.5 0.25)
			(end 0.5 -0.25)
			(stroke
				(width 0.15)
				(type solid)
			)
			(fill no)
			(layer "B.Fab")
		)
		(fp_text user "Author: Antmicro"
			(at -0.95 -4.169 180)
			(layer "B.Fab")
			(effects
				(font
					(size 0.7 0.7)
					(thickness 0.15)
				)
				(justify left bottom mirror)
			)
		)
		(fp_text user "License: Apache-2.0"
			(at -0.95 -5.169 180)
			(layer "B.Fab")
			(effects
				(font
					(size 0.7 0.7)
					(thickness 0.15)
				)
				(justify left bottom mirror)
			)
		)
		(fp_text user "${REFERENCE}"
			(at -0.95 -3.168 180)
			(layer "B.Fab")
			(effects
				(font
					(size 0.7 0.7)
					(thickness 0.15)
				)
				(justify left bottom mirror)
			)
		)
		(pad "1" smd roundrect
			(at -0.48 0)
			(size 0.59 0.64)
			(layers "B.Cu" "B.Mask" "B.Paste")
			(roundrect_rratio 0.25)
			(net 797 "+1V8")
			(pintype "passive")
		)
		(pad "2" smd roundrect
			(at 0.48 0)
			(size 0.59 0.64)
			(layers "B.Cu" "B.Mask" "B.Paste")
			(roundrect_rratio 0.25)
			(net 618 "/FPGA banks HP/HyperRAM.~{CS}")
			(pintype "passive")
		)
	)
	(footprint "antmicro-footprints:C_0402_1005Metric"
		(layer "B.Cu")
		(at 204.02 108.3 180)
		(descr "Capacitor SMD 0402")
		(tags "capacitor SMD 0402")
		(property "Reference" "C8"
			(at -2.52 -0.46 0)
			(layer "B.SilkS")
			(effects
				(font
					(size 0.7 0.7)
					(thickness 0.15)
				)
				(justify left bottom mirror)
			)
		)
		(property "Value" "C_100n_0402"
			(at -1.022927 -2.155213 0)
			(layer "B.Fab")
			(effects
				(font
					(size 0.7 0.7)
					(thickness 0.15)
				)
				(justify left bottom mirror)
			)
		)
		(property "Datasheet" "https://www.murata.com/products/productdetail?partno=GRM155R61H104KE14%23"
			(at 0 0 180)
			(layer "F.Fab")
			(hide yes)
			(effects
				(font
					(size 1.27 1.27)
					(thickness 0.15)
				)
			)
		)
		(property "MPN" "GRM155R61H104KE14D"
			(at 0 0 180)
			(unlocked yes)
			(layer "B.Fab")
			(hide yes)
			(effects
				(font
					(size 1 1)
					(thickness 0.15)
				)
				(justify mirror)
			)
		)
		(property "Manufacturer" "Murata"
			(at 0 0 180)
			(unlocked yes)
			(layer "B.Fab")
			(hide yes)
			(effects
				(font
					(size 1 1)
					(thickness 0.15)
				)
				(justify mirror)
			)
		)
		(property "License" "Apache-2.0"
			(at 0 0 180)
			(unlocked yes)
			(layer "B.Fab")
			(hide yes)
			(effects
				(font
					(size 1 1)
					(thickness 0.15)
				)
				(justify mirror)
			)
		)
		(property "Author" "Antmicro"
			(at 0 0 180)
			(unlocked yes)
			(layer "B.Fab")
			(hide yes)
			(effects
				(font
					(size 1 1)
					(thickness 0.15)
				)
				(justify mirror)
			)
		)
		(property "Val" "100n"
			(at 0 0 180)
			(unlocked yes)
			(layer "B.Fab")
			(hide yes)
			(effects
				(font
					(size 1 1)
					(thickness 0.15)
				)
				(justify mirror)
			)
		)
		(property "Voltage" "50V"
			(at 0 0 180)
			(unlocked yes)
			(layer "B.Fab")
			(hide yes)
			(effects
				(font
					(size 1 1)
					(thickness 0.15)
				)
				(justify mirror)
			)
		)
		(property "Dielectric" "X5R"
			(at 0 0 180)
			(unlocked yes)
			(layer "B.Fab")
			(hide yes)
			(effects
				(font
					(size 1 1)
					(thickness 0.15)
				)
				(justify mirror)
			)
		)
		(sheetname "/DDR5 RDIMM/")
		(sheetfile "ddr5-rdimm.kicad_sch")
		(attr smd)
		(fp_rect
			(start -0.925 0.47)
			(end 0.925 -0.47)
			(stroke
				(width 0.05)
				(type default)
			)
			(fill no)
			(layer "B.CrtYd")
		)
		(fp_line
			(start 0.504 0.25)
			(end 0.504 -0.248)
			(stroke
				(width 0.15)
				(type solid)
			)
			(layer "B.Fab")
		)
		(fp_line
			(start 0.504 -0.248)
			(end -0.494 -0.248)
			(stroke
				(width 0.15)
				(type solid)
			)
			(layer "B.Fab")
		)
		(fp_line
			(start -0.494 0.25)
			(end 0.504 0.25)
			(stroke
				(width 0.15)
				(type solid)
			)
			(layer "B.Fab")
		)
		(fp_line
			(start -0.494 -0.248)
			(end -0.494 0.25)
			(stroke
				(width 0.15)
				(type solid)
			)
			(layer "B.Fab")
		)
		(fp_text user "License: Apache-2.0"
			(at -0.939 -5.799 0)
			(layer "B.Fab")
			(effects
				(font
					(size 0.7 0.7)
					(thickness 0.15)
				)
				(justify left bottom mirror)
			)
		)
		(fp_text user "Author: Antmicro"
			(at -0.939 -3.399 0)
			(layer "B.Fab")
			(effects
				(font
					(size 0.7 0.7)
					(thickness 0.15)
				)
				(justify left bottom mirror)
			)
		)
		(fp_text user "${REFERENCE}"
			(at -0.939 -4.599 0)
			(layer "B.Fab")
			(effects
				(font
					(size 0.7 0.7)
					(thickness 0.15)
				)
				(justify left bottom mirror)
			)
		)
		(pad "1" smd roundrect
			(at -0.48 0 180)
			(size 0.59 0.64)
			(layers "B.Cu" "B.Mask" "B.Paste")
			(roundrect_rratio 0.25)
			(net 1 "GND")
			(pintype "passive")
		)
		(pad "2" smd roundrect
			(at 0.48 0 180)
			(size 0.59 0.64)
			(layers "B.Cu" "B.Mask" "B.Paste")
			(roundrect_rratio 0.25)
			(net 687 "VDDQ")
			(pintype "passive")
		)
	)
	(footprint "antmicro-footprints:R_0402_1005Metric_EIA"
		(layer "B.Cu")
		(at 200.5 154 180)
		(descr "Resistor SMD 0402 (1005 Metric), square (rectangular) end terminal, IPC_7351 nominal, (Body size source: IPC-SM-782 page 76, https://www.pcb-3d.com/wordpress/wp-content/uploads/ipc-sm-782a_amendment_1_and_2.pdf)")
		(tags "resistor 0402")
		(property "Reference" "R14"
			(at -1.1 0.7 0)
			(layer "B.SilkS")
			(effects
				(font
					(size 0.7 0.7)
					(thickness 0.15)
				)
				(justify left bottom mirror)
			)
		)
		(property "Value" "R_10k_0402"
			(at 0 -1.169 0)
			(layer "B.Fab")
			(effects
				(font
					(size 0.7 0.7)
					(thickness 0.15)
				)
				(justify left bottom mirror)
			)
		)
		(property "Datasheet" "https://www.bourns.com/docs/product-datasheets/cr.pdf"
			(at 0 0 180)
			(layer "F.Fab")
			(hide yes)
			(effects
				(font
					(size 1.27 1.27)
					(thickness 0.15)
				)
			)
		)
		(property "MPN" "CR0402-FX-1002GLF"
			(at 0 0 180)
			(unlocked yes)
			(layer "B.Fab")
			(hide yes)
			(effects
				(font
					(size 1 1)
					(thickness 0.15)
				)
				(justify mirror)
			)
		)
		(property "Manufacturer" "Bourns"
			(at 0 0 180)
			(unlocked yes)
			(layer "B.Fab")
			(hide yes)
			(effects
				(font
					(size 1 1)
					(thickness 0.15)
				)
				(justify mirror)
			)
		)
		(property "License" "Apache-2.0"
			(at 0 0 180)
			(unlocked yes)
			(layer "B.Fab")
			(hide yes)
			(effects
				(font
					(size 1 1)
					(thickness 0.15)
				)
				(justify mirror)
			)
		)
		(property "Author" "Antmicro"
			(at 0 0 180)
			(unlocked yes)
			(layer "B.Fab")
			(hide yes)
			(effects
				(font
					(size 1 1)
					(thickness 0.15)
				)
				(justify mirror)
			)
		)
		(property "Val" "10k"
			(at 0 0 180)
			(unlocked yes)
			(layer "B.Fab")
			(hide yes)
			(effects
				(font
					(size 1 1)
					(thickness 0.15)
				)
				(justify mirror)
			)
		)
		(property "Tolerance" "1%"
			(at 0 0 180)
			(unlocked yes)
			(layer "B.Fab")
			(hide yes)
			(effects
				(font
					(size 1 1)
					(thickness 0.15)
				)
				(justify mirror)
			)
		)
		(sheetname "/FPGA Config/")
		(sheetfile "fpga-config.kicad_sch")
		(attr smd)
		(fp_rect
			(start -0.95 0.45)
			(end 0.95 -0.45)
			(stroke
				(width 0.05)
				(type default)
			)
			(fill no)
			(layer "B.CrtYd")
		)
		(fp_line
			(start 0.499 0.25)
			(end 0.499 -0.249)
			(stroke
				(width 0.15)
				(type solid)
			)
			(layer "B.Fab")
		)
		(fp_line
			(start 0.499 -0.249)
			(end -0.5 -0.249)
			(stroke
				(width 0.15)
				(type solid)
			)
			(layer "B.Fab")
		)
		(fp_line
			(start -0.5 0.25)
			(end 0.499 0.25)
			(stroke
				(width 0.15)
				(type solid)
			)
			(layer "B.Fab")
		)
		(fp_line
			(start -0.5 -0.249)
			(end -0.5 0.25)
			(stroke
				(width 0.15)
				(type solid)
			)
			(layer "B.Fab")
		)
		(fp_text user "${REFERENCE}"
			(at -0.95 -3.169 0)
			(layer "B.Fab")
			(effects
				(font
					(size 0.7 0.7)
					(thickness 0.15)
				)
				(justify left bottom mirror)
			)
		)
		(fp_text user "Author: Antmicro"
			(at -0.95 -5.569 0)
			(layer "B.Fab")
			(effects
				(font
					(size 0.7 0.7)
					(thickness 0.15)
				)
				(justify left bottom mirror)
			)
		)
		(fp_text user "License: Apache-2.0"
			(at -0.95 -4.369 0)
			(layer "B.Fab")
			(effects
				(font
					(size 0.7 0.7)
					(thickness 0.15)
				)
				(justify left bottom mirror)
			)
		)
		(pad "1" smd roundrect
			(at -0.5 0 90)
			(size 0.6 0.6)
			(layers "B.Cu" "B.Mask" "B.Paste")
			(roundrect_rratio 0.25)
			(net 773 "MODE2")
			(pintype "passive")
		)
		(pad "2" smd roundrect
			(at 0.499 0 180)
			(size 0.6 0.6)
			(layers "B.Cu" "B.Mask" "B.Paste")
			(roundrect_rratio 0.25)
			(net 797 "+1V8")
			(pintype "passive")
		)
	)
	(footprint "antmicro-footprints:R_0402_1005Metric"
		(layer "B.Cu")
		(at 244.86 117.11)
		(descr "Resistor SMD 0402")
		(tags "resistor SMD 0402")
		(property "Reference" "R249"
			(at -1.4 -0.57 0)
			(layer "B.SilkS")
			(effects
				(font
					(size 0.7 0.7)
					(thickness 0.15)
				)
				(justify right bottom mirror)
			)
		)
		(property "Value" "R_47k_0402"
			(at -1.011843 -1.772047 0)
			(layer "B.Fab")
			(effects
				(font
					(size 0.7 0.7)
					(thickness 0.15)
				)
				(justify right bottom mirror)
			)
		)
		(property "Datasheet" "https://www.bourns.com/docs/product-datasheets/cr.pdf"
			(at 0 0 0)
			(layer "F.Fab")
			(hide yes)
			(effects
				(font
					(size 1.27 1.27)
					(thickness 0.15)
				)
			)
		)
		(property "MPN" "CR0402-FX-4702GLF"
			(at 0 0 0)
			(unlocked yes)
			(layer "B.Fab")
			(hide yes)
			(effects
				(font
					(size 1 1)
					(thickness 0.15)
				)
				(justify mirror)
			)
		)
		(property "Manufacturer" "Bourns"
			(at 0 0 0)
			(unlocked yes)
			(layer "B.Fab")
			(hide yes)
			(effects
				(font
					(size 1 1)
					(thickness 0.15)
				)
				(justify mirror)
			)
		)
		(property "License" "Apache-2.0"
			(at 0 0 0)
			(unlocked yes)
			(layer "B.Fab")
			(hide yes)
			(effects
				(font
					(size 1 1)
					(thickness 0.15)
				)
				(justify mirror)
			)
		)
		(property "Author" "Antmicro"
			(at 0 0 0)
			(unlocked yes)
			(layer "B.Fab")
			(hide yes)
			(effects
				(font
					(size 1 1)
					(thickness 0.15)
				)
				(justify mirror)
			)
		)
		(property "Val" "47k"
			(at 0 0 0)
			(unlocked yes)
			(layer "B.Fab")
			(hide yes)
			(effects
				(font
					(size 1 1)
					(thickness 0.15)
				)
				(justify mirror)
			)
		)
		(property "Tolerance" "1%"
			(at 0 0 0)
			(unlocked yes)
			(layer "B.Fab")
			(hide yes)
			(effects
				(font
					(size 1 1)
					(thickness 0.15)
				)
				(justify mirror)
			)
		)
		(sheetname "/Supply/")
		(sheetfile "supply.kicad_sch")
		(attr smd)
		(fp_rect
			(start -0.925 0.47)
			(end 0.925 -0.47)
			(stroke
				(width 0.05)
				(type default)
			)
			(fill no)
			(layer "B.CrtYd")
		)
		(fp_rect
			(start -0.5 0.25)
			(end 0.5 -0.25)
			(stroke
				(width 0.15)
				(type solid)
			)
			(fill no)
			(layer "B.Fab")
		)
		(fp_text user "License: Apache-2.0"
			(at -0.95 -5.169 180)
			(layer "B.Fab")
			(effects
				(font
					(size 0.7 0.7)
					(thickness 0.15)
				)
				(justify left bottom mirror)
			)
		)
		(fp_text user "Author: Antmicro"
			(at -0.95 -4.169 180)
			(layer "B.Fab")
			(effects
				(font
					(size 0.7 0.7)
					(thickness 0.15)
				)
				(justify left bottom mirror)
			)
		)
		(fp_text user "${REFERENCE}"
			(at -0.95 -3.168 180)
			(layer "B.Fab")
			(effects
				(font
					(size 0.7 0.7)
					(thickness 0.15)
				)
				(justify left bottom mirror)
			)
		)
		(pad "1" smd roundrect
			(at -0.48 0)
			(size 0.59 0.64)
			(layers "B.Cu" "B.Mask" "B.Paste")
			(roundrect_rratio 0.25)
			(net 813 "Net-(Q28-D)")
			(pintype "passive")
		)
		(pad "2" smd roundrect
			(at 0.48 0)
			(size 0.59 0.64)
			(layers "B.Cu" "B.Mask" "B.Paste")
			(roundrect_rratio 0.25)
			(net 35 "VDC")
			(pintype "passive")
		)
	)
	(footprint "antmicro-footprints:R_0402_1005Metric"
		(layer "B.Cu")
		(at 260.549499 176.104 90)
		(descr "Resistor SMD 0402")
		(tags "resistor SMD 0402")
		(property "Reference" "R207"
			(at -3.746 0.450501 90)
			(layer "B.SilkS")
			(effects
				(font
					(size 0.7 0.7)
					(thickness 0.15)
				)
				(justify right bottom mirror)
			)
		)
		(property "Value" "R_0R_0402"
			(at -1.011843 -1.772047 90)
			(layer "B.Fab")
			(effects
				(font
					(size 0.7 0.7)
					(thickness 0.15)
				)
				(justify right bottom mirror)
			)
		)
		(property "Datasheet" "https://industrial.panasonic.com/cdbs/www-data/pdf/RDA0000/AOA0000C301.pdf"
			(at 0 0 90)
			(layer "F.Fab")
			(hide yes)
			(effects
				(font
					(size 1.27 1.27)
					(thickness 0.15)
				)
			)
		)
		(property "Manufacturer" "Panasonic"
			(at 0 0 90)
			(unlocked yes)
			(layer "B.Fab")
			(hide yes)
			(effects
				(font
					(size 1 1)
					(thickness 0.15)
				)
				(justify mirror)
			)
		)
		(property "MPN" "ERJ2GE0R00X"
			(at 0 0 90)
			(unlocked yes)
			(layer "B.Fab")
			(hide yes)
			(effects
				(font
					(size 1 1)
					(thickness 0.15)
				)
				(justify mirror)
			)
		)
		(property "Val" "0R"
			(at 0 0 90)
			(unlocked yes)
			(layer "B.Fab")
			(hide yes)
			(effects
				(font
					(size 1 1)
					(thickness 0.15)
				)
				(justify mirror)
			)
		)
		(property "License" "Apache-2.0"
			(at 0 0 90)
			(unlocked yes)
			(layer "B.Fab")
			(hide yes)
			(effects
				(font
					(size 1 1)
					(thickness 0.15)
				)
				(justify mirror)
			)
		)
		(property "Author" "Antmicro"
			(at 0 0 90)
			(unlocked yes)
			(layer "B.Fab")
			(hide yes)
			(effects
				(font
					(size 1 1)
					(thickness 0.15)
				)
				(justify mirror)
			)
		)
		(property "Tolerance" "~"
			(at 0 0 90)
			(unlocked yes)
			(layer "B.Fab")
			(hide yes)
			(effects
				(font
					(size 1 1)
					(thickness 0.15)
				)
				(justify mirror)
			)
		)
		(property "Current" "1A"
			(at 0 0 90)
			(unlocked yes)
			(layer "B.Fab")
			(hide yes)
			(effects
				(font
					(size 1 1)
					(thickness 0.15)
				)
				(justify mirror)
			)
		)
		(sheetname "/Supply/DC-DC AUX, MGT/")
		(sheetfile "dc-dc-aux-mgt.kicad_sch")
		(attr smd exclude_from_bom dnp)
		(fp_rect
			(start -0.925 0.47)
			(end 0.925 -0.47)
			(stroke
				(width 0.05)
				(type default)
			)
			(fill no)
			(layer "B.CrtYd")
		)
		(fp_rect
			(start -0.5 0.25)
			(end 0.5 -0.25)
			(stroke
				(width 0.15)
				(type solid)
			)
			(fill no)
			(layer "B.Fab")
		)
		(fp_text user "License: Apache-2.0"
			(at -0.95 -5.169 270)
			(layer "B.Fab")
			(effects
				(font
					(size 0.7 0.7)
					(thickness 0.15)
				)
				(justify left bottom mirror)
			)
		)
		(fp_text user "${REFERENCE}"
			(at -0.95 -3.168 270)
			(layer "B.Fab")
			(effects
				(font
					(size 0.7 0.7)
					(thickness 0.15)
				)
				(justify left bottom mirror)
			)
		)
		(fp_text user "Author: Antmicro"
			(at -0.95 -4.169 270)
			(layer "B.Fab")
			(effects
				(font
					(size 0.7 0.7)
					(thickness 0.15)
				)
				(justify left bottom mirror)
			)
		)
		(pad "1" smd roundrect
			(at -0.48 0 90)
			(size 0.59 0.64)
			(layers "B.Cu" "B.Mask" "B.Paste")
			(roundrect_rratio 0.25)
			(net 1 "GND")
			(pintype "passive")
		)
		(pad "2" smd roundrect
			(at 0.48 0 90)
			(size 0.59 0.64)
			(layers "B.Cu" "B.Mask" "B.Paste")
			(roundrect_rratio 0.25)
			(net 717 "/Supply/DC-DC AUX, MGT/FB4")
			(pintype "passive")
		)
	)
	(footprint "antmicro-footprints:R_0402_1005Metric"
		(layer "B.Cu")
		(at 203.25 138.1045 180)
		(descr "Resistor SMD 0402")
		(tags "resistor SMD 0402")
		(property "Reference" "R255"
			(at 2.35 0 0)
			(layer "B.SilkS")
			(effects
				(font
					(size 0.7 0.7)
					(thickness 0.15)
				)
				(justify mirror)
			)
		)
		(property "Value" "R_0R_0402"
			(at -1.011843 -1.772047 0)
			(layer "B.Fab")
			(effects
				(font
					(size 0.7 0.7)
					(thickness 0.15)
				)
				(justify left bottom mirror)
			)
		)
		(property "Datasheet" "https://industrial.panasonic.com/cdbs/www-data/pdf/RDA0000/AOA0000C301.pdf"
			(at 0 0 0)
			(layer "B.Fab")
			(hide yes)
			(effects
				(font
					(size 1.27 1.27)
					(thickness 0.15)
				)
				(justify mirror)
			)
		)
		(property "MPN" "ERJ2GE0R00X"
			(at 0 0 0)
			(unlocked yes)
			(layer "B.Fab")
			(hide yes)
			(effects
				(font
					(size 1 1)
					(thickness 0.15)
				)
				(justify mirror)
			)
		)
		(property "Manufacturer" "Panasonic"
			(at 0 0 0)
			(unlocked yes)
			(layer "B.Fab")
			(hide yes)
			(effects
				(font
					(size 1 1)
					(thickness 0.15)
				)
				(justify mirror)
			)
		)
		(property "License" "Apache-2.0"
			(at 0 0 0)
			(unlocked yes)
			(layer "B.Fab")
			(hide yes)
			(effects
				(font
					(size 1 1)
					(thickness 0.15)
				)
				(justify mirror)
			)
		)
		(property "Author" "Antmicro"
			(at 0 0 0)
			(unlocked yes)
			(layer "B.Fab")
			(hide yes)
			(effects
				(font
					(size 1 1)
					(thickness 0.15)
				)
				(justify mirror)
			)
		)
		(property "Val" "0R"
			(at 0 0 0)
			(unlocked yes)
			(layer "B.Fab")
			(hide yes)
			(effects
				(font
					(size 1 1)
					(thickness 0.15)
				)
				(justify mirror)
			)
		)
		(property "Tolerance" "~"
			(at 0 0 0)
			(unlocked yes)
			(layer "B.Fab")
			(hide yes)
			(effects
				(font
					(size 1 1)
					(thickness 0.15)
				)
				(justify mirror)
			)
		)
		(property "Current" "1A"
			(at 0 0 0)
			(unlocked yes)
			(layer "B.Fab")
			(hide yes)
			(effects
				(font
					(size 1 1)
					(thickness 0.15)
				)
				(justify mirror)
			)
		)
		(sheetname "/FPGA banks HP/")
		(sheetfile "fpga-hp-banks.kicad_sch")
		(attr smd)
		(fp_rect
			(start -0.925 0.47)
			(end 0.925 -0.47)
			(stroke
				(width 0.05)
				(type default)
			)
			(fill no)
			(layer "B.CrtYd")
		)
		(fp_rect
			(start -0.5 0.25)
			(end 0.5 -0.25)
			(stroke
				(width 0.15)
				(type solid)
			)
			(fill no)
			(layer "B.Fab")
		)
		(fp_text user "Author: Antmicro"
			(at -0.95 -4.169 0)
			(layer "B.Fab")
			(effects
				(font
					(size 0.7 0.7)
					(thickness 0.15)
				)
				(justify left bottom mirror)
			)
		)
		(fp_text user "${REFERENCE}"
			(at -0.95 -3.168 0)
			(layer "B.Fab")
			(effects
				(font
					(size 0.7 0.7)
					(thickness 0.15)
				)
				(justify left bottom mirror)
			)
		)
		(fp_text user "License: Apache-2.0"
			(at -0.95 -5.169 0)
			(layer "B.Fab")
			(effects
				(font
					(size 0.7 0.7)
					(thickness 0.15)
				)
				(justify left bottom mirror)
			)
		)
		(pad "1" smd roundrect
			(at -0.48 0 180)
			(size 0.59 0.64)
			(layers "B.Cu" "B.Mask" "B.Paste")
			(roundrect_rratio 0.25)
			(net 825 "DAC_VREF")
			(pintype "passive")
		)
		(pad "2" smd roundrect
			(at 0.48 0 180)
			(size 0.59 0.64)
			(layers "B.Cu" "B.Mask" "B.Paste")
			(roundrect_rratio 0.25)
			(net 826 "/FPGA banks HP/VREF")
			(pintype "passive")
		)
	)
	(footprint "antmicro-footprints:X2SON8_1.4x1x0.32mm_P0.35mm"
		(layer "B.Cu")
		(at 118.525 166.79 90)
		(property "Reference" "U44"
			(at -1.98 -1.11 0)
			(layer "B.SilkS")
			(effects
				(font
					(size 0.7 0.7)
					(thickness 0.15)
				)
				(justify right bottom mirror)
			)
		)
		(property "Value" "TXS0102DQER"
			(at 0 -1.929 90)
			(layer "B.Fab")
			(effects
				(font
					(size 0.7 0.7)
					(thickness 0.15)
				)
				(justify right bottom mirror)
			)
		)
		(property "Datasheet" "https://www.ti.com/lit/ds/symlink/txs0102.pdf?ts=1637914596981&ref_url=https%253A%252F%252Fwww.ti.com%252Fstore%252Fti%252Fen%252Fp%252Fproduct%252F%253Fp%253DTXS0102DCTR%2526keyMatch%253DTXS0102DCTR%2526tisearch%253Dsearch-everything%2526usecase%253DOPN"
			(at 0 0 90)
			(layer "F.Fab")
			(hide yes)
			(effects
				(font
					(size 1.27 1.27)
					(thickness 0.15)
				)
			)
		)
		(property "MPN" "TXS0102DQER"
			(at 0 0 90)
			(unlocked yes)
			(layer "B.Fab")
			(hide yes)
			(effects
				(font
					(size 1 1)
					(thickness 0.15)
				)
				(justify mirror)
			)
		)
		(property "Manufacturer" "Texas Instruments"
			(at 0 0 90)
			(unlocked yes)
			(layer "B.Fab")
			(hide yes)
			(effects
				(font
					(size 1 1)
					(thickness 0.15)
				)
				(justify mirror)
			)
		)
		(property "Author" "Antmicro"
			(at 0 0 90)
			(unlocked yes)
			(layer "B.Fab")
			(hide yes)
			(effects
				(font
					(size 1 1)
					(thickness 0.15)
				)
				(justify mirror)
			)
		)
		(property "License" "Apache-2.0"
			(at 0 0 90)
			(unlocked yes)
			(layer "B.Fab")
			(hide yes)
			(effects
				(font
					(size 1 1)
					(thickness 0.15)
				)
				(justify mirror)
			)
		)
		(sheetname "/HDMI + SD Card/")
		(sheetfile "hdmi-sd-card.kicad_sch")
		(attr smd)
		(fp_line
			(start 0.598 -0.801)
			(end 0.498 -0.801)
			(stroke
				(width 0.15)
				(type solid)
			)
			(layer "B.SilkS")
		)
		(fp_line
			(start -0.6 -0.801)
			(end -0.5 -0.801)
			(stroke
				(width 0.15)
				(type solid)
			)
			(layer "B.SilkS")
		)
		(fp_line
			(start 0.598 -0.7)
			(end 0.598 -0.801)
			(stroke
				(width 0.15)
				(type solid)
			)
			(layer "B.SilkS")
		)
		(fp_line
			(start -0.6 -0.7)
			(end -0.6 -0.801)
			(stroke
				(width 0.15)
				(type solid)
			)
			(layer "B.SilkS")
		)
		(fp_line
			(start 0.598 0.7)
			(end 0.598 0.801)
			(stroke
				(width 0.15)
				(type solid)
			)
			(layer "B.SilkS")
		)
		(fp_line
			(start 0.598 0.801)
			(end 0.498 0.801)
			(stroke
				(width 0.15)
				(type solid)
			)
			(layer "B.SilkS")
		)
		(fp_line
			(start -0.402 0.801)
			(end -0.6 0.801)
			(stroke
				(width 0.15)
				(type solid)
			)
			(layer "B.SilkS")
		)
		(fp_line
			(start -0.6 0.801)
			(end -0.6 0.7)
			(stroke
				(width 0.15)
				(type solid)
			)
			(layer "B.SilkS")
		)
		(fp_circle
			(center -0.81 0.77)
			(end -0.81 0.72)
			(stroke
				(width 0.15)
				(type solid)
			)
			(fill yes)
			(layer "B.SilkS")
		)
		(fp_rect
			(start 0.75 0.925)
			(end -0.75 -0.925)
			(stroke
				(width 0.05)
				(type solid)
			)
			(fill no)
			(layer "B.CrtYd")
		)
		(fp_line
			(start -0.5 -0.724)
			(end 0.498 -0.724)
			(stroke
				(width 0.15)
				(type solid)
			)
			(layer "B.Fab")
		)
		(fp_line
			(start 0.498 0.719)
			(end 0.498 -0.719)
			(stroke
				(width 0.15)
				(type solid)
			)
			(layer "B.Fab")
		)
		(fp_line
			(start -0.5 0.724)
			(end 0.498 0.724)
			(stroke
				(width 0.15)
				(type solid)
			)
			(layer "B.Fab")
		)
		(fp_line
			(start -0.5 0.729)
			(end -0.5 -0.719)
			(stroke
				(width 0.15)
				(type solid)
			)
			(layer "B.Fab")
		)
		(fp_text user "Author: Antmicro"
			(at -0.95 -5.129 270)
			(layer "B.Fab")
			(effects
				(font
					(size 0.7 0.7)
					(thickness 0.15)
				)
				(justify left bottom mirror)
			)
		)
		(fp_text user "${REFERENCE}"
			(at -0.95 -3.929 270)
			(layer "B.Fab")
			(effects
				(font
					(size 0.7 0.7)
					(thickness 0.15)
				)
				(justify left bottom mirror)
			)
		)
		(fp_text user "License: Apache-2.0"
			(at -0.95 -6.329 270)
			(layer "B.Fab")
			(effects
				(font
					(size 0.7 0.7)
					(thickness 0.15)
				)
				(justify left bottom mirror)
			)
		)
		(pad "1" smd rect
			(at -0.43 0.526 180)
			(size 0.17 0.5)
			(layers "B.Cu" "B.Mask" "B.Paste")
			(net 151 "+3V3")
			(pinfunction "VCCA")
			(pintype "power_in")
		)
		(pad "2" smd rect
			(at -0.43 0.175 180)
			(size 0.17 0.5)
			(layers "B.Cu" "B.Mask" "B.Paste")
			(net 555 "/FPGA banks HD/HDMI_IN_I2C.SDA")
			(pinfunction "A1")
			(pintype "bidirectional")
		)
		(pad "3" smd rect
			(at -0.43 -0.175 180)
			(size 0.17 0.5)
			(layers "B.Cu" "B.Mask" "B.Paste")
			(net 550 "/FPGA banks HD/HDMI_IN_I2C.SCL")
			(pinfunction "A2")
			(pintype "bidirectional")
		)
		(pad "4" smd rect
			(at -0.43 -0.526 180)
			(size 0.17 0.5)
			(layers "B.Cu" "B.Mask" "B.Paste")
			(net 1 "GND")
			(pinfunction "GND")
			(pintype "power_in")
		)
		(pad "5" smd rect
			(at 0.43 -0.526 180)
			(size 0.17 0.5)
			(layers "B.Cu" "B.Mask" "B.Paste")
			(net 151 "+3V3")
			(pinfunction "OE")
			(pintype "tri_state")
		)
		(pad "6" smd rect
			(at 0.43 -0.175 180)
			(size 0.17 0.5)
			(layers "B.Cu" "B.Mask" "B.Paste")
			(net 499 "/HDMI + SD Card/HDMI_IN_5V.SCL")
			(pinfunction "B2")
			(pintype "bidirectional")
		)
		(pad "7" smd rect
			(at 0.43 0.175 180)
			(size 0.17 0.5)
			(layers "B.Cu" "B.Mask" "B.Paste")
			(net 480 "/HDMI + SD Card/HDMI_IN_5V.SDA")
			(pinfunction "B1")
			(pintype "bidirectional")
		)
		(pad "8" smd rect
			(at 0.43 0.526 180)
			(size 0.17 0.5)
			(layers "B.Cu" "B.Mask" "B.Paste")
			(net 297 "/HDMI + SD Card/HDMI_IN_5V")
			(pinfunction "VCCB")
			(pintype "power_in")
		)
	)
	(footprint "antmicro-footprints:C_0402_1005Metric"
		(layer "B.Cu")
		(at 122.95 153.61 180)
		(descr "Capacitor SMD 0402")
		(tags "capacitor SMD 0402")
		(property "Reference" "C289"
			(at -5.23 -1.79 0)
			(layer "B.SilkS")
			(effects
				(font
					(size 0.7 0.7)
					(thickness 0.15)
				)
				(justify left bottom mirror)
			)
		)
		(property "Value" "C_100n_0402"
			(at -1.022927 -2.155213 0)
			(layer "B.Fab")
			(effects
				(font
					(size 0.7 0.7)
					(thickness 0.15)
				)
				(justify left bottom mirror)
			)
		)
		(property "Datasheet" "https://www.murata.com/products/productdetail?partno=GRM155R61H104KE14%23"
			(at 0 0 180)
			(layer "F.Fab")
			(hide yes)
			(effects
				(font
					(size 1.27 1.27)
					(thickness 0.15)
				)
			)
		)
		(property "Manufacturer" "Murata"
			(at 0 0 180)
			(unlocked yes)
			(layer "B.Fab")
			(hide yes)
			(effects
				(font
					(size 1 1)
					(thickness 0.15)
				)
				(justify mirror)
			)
		)
		(property "MPN" "GRM155R61H104KE14D"
			(at 0 0 180)
			(unlocked yes)
			(layer "B.Fab")
			(hide yes)
			(effects
				(font
					(size 1 1)
					(thickness 0.15)
				)
				(justify mirror)
			)
		)
		(property "Val" "100n"
			(at 0 0 180)
			(unlocked yes)
			(layer "B.Fab")
			(hide yes)
			(effects
				(font
					(size 1 1)
					(thickness 0.15)
				)
				(justify mirror)
			)
		)
		(property "License" "Apache-2.0"
			(at 0 0 180)
			(unlocked yes)
			(layer "B.Fab")
			(hide yes)
			(effects
				(font
					(size 1 1)
					(thickness 0.15)
				)
				(justify mirror)
			)
		)
		(property "Author" "Antmicro"
			(at 0 0 180)
			(unlocked yes)
			(layer "B.Fab")
			(hide yes)
			(effects
				(font
					(size 1 1)
					(thickness 0.15)
				)
				(justify mirror)
			)
		)
		(property "Voltage" "50V"
			(at 0 0 180)
			(unlocked yes)
			(layer "B.Fab")
			(hide yes)
			(effects
				(font
					(size 1 1)
					(thickness 0.15)
				)
				(justify mirror)
			)
		)
		(property "Dielectric" "X5R"
			(at 0 0 180)
			(unlocked yes)
			(layer "B.Fab")
			(hide yes)
			(effects
				(font
					(size 1 1)
					(thickness 0.15)
				)
				(justify mirror)
			)
		)
		(sheetname "/FPGA MGT Interface/")
		(sheetfile "fpga-mgt.kicad_sch")
		(attr smd)
		(fp_rect
			(start -0.925 0.47)
			(end 0.925 -0.47)
			(stroke
				(width 0.05)
				(type default)
			)
			(fill no)
			(layer "B.CrtYd")
		)
		(fp_line
			(start 0.504 0.25)
			(end 0.504 -0.248)
			(stroke
				(width 0.15)
				(type solid)
			)
			(layer "B.Fab")
		)
		(fp_line
			(start 0.504 -0.248)
			(end -0.494 -0.248)
			(stroke
				(width 0.15)
				(type solid)
			)
			(layer "B.Fab")
		)
		(fp_line
			(start -0.494 0.25)
			(end 0.504 0.25)
			(stroke
				(width 0.15)
				(type solid)
			)
			(layer "B.Fab")
		)
		(fp_line
			(start -0.494 -0.248)
			(end -0.494 0.25)
			(stroke
				(width 0.15)
				(type solid)
			)
			(layer "B.Fab")
		)
		(fp_text user "Author: Antmicro"
			(at -0.939 -3.399 0)
			(layer "B.Fab")
			(effects
				(font
					(size 0.7 0.7)
					(thickness 0.15)
				)
				(justify left bottom mirror)
			)
		)
		(fp_text user "${REFERENCE}"
			(at -0.939 -4.599 0)
			(layer "B.Fab")
			(effects
				(font
					(size 0.7 0.7)
					(thickness 0.15)
				)
				(justify left bottom mirror)
			)
		)
		(fp_text user "License: Apache-2.0"
			(at -0.939 -5.799 0)
			(layer "B.Fab")
			(effects
				(font
					(size 0.7 0.7)
					(thickness 0.15)
				)
				(justify left bottom mirror)
			)
		)
		(pad "1" smd roundrect
			(at -0.48 0 180)
			(size 0.59 0.64)
			(layers "B.Cu" "B.Mask" "B.Paste")
			(roundrect_rratio 0.25)
			(net 268 "/FPGA MGT Interface/HDMI_IN_CLK_C_P")
			(pintype "passive")
		)
		(pad "2" smd roundrect
			(at 0.48 0 180)
			(size 0.59 0.64)
			(layers "B.Cu" "B.Mask" "B.Paste")
			(roundrect_rratio 0.25)
			(net 269 "/FPGA MGT Interface/HDMI_IN.CLK_P")
			(pintype "passive")
		)
	)
	(footprint "antmicro-footprints:USON-10_2.5x1mm_P0.5mm"
		(layer "B.Cu")
		(at 107.804 157.119 180)
		(descr "USON-10 2.5x1mm_ Pitch 0.5mm")
		(tags "USON-10 2.5x1mm Pitch 0.5mm")
		(property "Reference" "U37"
			(at -2.046 -0.731 90)
			(layer "B.SilkS")
			(effects
				(font
					(size 0.7 0.7)
					(thickness 0.15)
				)
				(justify right bottom mirror)
			)
		)
		(property "Value" "TPD4E05U06QDQARQ1"
			(at 0.018 -2.499 0)
			(layer "B.Fab")
			(effects
				(font
					(size 0.7 0.7)
					(thickness 0.15)
				)
				(justify left bottom mirror)
			)
		)
		(property "Datasheet" "https://www.ti.com/lit/ds/symlink/tpd4e05u06-q1.pdf?HQS=dis-mous-null-mousermode-dsf-pf-null-wwe&ts=1663591265741&ref_url=https%253A%252F%252Fwww.mouser.com%252F"
			(at 0 0 180)
			(layer "F.Fab")
			(hide yes)
			(effects
				(font
					(size 1.27 1.27)
					(thickness 0.15)
				)
			)
		)
		(property "Manufacturer" "Texas Instruments"
			(at 0 0 180)
			(unlocked yes)
			(layer "B.Fab")
			(hide yes)
			(effects
				(font
					(size 1 1)
					(thickness 0.15)
				)
				(justify mirror)
			)
		)
		(property "MPN" "TPD4E05U06QDQARQ1"
			(at 0 0 180)
			(unlocked yes)
			(layer "B.Fab")
			(hide yes)
			(effects
				(font
					(size 1 1)
					(thickness 0.15)
				)
				(justify mirror)
			)
		)
		(property "Author" "Antmicro"
			(at 0 0 180)
			(unlocked yes)
			(layer "B.Fab")
			(hide yes)
			(effects
				(font
					(size 1 1)
					(thickness 0.15)
				)
				(justify mirror)
			)
		)
		(property "License" "Apache-2.0"
			(at 0 0 180)
			(unlocked yes)
			(layer "B.Fab")
			(hide yes)
			(effects
				(font
					(size 1 1)
					(thickness 0.15)
				)
				(justify mirror)
			)
		)
		(sheetname "/HDMI + SD Card/")
		(sheetfile "hdmi-sd-card.kicad_sch")
		(attr smd)
		(fp_line
			(start 0.498 1.401)
			(end -0.5 1.401)
			(stroke
				(width 0.15)
				(type solid)
			)
			(layer "B.SilkS")
		)
		(fp_line
			(start 0.498 -1.398)
			(end -0.5 -1.398)
			(stroke
				(width 0.15)
				(type solid)
			)
			(layer "B.SilkS")
		)
		(fp_circle
			(center -0.68 1.27)
			(end -0.63 1.27)
			(stroke
				(width 0.15)
				(type solid)
			)
			(fill yes)
			(layer "B.SilkS")
		)
		(fp_rect
			(start -0.8 1.5)
			(end 0.8 -1.499)
			(stroke
				(width 0.05)
				(type solid)
			)
			(fill no)
			(layer "B.CrtYd")
		)
		(fp_line
			(start 0.498 1.25)
			(end 0.498 -1.249)
			(stroke
				(width 0.15)
				(type solid)
			)
			(layer "B.Fab")
		)
		(fp_line
			(start 0.498 1.25)
			(end -0.25 1.25)
			(stroke
				(width 0.15)
				(type solid)
			)
			(layer "B.Fab")
		)
		(fp_line
			(start -0.25 1.25)
			(end -0.5 1)
			(stroke
				(width 0.15)
				(type solid)
			)
			(layer "B.Fab")
		)
		(fp_line
			(start -0.5 1)
			(end -0.5 -1.249)
			(stroke
				(width 0.15)
				(type solid)
			)
			(layer "B.Fab")
		)
		(fp_line
			(start -0.5 -1.249)
			(end 0.498 -1.249)
			(stroke
				(width 0.15)
				(type solid)
			)
			(layer "B.Fab")
		)
		(fp_text user "Author: Antmicro"
			(at -0.802 -5.7 0)
			(layer "B.Fab")
			(effects
				(font
					(size 0.7 0.7)
					(thickness 0.15)
				)
				(justify left bottom mirror)
			)
		)
		(fp_text user "License: Apache-2.0"
			(at -0.802 -6.9 0)
			(layer "B.Fab")
			(effects
				(font
					(size 0.7 0.7)
					(thickness 0.15)
				)
				(justify left bottom mirror)
			)
		)
		(fp_text user "${REFERENCE}"
			(at -0.802 -4.498 0)
			(layer "B.Fab")
			(effects
				(font
					(size 0.7 0.7)
					(thickness 0.15)
				)
				(justify left bottom mirror)
			)
		)
		(pad "1" smd roundrect
			(at -0.387 1 270)
			(size 0.25 0.55)
			(layers "B.Cu" "B.Mask" "B.Paste")
			(roundrect_rratio 0.25)
			(net 344 "/FPGA MGT Interface/HDMI_IN.D2_P")
			(pintype "passive")
		)
		(pad "2" smd roundrect
			(at -0.387 0.5 270)
			(size 0.25 0.55)
			(layers "B.Cu" "B.Mask" "B.Paste")
			(roundrect_rratio 0.25)
			(net 342 "/FPGA MGT Interface/HDMI_IN.D2_N")
			(pintype "passive")
		)
		(pad "3" smd roundrect
			(at -0.387 0 270)
			(size 0.4 0.55)
			(layers "B.Cu" "B.Mask" "B.Paste")
			(roundrect_rratio 0.25)
			(net 1 "GND")
			(pintype "power_in")
		)
		(pad "4" smd roundrect
			(at -0.387 -0.498 270)
			(size 0.25 0.55)
			(layers "B.Cu" "B.Mask" "B.Paste")
			(roundrect_rratio 0.25)
			(net 348 "/FPGA MGT Interface/HDMI_IN.D1_P")
			(pintype "passive")
		)
		(pad "5" smd roundrect
			(at -0.387 -0.998 270)
			(size 0.25 0.55)
			(layers "B.Cu" "B.Mask" "B.Paste")
			(roundrect_rratio 0.25)
			(net 346 "/FPGA MGT Interface/HDMI_IN.D1_N")
			(pintype "passive")
		)
		(pad "6" smd roundrect
			(at 0.385 -0.998 270)
			(size 0.25 0.55)
			(layers "B.Cu" "B.Mask" "B.Paste")
			(roundrect_rratio 0.25)
			(net 346 "/FPGA MGT Interface/HDMI_IN.D1_N")
			(pintype "passive")
		)
		(pad "7" smd roundrect
			(at 0.385 -0.498 270)
			(size 0.25 0.55)
			(layers "B.Cu" "B.Mask" "B.Paste")
			(roundrect_rratio 0.25)
			(net 348 "/FPGA MGT Interface/HDMI_IN.D1_P")
			(pintype "passive")
		)
		(pad "8" smd roundrect
			(at 0.385 0 270)
			(size 0.4 0.55)
			(layers "B.Cu" "B.Mask" "B.Paste")
			(roundrect_rratio 0.25)
			(net 1 "GND")
			(pintype "passive")
		)
		(pad "9" smd roundrect
			(at 0.385 0.5 270)
			(size 0.25 0.55)
			(layers "B.Cu" "B.Mask" "B.Paste")
			(roundrect_rratio 0.25)
			(net 342 "/FPGA MGT Interface/HDMI_IN.D2_N")
			(pintype "passive")
		)
		(pad "10" smd roundrect
			(at 0.385 1 270)
			(size 0.25 0.55)
			(layers "B.Cu" "B.Mask" "B.Paste")
			(roundrect_rratio 0.25)
			(net 344 "/FPGA MGT Interface/HDMI_IN.D2_P")
			(pintype "passive")
		)
	)
	(footprint "antmicro-footprints:C_0402_1005Metric"
		(layer "B.Cu")
		(at 221.9 179.775 90)
		(descr "Capacitor SMD 0402")
		(tags "capacitor SMD 0402")
		(property "Reference" "C264"
			(at -2.2 -0.725 90)
			(layer "B.SilkS")
			(effects
				(font
					(size 0.7 0.7)
					(thickness 0.15)
				)
				(justify right bottom mirror)
			)
		)
		(property "Value" "C_22p_0402"
			(at -1.022927 -2.155213 90)
			(layer "B.Fab")
			(effects
				(font
					(size 0.7 0.7)
					(thickness 0.15)
				)
				(justify right bottom mirror)
			)
		)
		(property "Datasheet" "https://www.yageo.com/en/Chart/Download/pdf/CC0402JRNPO9BN220"
			(at 0 0 90)
			(layer "F.Fab")
			(hide yes)
			(effects
				(font
					(size 1.27 1.27)
					(thickness 0.15)
				)
			)
		)
		(property "Description" "SMD Multilayer Ceramic Capacitor, 22 pF, 50 V, 0402 [1005 Metric], ± 5%, C0G / NP0, CC Series"
			(at 0 0 90)
			(layer "F.Fab")
			(hide yes)
			(effects
				(font
					(size 1.27 1.27)
					(thickness 0.15)
				)
			)
		)
		(property "MPN" "CC0402JRNPO9BN220"
			(at 0 0 90)
			(unlocked yes)
			(layer "B.Fab")
			(hide yes)
			(effects
				(font
					(size 1 1)
					(thickness 0.15)
				)
				(justify mirror)
			)
		)
		(property "Manufacturer" "YAGEO"
			(at 0 0 90)
			(unlocked yes)
			(layer "B.Fab")
			(hide yes)
			(effects
				(font
					(size 1 1)
					(thickness 0.15)
				)
				(justify mirror)
			)
		)
		(property "License" "Apache-2.0"
			(at 0 0 90)
			(unlocked yes)
			(layer "B.Fab")
			(hide yes)
			(effects
				(font
					(size 1 1)
					(thickness 0.15)
				)
				(justify mirror)
			)
		)
		(property "Author" "Antmicro"
			(at 0 0 90)
			(unlocked yes)
			(layer "B.Fab")
			(hide yes)
			(effects
				(font
					(size 1 1)
					(thickness 0.15)
				)
				(justify mirror)
			)
		)
		(property "Val" "22p"
			(at 0 0 90)
			(unlocked yes)
			(layer "B.Fab")
			(hide yes)
			(effects
				(font
					(size 1 1)
					(thickness 0.15)
				)
				(justify mirror)
			)
		)
		(property "Voltage" ""
			(at 0 0 90)
			(unlocked yes)
			(layer "B.Fab")
			(hide yes)
			(effects
				(font
					(size 1 1)
					(thickness 0.15)
				)
				(justify mirror)
			)
		)
		(property "Dielectric" ""
			(at 0 0 90)
			(unlocked yes)
			(layer "B.Fab")
			(hide yes)
			(effects
				(font
					(size 1 1)
					(thickness 0.15)
				)
				(justify mirror)
			)
		)
		(sheetname "/Supply/DC-DC VCCINT/")
		(sheetfile "dc-dc-vccint.kicad_sch")
		(attr smd)
		(fp_rect
			(start -0.925 0.47)
			(end 0.925 -0.47)
			(stroke
				(width 0.05)
				(type default)
			)
			(fill no)
			(layer "B.CrtYd")
		)
		(fp_line
			(start 0.504 -0.248)
			(end -0.494 -0.248)
			(stroke
				(width 0.15)
				(type solid)
			)
			(layer "B.Fab")
		)
		(fp_line
			(start -0.494 -0.248)
			(end -0.494 0.25)
			(stroke
				(width 0.15)
				(type solid)
			)
			(layer "B.Fab")
		)
		(fp_line
			(start 0.504 0.25)
			(end 0.504 -0.248)
			(stroke
				(width 0.15)
				(type solid)
			)
			(layer "B.Fab")
		)
		(fp_line
			(start -0.494 0.25)
			(end 0.504 0.25)
			(stroke
				(width 0.15)
				(type solid)
			)
			(layer "B.Fab")
		)
		(fp_text user "${REFERENCE}"
			(at -0.939 -4.599 270)
			(layer "B.Fab")
			(effects
				(font
					(size 0.7 0.7)
					(thickness 0.15)
				)
				(justify left bottom mirror)
			)
		)
		(fp_text user "Author: Antmicro"
			(at -0.939 -3.399 270)
			(layer "B.Fab")
			(effects
				(font
					(size 0.7 0.7)
					(thickness 0.15)
				)
				(justify left bottom mirror)
			)
		)
		(fp_text user "License: Apache-2.0"
			(at -0.939 -5.799 270)
			(layer "B.Fab")
			(effects
				(font
					(size 0.7 0.7)
					(thickness 0.15)
				)
				(justify left bottom mirror)
			)
		)
		(pad "1" smd roundrect
			(at -0.48 0 90)
			(size 0.59 0.64)
			(layers "B.Cu" "B.Mask" "B.Paste")
			(roundrect_rratio 0.25)
			(net 226 "/Supply/DC-DC VCCINT/V_{0SNS+}")
			(pintype "passive")
		)
		(pad "2" smd roundrect
			(at 0.48 0 90)
			(size 0.59 0.64)
			(layers "B.Cu" "B.Mask" "B.Paste")
			(roundrect_rratio 0.25)
			(net 756 "Net-(C264-Pad2)")
			(pintype "passive")
		)
	)
	(footprint "antmicro-footprints:C_0402_1005Metric"
		(layer "B.Cu")
		(at 172.65 193.299501 90)
		(descr "Capacitor SMD 0402")
		(tags "capacitor SMD 0402")
		(property "Reference" "C231"
			(at 0.994 0.403501 90)
			(layer "B.SilkS")
			(effects
				(font
					(size 0.7 0.7)
					(thickness 0.15)
				)
				(justify right bottom mirror)
			)
		)
		(property "Value" "C_100n_0402"
			(at -1.022927 -2.155213 90)
			(layer "B.Fab")
			(effects
				(font
					(size 0.7 0.7)
					(thickness 0.15)
				)
				(justify right bottom mirror)
			)
		)
		(property "Datasheet" "https://www.murata.com/products/productdetail?partno=GRM155R61H104KE14%23"
			(at 0 0 90)
			(layer "F.Fab")
			(hide yes)
			(effects
				(font
					(size 1.27 1.27)
					(thickness 0.15)
				)
			)
		)
		(property "Manufacturer" "Murata"
			(at 0 0 90)
			(unlocked yes)
			(layer "B.Fab")
			(hide yes)
			(effects
				(font
					(size 1 1)
					(thickness 0.15)
				)
				(justify mirror)
			)
		)
		(property "MPN" "GRM155R61H104KE14D"
			(at 0 0 90)
			(unlocked yes)
			(layer "B.Fab")
			(hide yes)
			(effects
				(font
					(size 1 1)
					(thickness 0.15)
				)
				(justify mirror)
			)
		)
		(property "Val" "100n"
			(at 0 0 90)
			(unlocked yes)
			(layer "B.Fab")
			(hide yes)
			(effects
				(font
					(size 1 1)
					(thickness 0.15)
				)
				(justify mirror)
			)
		)
		(property "License" "Apache-2.0"
			(at 0 0 90)
			(unlocked yes)
			(layer "B.Fab")
			(hide yes)
			(effects
				(font
					(size 1 1)
					(thickness 0.15)
				)
				(justify mirror)
			)
		)
		(property "Author" "Antmicro"
			(at 0 0 90)
			(unlocked yes)
			(layer "B.Fab")
			(hide yes)
			(effects
				(font
					(size 1 1)
					(thickness 0.15)
				)
				(justify mirror)
			)
		)
		(property "Voltage" "50V"
			(at 0 0 90)
			(unlocked yes)
			(layer "B.Fab")
			(hide yes)
			(effects
				(font
					(size 1 1)
					(thickness 0.15)
				)
				(justify mirror)
			)
		)
		(property "Dielectric" "X5R"
			(at 0 0 90)
			(unlocked yes)
			(layer "B.Fab")
			(hide yes)
			(effects
				(font
					(size 1 1)
					(thickness 0.15)
				)
				(justify mirror)
			)
		)
		(sheetname "/FPGA MGT Interface/")
		(sheetfile "fpga-mgt.kicad_sch")
		(attr smd)
		(fp_rect
			(start -0.925 0.47)
			(end 0.925 -0.47)
			(stroke
				(width 0.05)
				(type default)
			)
			(fill no)
			(layer "B.CrtYd")
		)
		(fp_line
			(start 0.504 -0.248)
			(end -0.494 -0.248)
			(stroke
				(width 0.15)
				(type solid)
			)
			(layer "B.Fab")
		)
		(fp_line
			(start -0.494 -0.248)
			(end -0.494 0.25)
			(stroke
				(width 0.15)
				(type solid)
			)
			(layer "B.Fab")
		)
		(fp_line
			(start 0.504 0.25)
			(end 0.504 -0.248)
			(stroke
				(width 0.15)
				(type solid)
			)
			(layer "B.Fab")
		)
		(fp_line
			(start -0.494 0.25)
			(end 0.504 0.25)
			(stroke
				(width 0.15)
				(type solid)
			)
			(layer "B.Fab")
		)
		(fp_text user "Author: Antmicro"
			(at -0.939 -3.399 270)
			(layer "B.Fab")
			(effects
				(font
					(size 0.7 0.7)
					(thickness 0.15)
				)
				(justify left bottom mirror)
			)
		)
		(fp_text user "License: Apache-2.0"
			(at -0.939 -5.799 270)
			(layer "B.Fab")
			(effects
				(font
					(size 0.7 0.7)
					(thickness 0.15)
				)
				(justify left bottom mirror)
			)
		)
		(fp_text user "${REFERENCE}"
			(at -0.939 -4.599 270)
			(layer "B.Fab")
			(effects
				(font
					(size 0.7 0.7)
					(thickness 0.15)
				)
				(justify left bottom mirror)
			)
		)
		(pad "1" smd roundrect
			(at -0.48 0 90)
			(size 0.59 0.64)
			(layers "B.Cu" "B.Mask" "B.Paste")
			(roundrect_rratio 0.25)
			(net 25 "/FPGA MGT Interface/PCIE.TXD2_N")
			(pintype "passive")
		)
		(pad "2" smd roundrect
			(at 0.48 0 90)
			(size 0.59 0.64)
			(layers "B.Cu" "B.Mask" "B.Paste")
			(roundrect_rratio 0.25)
			(net 26 "/FPGA MGT Interface/GTY_225_TX1_N")
			(pintype "passive")
		)
	)
	(footprint "antmicro-footprints:C_0603_1608Metric"
		(layer "B.Cu")
		(at 253.7 104.325 90)
		(descr "Capacitor SMD 0603")
		(tags "capacitor 0603")
		(property "Reference" "C319"
			(at -4.075 0.5 90)
			(layer "B.SilkS")
			(effects
				(font
					(size 0.7 0.7)
					(thickness 0.15)
				)
				(justify right bottom mirror)
			)
		)
		(property "Value" "C_10u_25V_0603"
			(at -1.42757 -1.770288 90)
			(layer "B.Fab")
			(effects
				(font
					(size 0.7 0.7)
					(thickness 0.15)
				)
				(justify right bottom mirror)
			)
		)
		(property "Datasheet" "https://product.tdk.com/en/search/capacitor/ceramic/mlcc/info?part_no=C1608X5R1E106M080AC"
			(at 0 0 90)
			(layer "B.Fab")
			(hide yes)
			(effects
				(font
					(size 1.27 1.27)
					(thickness 0.15)
				)
				(justify mirror)
			)
		)
		(property "MPN" "C1608X5R1E106M080AC"
			(at 0 0 90)
			(unlocked yes)
			(layer "B.Fab")
			(hide yes)
			(effects
				(font
					(size 1 1)
					(thickness 0.15)
				)
				(justify mirror)
			)
		)
		(property "Manufacturer" "TDK"
			(at 0 0 90)
			(unlocked yes)
			(layer "B.Fab")
			(hide yes)
			(effects
				(font
					(size 1 1)
					(thickness 0.15)
				)
				(justify mirror)
			)
		)
		(property "License" "Apache-2.0"
			(at 0 0 90)
			(unlocked yes)
			(layer "B.Fab")
			(hide yes)
			(effects
				(font
					(size 1 1)
					(thickness 0.15)
				)
				(justify mirror)
			)
		)
		(property "Author" "Antmicro"
			(at 0 0 90)
			(unlocked yes)
			(layer "B.Fab")
			(hide yes)
			(effects
				(font
					(size 1 1)
					(thickness 0.15)
				)
				(justify mirror)
			)
		)
		(property "Val" "10u"
			(at 0 0 90)
			(unlocked yes)
			(layer "B.Fab")
			(hide yes)
			(effects
				(font
					(size 1 1)
					(thickness 0.15)
				)
				(justify mirror)
			)
		)
		(property "Voltage" "25V"
			(at 0 0 90)
			(unlocked yes)
			(layer "B.Fab")
			(hide yes)
			(effects
				(font
					(size 1 1)
					(thickness 0.15)
				)
				(justify mirror)
			)
		)
		(property "Dielectric" ""
			(at 0 0 90)
			(unlocked yes)
			(layer "B.Fab")
			(hide yes)
			(effects
				(font
					(size 1 1)
					(thickness 0.15)
				)
				(justify mirror)
			)
		)
		(sheetname "/DDR5 RDIMM/")
		(sheetfile "ddr5-rdimm.kicad_sch")
		(attr smd)
		(fp_line
			(start -0.15 -0.4)
			(end 0.15 -0.4)
			(stroke
				(width 0.15)
				(type solid)
			)
			(layer "B.SilkS")
		)
		(fp_line
			(start -0.15 0.4)
			(end 0.15 0.4)
			(stroke
				(width 0.15)
				(type solid)
			)
			(layer "B.SilkS")
		)
		(fp_rect
			(start -1.25 0.65)
			(end 1.25 -0.65)
			(stroke
				(width 0.05)
				(type solid)
			)
			(fill no)
			(layer "B.CrtYd")
		)
		(fp_rect
			(start -0.8 0.4)
			(end 0.8 -0.4)
			(stroke
				(width 0.15)
				(type solid)
			)
			(fill no)
			(layer "B.Fab")
		)
		(fp_text user "Author: Antmicro"
			(at -1.682 -4.894 270)
			(layer "B.Fab")
			(effects
				(font
					(size 0.7 0.7)
					(thickness 0.15)
				)
				(justify left bottom mirror)
			)
		)
		(fp_text user "License: Apache-2.0"
			(at -1.682 -5.895 270)
			(layer "B.Fab")
			(effects
				(font
					(size 0.7 0.7)
					(thickness 0.15)
				)
				(justify left bottom mirror)
			)
		)
		(fp_text user "${REFERENCE}"
			(at -1.682 -3.895 270)
			(layer "B.Fab")
			(effects
				(font
					(size 0.7 0.7)
					(thickness 0.15)
				)
				(justify left bottom mirror)
			)
		)
		(pad "1" smd roundrect
			(at -0.7 0 90)
			(size 0.8 1)
			(layers "B.Cu" "B.Mask" "B.Paste")
			(roundrect_rratio 0.2)
			(net 1 "GND")
			(pintype "passive")
		)
		(pad "2" smd roundrect
			(at 0.7 0 90)
			(size 0.8 1)
			(layers "B.Cu" "B.Mask" "B.Paste")
			(roundrect_rratio 0.2)
			(net 803 "/DDR5 RDIMM/VIN_MGMT")
			(pintype "passive")
		)
	)
	(footprint "antmicro-footprints:C_0402_1005Metric_EIA"
		(layer "B.Cu")
		(at 196.502 159)
		(descr "Capacitor SMD 0402 (1005 Metric), square (rectangular) end terminal, IPC_7351 nominal, (Body size source: IPC-SM-782 page 76, https://www.pcb-3d.com/wordpress/wp-content/uploads/ipc-sm-782a_amendment_1_and_2.pdf)")
		(tags "capacitor 0402")
		(property "Reference" "C98"
			(at -31.927 -10.3 0)
			(layer "B.SilkS")
			(effects
				(font
					(size 0.7 0.7)
					(thickness 0.15)
				)
				(justify right bottom mirror)
			)
		)
		(property "Value" "C_100n_0402"
			(at 0 -1.169 0)
			(layer "B.Fab")
			(effects
				(font
					(size 0.7 0.7)
					(thickness 0.15)
				)
				(justify right bottom mirror)
			)
		)
		(property "Datasheet" "https://www.murata.com/products/productdetail?partno=GRM155R61H104KE14%23"
			(at 0 0 0)
			(layer "F.Fab")
			(hide yes)
			(effects
				(font
					(size 1.27 1.27)
					(thickness 0.15)
				)
			)
		)
		(property "MPN" "GRM155R61H104KE14D"
			(at 0 0 0)
			(unlocked yes)
			(layer "B.Fab")
			(hide yes)
			(effects
				(font
					(size 1 1)
					(thickness 0.15)
				)
				(justify mirror)
			)
		)
		(property "Manufacturer" "Murata"
			(at 0 0 0)
			(unlocked yes)
			(layer "B.Fab")
			(hide yes)
			(effects
				(font
					(size 1 1)
					(thickness 0.15)
				)
				(justify mirror)
			)
		)
		(property "License" "Apache-2.0"
			(at 0 0 0)
			(unlocked yes)
			(layer "B.Fab")
			(hide yes)
			(effects
				(font
					(size 1 1)
					(thickness 0.15)
				)
				(justify mirror)
			)
		)
		(property "Author" "Antmicro"
			(at 0 0 0)
			(unlocked yes)
			(layer "B.Fab")
			(hide yes)
			(effects
				(font
					(size 1 1)
					(thickness 0.15)
				)
				(justify mirror)
			)
		)
		(property "Val" "100n"
			(at 0 0 0)
			(unlocked yes)
			(layer "B.Fab")
			(hide yes)
			(effects
				(font
					(size 1 1)
					(thickness 0.15)
				)
				(justify mirror)
			)
		)
		(property "Voltage" "50V"
			(at 0 0 0)
			(unlocked yes)
			(layer "B.Fab")
			(hide yes)
			(effects
				(font
					(size 1 1)
					(thickness 0.15)
				)
				(justify mirror)
			)
		)
		(property "Dielectric" "X5R"
			(at 0 0 0)
			(unlocked yes)
			(layer "B.Fab")
			(hide yes)
			(effects
				(font
					(size 1 1)
					(thickness 0.15)
				)
				(justify mirror)
			)
		)
		(sheetname "/FPGA power/")
		(sheetfile "fpga-power.kicad_sch")
		(attr smd)
		(fp_rect
			(start -0.95 0.45)
			(end 0.95 -0.45)
			(stroke
				(width 0.05)
				(type default)
			)
			(fill no)
			(layer "B.CrtYd")
		)
		(fp_line
			(start -0.5 -0.248)
			(end -0.5 0.25)
			(stroke
				(width 0.15)
				(type solid)
			)
			(layer "B.Fab")
		)
		(fp_line
			(start -0.5 0.25)
			(end 0.498 0.25)
			(stroke
				(width 0.15)
				(type solid)
			)
			(layer "B.Fab")
		)
		(fp_line
			(start 0.498 -0.248)
			(end -0.5 -0.248)
			(stroke
				(width 0.15)
				(type solid)
			)
			(layer "B.Fab")
		)
		(fp_line
			(start 0.498 0.25)
			(end 0.498 -0.248)
			(stroke
				(width 0.15)
				(type solid)
			)
			(layer "B.Fab")
		)
		(fp_text user "License: Apache-2.0"
			(at -0.9656 -4.369 180)
			(layer "B.Fab")
			(effects
				(font
					(size 0.7 0.7)
					(thickness 0.15)
				)
				(justify left bottom mirror)
			)
		)
		(fp_text user "Author: Antmicro"
			(at -0.9656 -5.569 180)
			(layer "B.Fab")
			(effects
				(font
					(size 0.7 0.7)
					(thickness 0.15)
				)
				(justify left bottom mirror)
			)
		)
		(fp_text user "${REFERENCE}"
			(at -0.9656 -3.169 180)
			(layer "B.Fab")
			(effects
				(font
					(size 0.7 0.7)
					(thickness 0.15)
				)
				(justify left bottom mirror)
			)
		)
		(pad "1" smd roundrect
			(at -0.5 0 270)
			(size 0.6 0.6)
			(layers "B.Cu" "B.Mask" "B.Paste")
			(roundrect_rratio 0.25)
			(net 1 "GND")
			(pintype "passive")
		)
		(pad "2" smd roundrect
			(at 0.498 0)
			(size 0.6 0.6)
			(layers "B.Cu" "B.Mask" "B.Paste")
			(roundrect_rratio 0.25)
			(net 820 "+0V9_MGTAVCC")
			(pintype "passive")
		)
	)
	(footprint "antmicro-footprints:C_0603_1608Metric"
		(layer "B.Cu")
		(at 228.784999 172.080002 90)
		(descr "Capacitor SMD 0603")
		(tags "capacitor 0603")
		(property "Reference" "C263"
			(at -4.069998 0.320001 90)
			(layer "B.SilkS")
			(effects
				(font
					(size 0.7 0.7)
					(thickness 0.15)
				)
				(justify right bottom mirror)
			)
		)
		(property "Value" "C_22u_0603"
			(at -1.42757 -1.770288 90)
			(layer "B.Fab")
			(effects
				(font
					(size 0.7 0.7)
					(thickness 0.15)
				)
				(justify right bottom mirror)
			)
		)
		(property "Datasheet" "https://www.murata.com/products/productdetail?partno=GRM188R60J226MEA0%23"
			(at 0 0 90)
			(layer "F.Fab")
			(hide yes)
			(effects
				(font
					(size 1.27 1.27)
					(thickness 0.15)
				)
			)
		)
		(property "Manufacturer" "Murata"
			(at 0 0 90)
			(unlocked yes)
			(layer "B.Fab")
			(hide yes)
			(effects
				(font
					(size 1 1)
					(thickness 0.15)
				)
				(justify mirror)
			)
		)
		(property "MPN" "GRM188R60J226MEA0D"
			(at 0 0 90)
			(unlocked yes)
			(layer "B.Fab")
			(hide yes)
			(effects
				(font
					(size 1 1)
					(thickness 0.15)
				)
				(justify mirror)
			)
		)
		(property "Val" "22u"
			(at 0 0 90)
			(unlocked yes)
			(layer "B.Fab")
			(hide yes)
			(effects
				(font
					(size 1 1)
					(thickness 0.15)
				)
				(justify mirror)
			)
		)
		(property "License" "Apache-2.0"
			(at 0 0 90)
			(unlocked yes)
			(layer "B.Fab")
			(hide yes)
			(effects
				(font
					(size 1 1)
					(thickness 0.15)
				)
				(justify mirror)
			)
		)
		(property "Author" "Antmicro"
			(at 0 0 90)
			(unlocked yes)
			(layer "B.Fab")
			(hide yes)
			(effects
				(font
					(size 1 1)
					(thickness 0.15)
				)
				(justify mirror)
			)
		)
		(property "Voltage" ""
			(at 0 0 90)
			(unlocked yes)
			(layer "B.Fab")
			(hide yes)
			(effects
				(font
					(size 1 1)
					(thickness 0.15)
				)
				(justify mirror)
			)
		)
		(property "Dielectric" ""
			(at 0 0 90)
			(unlocked yes)
			(layer "B.Fab")
			(hide yes)
			(effects
				(font
					(size 1 1)
					(thickness 0.15)
				)
				(justify mirror)
			)
		)
		(sheetname "/Supply/DC-DC VCCINT/")
		(sheetfile "dc-dc-vccint.kicad_sch")
		(attr smd)
		(fp_line
			(start -0.15 -0.4)
			(end 0.15 -0.4)
			(stroke
				(width 0.15)
				(type solid)
			)
			(layer "B.SilkS")
		)
		(fp_line
			(start -0.15 0.4)
			(end 0.15 0.4)
			(stroke
				(width 0.15)
				(type solid)
			)
			(layer "B.SilkS")
		)
		(fp_rect
			(start -1.25 0.65)
			(end 1.25 -0.65)
			(stroke
				(width 0.05)
				(type solid)
			)
			(fill no)
			(layer "B.CrtYd")
		)
		(fp_rect
			(start -0.8 0.4)
			(end 0.8 -0.4)
			(stroke
				(width 0.15)
				(type solid)
			)
			(fill no)
			(layer "B.Fab")
		)
		(fp_text user "Author: Antmicro"
			(at -1.682 -4.894 270)
			(layer "B.Fab")
			(effects
				(font
					(size 0.7 0.7)
					(thickness 0.15)
				)
				(justify left bottom mirror)
			)
		)
		(fp_text user "${REFERENCE}"
			(at -1.682 -3.895 270)
			(layer "B.Fab")
			(effects
				(font
					(size 0.7 0.7)
					(thickness 0.15)
				)
				(justify left bottom mirror)
			)
		)
		(fp_text user "License: Apache-2.0"
			(at -1.682 -5.895 270)
			(layer "B.Fab")
			(effects
				(font
					(size 0.7 0.7)
					(thickness 0.15)
				)
				(justify left bottom mirror)
			)
		)
		(pad "1" smd roundrect
			(at -0.7 0 90)
			(size 0.8 1)
			(layers "B.Cu" "B.Mask" "B.Paste")
			(roundrect_rratio 0.2)
			(net 1 "GND")
			(pintype "passive")
		)
		(pad "2" smd roundrect
			(at 0.7 0 90)
			(size 0.8 1)
			(layers "B.Cu" "B.Mask" "B.Paste")
			(roundrect_rratio 0.2)
			(net 224 "/Supply/DC-DC VCCINT/0V85_REG1")
			(pintype "passive")
		)
	)
	(footprint "antmicro-footprints:C_0402_1005Metric_EIA"
		(layer "B.Cu")
		(at 178.499999 157)
		(descr "Capacitor SMD 0402 (1005 Metric), square (rectangular) end terminal, IPC_7351 nominal, (Body size source: IPC-SM-782 page 76, https://www.pcb-3d.com/wordpress/wp-content/uploads/ipc-sm-782a_amendment_1_and_2.pdf)")
		(tags "capacitor 0402")
		(property "Reference" "C17"
			(at -2.999999 0.45 0)
			(layer "B.SilkS")
			(effects
				(font
					(size 0.7 0.7)
					(thickness 0.15)
				)
				(justify right bottom mirror)
			)
		)
		(property "Value" "C_100n_0402"
			(at 0 -1.169 0)
			(layer "B.Fab")
			(effects
				(font
					(size 0.7 0.7)
					(thickness 0.15)
				)
				(justify right bottom mirror)
			)
		)
		(property "Datasheet" "https://www.murata.com/products/productdetail?partno=GRM155R61H104KE14%23"
			(at 0 0 0)
			(layer "F.Fab")
			(hide yes)
			(effects
				(font
					(size 1.27 1.27)
					(thickness 0.15)
				)
			)
		)
		(property "MPN" "GRM155R61H104KE14D"
			(at 0 0 0)
			(unlocked yes)
			(layer "B.Fab")
			(hide yes)
			(effects
				(font
					(size 1 1)
					(thickness 0.15)
				)
				(justify mirror)
			)
		)
		(property "Manufacturer" "Murata"
			(at 0 0 0)
			(unlocked yes)
			(layer "B.Fab")
			(hide yes)
			(effects
				(font
					(size 1 1)
					(thickness 0.15)
				)
				(justify mirror)
			)
		)
		(property "License" "Apache-2.0"
			(at 0 0 0)
			(unlocked yes)
			(layer "B.Fab")
			(hide yes)
			(effects
				(font
					(size 1 1)
					(thickness 0.15)
				)
				(justify mirror)
			)
		)
		(property "Author" "Antmicro"
			(at 0 0 0)
			(unlocked yes)
			(layer "B.Fab")
			(hide yes)
			(effects
				(font
					(size 1 1)
					(thickness 0.15)
				)
				(justify mirror)
			)
		)
		(property "Val" "100n"
			(at 0 0 0)
			(unlocked yes)
			(layer "B.Fab")
			(hide yes)
			(effects
				(font
					(size 1 1)
					(thickness 0.15)
				)
				(justify mirror)
			)
		)
		(property "Voltage" "50V"
			(at 0 0 0)
			(unlocked yes)
			(layer "B.Fab")
			(hide yes)
			(effects
				(font
					(size 1 1)
					(thickness 0.15)
				)
				(justify mirror)
			)
		)
		(property "Dielectric" "X5R"
			(at 0 0 0)
			(unlocked yes)
			(layer "B.Fab")
			(hide yes)
			(effects
				(font
					(size 1 1)
					(thickness 0.15)
				)
				(justify mirror)
			)
		)
		(sheetname "/FPGA power/")
		(sheetfile "fpga-power.kicad_sch")
		(attr smd)
		(fp_rect
			(start -0.95 0.45)
			(end 0.95 -0.45)
			(stroke
				(width 0.05)
				(type default)
			)
			(fill no)
			(layer "B.CrtYd")
		)
		(fp_line
			(start -0.5 -0.248)
			(end -0.5 0.25)
			(stroke
				(width 0.15)
				(type solid)
			)
			(layer "B.Fab")
		)
		(fp_line
			(start -0.5 0.25)
			(end 0.498 0.25)
			(stroke
				(width 0.15)
				(type solid)
			)
			(layer "B.Fab")
		)
		(fp_line
			(start 0.498 -0.248)
			(end -0.5 -0.248)
			(stroke
				(width 0.15)
				(type solid)
			)
			(layer "B.Fab")
		)
		(fp_line
			(start 0.498 0.25)
			(end 0.498 -0.248)
			(stroke
				(width 0.15)
				(type solid)
			)
			(layer "B.Fab")
		)
		(fp_text user "License: Apache-2.0"
			(at -0.9656 -4.369 180)
			(layer "B.Fab")
			(effects
				(font
					(size 0.7 0.7)
					(thickness 0.15)
				)
				(justify left bottom mirror)
			)
		)
		(fp_text user "Author: Antmicro"
			(at -0.9656 -5.569 180)
			(layer "B.Fab")
			(effects
				(font
					(size 0.7 0.7)
					(thickness 0.15)
				)
				(justify left bottom mirror)
			)
		)
		(fp_text user "${REFERENCE}"
			(at -0.9656 -3.169 180)
			(layer "B.Fab")
			(effects
				(font
					(size 0.7 0.7)
					(thickness 0.15)
				)
				(justify left bottom mirror)
			)
		)
		(pad "1" smd roundrect
			(at -0.5 0 270)
			(size 0.6 0.6)
			(layers "B.Cu" "B.Mask" "B.Paste")
			(roundrect_rratio 0.25)
			(net 1 "GND")
			(pintype "passive")
		)
		(pad "2" smd roundrect
			(at 0.498 0)
			(size 0.6 0.6)
			(layers "B.Cu" "B.Mask" "B.Paste")
			(roundrect_rratio 0.25)
			(net 151 "+3V3")
			(pintype "passive")
		)
	)
	(footprint "antmicro-footprints:C_0603_1608Metric"
		(layer "B.Cu")
		(at 246.94 121.47 90)
		(descr "Capacitor SMD 0603")
		(tags "capacitor 0603")
		(property "Reference" "C327"
			(at -4.11 0.48 90)
			(layer "B.SilkS")
			(effects
				(font
					(size 0.7 0.7)
					(thickness 0.15)
				)
				(justify right bottom mirror)
			)
		)
		(property "Value" "C_10u_25V_0603"
			(at -1.42757 -1.770288 90)
			(layer "B.Fab")
			(effects
				(font
					(size 0.7 0.7)
					(thickness 0.15)
				)
				(justify right bottom mirror)
			)
		)
		(property "Datasheet" "https://product.tdk.com/en/search/capacitor/ceramic/mlcc/info?part_no=C1608X5R1E106M080AC"
			(at 0 0 90)
			(layer "F.Fab")
			(hide yes)
			(effects
				(font
					(size 1.27 1.27)
					(thickness 0.15)
				)
			)
		)
		(property "MPN" "C1608X5R1E106M080AC"
			(at 0 0 90)
			(unlocked yes)
			(layer "B.Fab")
			(hide yes)
			(effects
				(font
					(size 1 1)
					(thickness 0.15)
				)
				(justify mirror)
			)
		)
		(property "Manufacturer" "TDK"
			(at 0 0 90)
			(unlocked yes)
			(layer "B.Fab")
			(hide yes)
			(effects
				(font
					(size 1 1)
					(thickness 0.15)
				)
				(justify mirror)
			)
		)
		(property "License" "Apache-2.0"
			(at 0 0 90)
			(unlocked yes)
			(layer "B.Fab")
			(hide yes)
			(effects
				(font
					(size 1 1)
					(thickness 0.15)
				)
				(justify mirror)
			)
		)
		(property "Author" "Antmicro"
			(at 0 0 90)
			(unlocked yes)
			(layer "B.Fab")
			(hide yes)
			(effects
				(font
					(size 1 1)
					(thickness 0.15)
				)
				(justify mirror)
			)
		)
		(property "Val" "10u"
			(at 0 0 90)
			(unlocked yes)
			(layer "B.Fab")
			(hide yes)
			(effects
				(font
					(size 1 1)
					(thickness 0.15)
				)
				(justify mirror)
			)
		)
		(property "Voltage" "25V"
			(at 0 0 90)
			(unlocked yes)
			(layer "B.Fab")
			(hide yes)
			(effects
				(font
					(size 1 1)
					(thickness 0.15)
				)
				(justify mirror)
			)
		)
		(property "Dielectric" ""
			(at 0 0 90)
			(unlocked yes)
			(layer "B.Fab")
			(hide yes)
			(effects
				(font
					(size 1 1)
					(thickness 0.15)
				)
				(justify mirror)
			)
		)
		(sheetname "/Supply/")
		(sheetfile "supply.kicad_sch")
		(attr smd)
		(fp_line
			(start -0.15 -0.4)
			(end 0.15 -0.4)
			(stroke
				(width 0.15)
				(type solid)
			)
			(layer "B.SilkS")
		)
		(fp_line
			(start -0.15 0.4)
			(end 0.15 0.4)
			(stroke
				(width 0.15)
				(type solid)
			)
			(layer "B.SilkS")
		)
		(fp_rect
			(start -1.25 0.65)
			(end 1.25 -0.65)
			(stroke
				(width 0.05)
				(type solid)
			)
			(fill no)
			(layer "B.CrtYd")
		)
		(fp_rect
			(start -0.8 0.4)
			(end 0.8 -0.4)
			(stroke
				(width 0.15)
				(type solid)
			)
			(fill no)
			(layer "B.Fab")
		)
		(fp_text user "${REFERENCE}"
			(at -1.682 -3.895 270)
			(layer "B.Fab")
			(effects
				(font
					(size 0.7 0.7)
					(thickness 0.15)
				)
				(justify left bottom mirror)
			)
		)
		(fp_text user "Author: Antmicro"
			(at -1.682 -4.894 270)
			(layer "B.Fab")
			(effects
				(font
					(size 0.7 0.7)
					(thickness 0.15)
				)
				(justify left bottom mirror)
			)
		)
		(fp_text user "License: Apache-2.0"
			(at -1.682 -5.895 270)
			(layer "B.Fab")
			(effects
				(font
					(size 0.7 0.7)
					(thickness 0.15)
				)
				(justify left bottom mirror)
			)
		)
		(pad "1" smd roundrect
			(at -0.7 0 90)
			(size 0.8 1)
			(layers "B.Cu" "B.Mask" "B.Paste")
			(roundrect_rratio 0.2)
			(net 1 "GND")
			(pintype "passive")
		)
		(pad "2" smd roundrect
			(at 0.7 0 90)
			(size 0.8 1)
			(layers "B.Cu" "B.Mask" "B.Paste")
			(roundrect_rratio 0.2)
			(net 35 "VDC")
			(pintype "passive")
		)
	)
	(footprint "antmicro-footprints:R_0402_1005Metric"
		(layer "B.Cu")
		(at 260.499499 153.299 90)
		(descr "Resistor SMD 0402")
		(tags "resistor SMD 0402")
		(property "Reference" "R167"
			(at 0.949 0.400501 90)
			(layer "B.SilkS")
			(effects
				(font
					(size 0.7 0.7)
					(thickness 0.15)
				)
				(justify right bottom mirror)
			)
		)
		(property "Value" "R_0R_0402"
			(at -1.011843 -1.772047 90)
			(layer "B.Fab")
			(effects
				(font
					(size 0.7 0.7)
					(thickness 0.15)
				)
				(justify right bottom mirror)
			)
		)
		(property "Datasheet" "https://industrial.panasonic.com/cdbs/www-data/pdf/RDA0000/AOA0000C301.pdf"
			(at 0 0 90)
			(layer "F.Fab")
			(hide yes)
			(effects
				(font
					(size 1.27 1.27)
					(thickness 0.15)
				)
			)
		)
		(property "Manufacturer" "Panasonic"
			(at 0 0 90)
			(unlocked yes)
			(layer "B.Fab")
			(hide yes)
			(effects
				(font
					(size 1 1)
					(thickness 0.15)
				)
				(justify mirror)
			)
		)
		(property "MPN" "ERJ2GE0R00X"
			(at 0 0 90)
			(unlocked yes)
			(layer "B.Fab")
			(hide yes)
			(effects
				(font
					(size 1 1)
					(thickness 0.15)
				)
				(justify mirror)
			)
		)
		(property "Val" "0R"
			(at 0 0 90)
			(unlocked yes)
			(layer "B.Fab")
			(hide yes)
			(effects
				(font
					(size 1 1)
					(thickness 0.15)
				)
				(justify mirror)
			)
		)
		(property "License" "Apache-2.0"
			(at 0 0 90)
			(unlocked yes)
			(layer "B.Fab")
			(hide yes)
			(effects
				(font
					(size 1 1)
					(thickness 0.15)
				)
				(justify mirror)
			)
		)
		(property "Author" "Antmicro"
			(at 0 0 90)
			(unlocked yes)
			(layer "B.Fab")
			(hide yes)
			(effects
				(font
					(size 1 1)
					(thickness 0.15)
				)
				(justify mirror)
			)
		)
		(property "Tolerance" "~"
			(at 0 0 90)
			(unlocked yes)
			(layer "B.Fab")
			(hide yes)
			(effects
				(font
					(size 1 1)
					(thickness 0.15)
				)
				(justify mirror)
			)
		)
		(property "Current" "1A"
			(at 0 0 90)
			(unlocked yes)
			(layer "B.Fab")
			(hide yes)
			(effects
				(font
					(size 1 1)
					(thickness 0.15)
				)
				(justify mirror)
			)
		)
		(sheetname "/Supply/DC-DC IO/")
		(sheetfile "dc-dc-io.kicad_sch")
		(attr smd exclude_from_bom dnp)
		(fp_rect
			(start -0.925 0.47)
			(end 0.925 -0.47)
			(stroke
				(width 0.05)
				(type default)
			)
			(fill no)
			(layer "B.CrtYd")
		)
		(fp_rect
			(start -0.5 0.25)
			(end 0.5 -0.25)
			(stroke
				(width 0.15)
				(type solid)
			)
			(fill no)
			(layer "B.Fab")
		)
		(fp_text user "Author: Antmicro"
			(at -0.95 -4.169 270)
			(layer "B.Fab")
			(effects
				(font
					(size 0.7 0.7)
					(thickness 0.15)
				)
				(justify left bottom mirror)
			)
		)
		(fp_text user "License: Apache-2.0"
			(at -0.95 -5.169 270)
			(layer "B.Fab")
			(effects
				(font
					(size 0.7 0.7)
					(thickness 0.15)
				)
				(justify left bottom mirror)
			)
		)
		(fp_text user "${REFERENCE}"
			(at -0.95 -3.168 270)
			(layer "B.Fab")
			(effects
				(font
					(size 0.7 0.7)
					(thickness 0.15)
				)
				(justify left bottom mirror)
			)
		)
		(pad "1" smd roundrect
			(at -0.48 0 90)
			(size 0.59 0.64)
			(layers "B.Cu" "B.Mask" "B.Paste")
			(roundrect_rratio 0.25)
			(net 1 "GND")
			(pintype "passive")
		)
		(pad "2" smd roundrect
			(at 0.48 0 90)
			(size 0.59 0.64)
			(layers "B.Cu" "B.Mask" "B.Paste")
			(roundrect_rratio 0.25)
			(net 718 "/Supply/DC-DC IO/FB7")
			(pintype "passive")
		)
	)
	(footprint "antmicro-footprints:C_0402_1005Metric"
		(layer "B.Cu")
		(at 122.95 154.61 180)
		(descr "Capacitor SMD 0402")
		(tags "capacitor SMD 0402")
		(property "Reference" "C291"
			(at -5.22 -1.66 0)
			(layer "B.SilkS")
			(effects
				(font
					(size 0.7 0.7)
					(thickness 0.15)
				)
				(justify left bottom mirror)
			)
		)
		(property "Value" "C_100n_0402"
			(at -1.022927 -2.155213 0)
			(layer "B.Fab")
			(effects
				(font
					(size 0.7 0.7)
					(thickness 0.15)
				)
				(justify left bottom mirror)
			)
		)
		(property "Datasheet" "https://www.murata.com/products/productdetail?partno=GRM155R61H104KE14%23"
			(at 0 0 180)
			(layer "F.Fab")
			(hide yes)
			(effects
				(font
					(size 1.27 1.27)
					(thickness 0.15)
				)
			)
		)
		(property "Manufacturer" "Murata"
			(at 0 0 180)
			(unlocked yes)
			(layer "B.Fab")
			(hide yes)
			(effects
				(font
					(size 1 1)
					(thickness 0.15)
				)
				(justify mirror)
			)
		)
		(property "MPN" "GRM155R61H104KE14D"
			(at 0 0 180)
			(unlocked yes)
			(layer "B.Fab")
			(hide yes)
			(effects
				(font
					(size 1 1)
					(thickness 0.15)
				)
				(justify mirror)
			)
		)
		(property "Val" "100n"
			(at 0 0 180)
			(unlocked yes)
			(layer "B.Fab")
			(hide yes)
			(effects
				(font
					(size 1 1)
					(thickness 0.15)
				)
				(justify mirror)
			)
		)
		(property "License" "Apache-2.0"
			(at 0 0 180)
			(unlocked yes)
			(layer "B.Fab")
			(hide yes)
			(effects
				(font
					(size 1 1)
					(thickness 0.15)
				)
				(justify mirror)
			)
		)
		(property "Author" "Antmicro"
			(at 0 0 180)
			(unlocked yes)
			(layer "B.Fab")
			(hide yes)
			(effects
				(font
					(size 1 1)
					(thickness 0.15)
				)
				(justify mirror)
			)
		)
		(property "Voltage" "50V"
			(at 0 0 180)
			(unlocked yes)
			(layer "B.Fab")
			(hide yes)
			(effects
				(font
					(size 1 1)
					(thickness 0.15)
				)
				(justify mirror)
			)
		)
		(property "Dielectric" "X5R"
			(at 0 0 180)
			(unlocked yes)
			(layer "B.Fab")
			(hide yes)
			(effects
				(font
					(size 1 1)
					(thickness 0.15)
				)
				(justify mirror)
			)
		)
		(sheetname "/FPGA MGT Interface/")
		(sheetfile "fpga-mgt.kicad_sch")
		(attr smd)
		(fp_rect
			(start -0.925 0.47)
			(end 0.925 -0.47)
			(stroke
				(width 0.05)
				(type default)
			)
			(fill no)
			(layer "B.CrtYd")
		)
		(fp_line
			(start 0.504 0.25)
			(end 0.504 -0.248)
			(stroke
				(width 0.15)
				(type solid)
			)
			(layer "B.Fab")
		)
		(fp_line
			(start 0.504 -0.248)
			(end -0.494 -0.248)
			(stroke
				(width 0.15)
				(type solid)
			)
			(layer "B.Fab")
		)
		(fp_line
			(start -0.494 0.25)
			(end 0.504 0.25)
			(stroke
				(width 0.15)
				(type solid)
			)
			(layer "B.Fab")
		)
		(fp_line
			(start -0.494 -0.248)
			(end -0.494 0.25)
			(stroke
				(width 0.15)
				(type solid)
			)
			(layer "B.Fab")
		)
		(fp_text user "${REFERENCE}"
			(at -0.939 -4.599 0)
			(layer "B.Fab")
			(effects
				(font
					(size 0.7 0.7)
					(thickness 0.15)
				)
				(justify left bottom mirror)
			)
		)
		(fp_text user "Author: Antmicro"
			(at -0.939 -3.399 0)
			(layer "B.Fab")
			(effects
				(font
					(size 0.7 0.7)
					(thickness 0.15)
				)
				(justify left bottom mirror)
			)
		)
		(fp_text user "License: Apache-2.0"
			(at -0.939 -5.799 0)
			(layer "B.Fab")
			(effects
				(font
					(size 0.7 0.7)
					(thickness 0.15)
				)
				(justify left bottom mirror)
			)
		)
		(pad "1" smd roundrect
			(at -0.48 0 180)
			(size 0.59 0.64)
			(layers "B.Cu" "B.Mask" "B.Paste")
			(roundrect_rratio 0.25)
			(net 291 "/FPGA MGT Interface/HDMI_IN_CLK_C_N")
			(pintype "passive")
		)
		(pad "2" smd roundrect
			(at 0.48 0 180)
			(size 0.59 0.64)
			(layers "B.Cu" "B.Mask" "B.Paste")
			(roundrect_rratio 0.25)
			(net 292 "/FPGA MGT Interface/HDMI_IN.CLK_N")
			(pintype "passive")
		)
	)
	(footprint "antmicro-footprints:R_0402_1005Metric"
		(layer "B.Cu")
		(at 255.289499 138.25 180)
		(descr "Resistor SMD 0402")
		(tags "resistor SMD 0402")
		(property "Reference" "R206"
			(at -4.210501 -0.35 0)
			(layer "B.SilkS")
			(effects
				(font
					(size 0.7 0.7)
					(thickness 0.15)
				)
				(justify left bottom mirror)
			)
		)
		(property "Value" "R_4k7_0402"
			(at -1.011843 -1.772047 0)
			(layer "B.Fab")
			(effects
				(font
					(size 0.7 0.7)
					(thickness 0.15)
				)
				(justify left bottom mirror)
			)
		)
		(property "Datasheet" "https://www.bourns.com/docs/product-datasheets/cr.pdf"
			(at 0 0 180)
			(layer "F.Fab")
			(hide yes)
			(effects
				(font
					(size 1.27 1.27)
					(thickness 0.15)
				)
			)
		)
		(property "MPN" "CR0402-FX-4701GLF"
			(at 0 0 180)
			(unlocked yes)
			(layer "B.Fab")
			(hide yes)
			(effects
				(font
					(size 1 1)
					(thickness 0.15)
				)
				(justify mirror)
			)
		)
		(property "Manufacturer" "Bourns"
			(at 0 0 180)
			(unlocked yes)
			(layer "B.Fab")
			(hide yes)
			(effects
				(font
					(size 1 1)
					(thickness 0.15)
				)
				(justify mirror)
			)
		)
		(property "License" "Apache-2.0"
			(at 0 0 180)
			(unlocked yes)
			(layer "B.Fab")
			(hide yes)
			(effects
				(font
					(size 1 1)
					(thickness 0.15)
				)
				(justify mirror)
			)
		)
		(property "Author" "Antmicro"
			(at 0 0 180)
			(unlocked yes)
			(layer "B.Fab")
			(hide yes)
			(effects
				(font
					(size 1 1)
					(thickness 0.15)
				)
				(justify mirror)
			)
		)
		(property "Val" "4k7"
			(at 0 0 180)
			(unlocked yes)
			(layer "B.Fab")
			(hide yes)
			(effects
				(font
					(size 1 1)
					(thickness 0.15)
				)
				(justify mirror)
			)
		)
		(property "Tolerance" "1%"
			(at 0 0 180)
			(unlocked yes)
			(layer "B.Fab")
			(hide yes)
			(effects
				(font
					(size 1 1)
					(thickness 0.15)
				)
				(justify mirror)
			)
		)
		(sheetname "/Supply/")
		(sheetfile "supply.kicad_sch")
		(attr smd)
		(fp_rect
			(start -0.925 0.47)
			(end 0.925 -0.47)
			(stroke
				(width 0.05)
				(type default)
			)
			(fill no)
			(layer "B.CrtYd")
		)
		(fp_rect
			(start -0.5 0.25)
			(end 0.5 -0.25)
			(stroke
				(width 0.15)
				(type solid)
			)
			(fill no)
			(layer "B.Fab")
		)
		(fp_text user "License: Apache-2.0"
			(at -0.95 -5.169 0)
			(layer "B.Fab")
			(effects
				(font
					(size 0.7 0.7)
					(thickness 0.15)
				)
				(justify left bottom mirror)
			)
		)
		(fp_text user "Author: Antmicro"
			(at -0.95 -4.169 0)
			(layer "B.Fab")
			(effects
				(font
					(size 0.7 0.7)
					(thickness 0.15)
				)
				(justify left bottom mirror)
			)
		)
		(fp_text user "${REFERENCE}"
			(at -0.95 -3.168 0)
			(layer "B.Fab")
			(effects
				(font
					(size 0.7 0.7)
					(thickness 0.15)
				)
				(justify left bottom mirror)
			)
		)
		(pad "1" smd roundrect
			(at -0.48 0 180)
			(size 0.59 0.64)
			(layers "B.Cu" "B.Mask" "B.Paste")
			(roundrect_rratio 0.25)
			(net 625 "Net-(Q17-D)")
			(pintype "passive")
		)
		(pad "2" smd roundrect
			(at 0.48 0 180)
			(size 0.59 0.64)
			(layers "B.Cu" "B.Mask" "B.Paste")
			(roundrect_rratio 0.25)
			(net 50 "/Supply/SEQ_EN")
			(pintype "passive")
		)
	)
	(footprint "antmicro-footprints:C_0402_1005Metric_EIA"
		(layer "B.Cu")
		(at 187 156.5 -90)
		(descr "Capacitor SMD 0402 (1005 Metric), square (rectangular) end terminal, IPC_7351 nominal, (Body size source: IPC-SM-782 page 76, https://www.pcb-3d.com/wordpress/wp-content/uploads/ipc-sm-782a_amendment_1_and_2.pdf)")
		(tags "capacitor 0402")
		(property "Reference" "C33"
			(at -11.925 30.625 90)
			(layer "B.SilkS")
			(effects
				(font
					(size 0.7 0.7)
					(thickness 0.15)
				)
				(justify left bottom mirror)
			)
		)
		(property "Value" "C_100n_0402"
			(at 0 -1.169 90)
			(layer "B.Fab")
			(effects
				(font
					(size 0.7 0.7)
					(thickness 0.15)
				)
				(justify left bottom mirror)
			)
		)
		(property "Datasheet" "https://www.murata.com/products/productdetail?partno=GRM155R61H104KE14%23"
			(at 0 0 270)
			(layer "F.Fab")
			(hide yes)
			(effects
				(font
					(size 1.27 1.27)
					(thickness 0.15)
				)
			)
		)
		(property "MPN" "GRM155R61H104KE14D"
			(at 0 0 270)
			(unlocked yes)
			(layer "B.Fab")
			(hide yes)
			(effects
				(font
					(size 1 1)
					(thickness 0.15)
				)
				(justify mirror)
			)
		)
		(property "Manufacturer" "Murata"
			(at 0 0 270)
			(unlocked yes)
			(layer "B.Fab")
			(hide yes)
			(effects
				(font
					(size 1 1)
					(thickness 0.15)
				)
				(justify mirror)
			)
		)
		(property "License" "Apache-2.0"
			(at 0 0 270)
			(unlocked yes)
			(layer "B.Fab")
			(hide yes)
			(effects
				(font
					(size 1 1)
					(thickness 0.15)
				)
				(justify mirror)
			)
		)
		(property "Author" "Antmicro"
			(at 0 0 270)
			(unlocked yes)
			(layer "B.Fab")
			(hide yes)
			(effects
				(font
					(size 1 1)
					(thickness 0.15)
				)
				(justify mirror)
			)
		)
		(property "Val" "100n"
			(at 0 0 270)
			(unlocked yes)
			(layer "B.Fab")
			(hide yes)
			(effects
				(font
					(size 1 1)
					(thickness 0.15)
				)
				(justify mirror)
			)
		)
		(property "Voltage" "50V"
			(at 0 0 270)
			(unlocked yes)
			(layer "B.Fab")
			(hide yes)
			(effects
				(font
					(size 1 1)
					(thickness 0.15)
				)
				(justify mirror)
			)
		)
		(property "Dielectric" "X5R"
			(at 0 0 270)
			(unlocked yes)
			(layer "B.Fab")
			(hide yes)
			(effects
				(font
					(size 1 1)
					(thickness 0.15)
				)
				(justify mirror)
			)
		)
		(sheetname "/FPGA power/")
		(sheetfile "fpga-power.kicad_sch")
		(attr smd)
		(fp_rect
			(start -0.95 0.45)
			(end 0.95 -0.45)
			(stroke
				(width 0.05)
				(type default)
			)
			(fill no)
			(layer "B.CrtYd")
		)
		(fp_line
			(start -0.5 0.25)
			(end 0.498 0.25)
			(stroke
				(width 0.15)
				(type solid)
			)
			(layer "B.Fab")
		)
		(fp_line
			(start 0.498 0.25)
			(end 0.498 -0.248)
			(stroke
				(width 0.15)
				(type solid)
			)
			(layer "B.Fab")
		)
		(fp_line
			(start -0.5 -0.248)
			(end -0.5 0.25)
			(stroke
				(width 0.15)
				(type solid)
			)
			(layer "B.Fab")
		)
		(fp_line
			(start 0.498 -0.248)
			(end -0.5 -0.248)
			(stroke
				(width 0.15)
				(type solid)
			)
			(layer "B.Fab")
		)
		(fp_text user "License: Apache-2.0"
			(at -0.9656 -4.369 90)
			(layer "B.Fab")
			(effects
				(font
					(size 0.7 0.7)
					(thickness 0.15)
				)
				(justify left bottom mirror)
			)
		)
		(fp_text user "Author: Antmicro"
			(at -0.9656 -5.569 90)
			(layer "B.Fab")
			(effects
				(font
					(size 0.7 0.7)
					(thickness 0.15)
				)
				(justify left bottom mirror)
			)
		)
		(fp_text user "${REFERENCE}"
			(at -0.9656 -3.169 90)
			(layer "B.Fab")
			(effects
				(font
					(size 0.7 0.7)
					(thickness 0.15)
				)
				(justify left bottom mirror)
			)
		)
		(pad "1" smd roundrect
			(at -0.5 0 180)
			(size 0.6 0.6)
			(layers "B.Cu" "B.Mask" "B.Paste")
			(roundrect_rratio 0.25)
			(net 1 "GND")
			(pintype "passive")
		)
		(pad "2" smd roundrect
			(at 0.498 0 270)
			(size 0.6 0.6)
			(layers "B.Cu" "B.Mask" "B.Paste")
			(roundrect_rratio 0.25)
			(net 553 "+0V85")
			(pintype "passive")
		)
	)
	(footprint "antmicro-footprints:C_0402_1005Metric_EIA"
		(layer "B.Cu")
		(at 191.5 147 180)
		(descr "Capacitor SMD 0402 (1005 Metric), square (rectangular) end terminal, IPC_7351 nominal, (Body size source: IPC-SM-782 page 76, https://www.pcb-3d.com/wordpress/wp-content/uploads/ipc-sm-782a_amendment_1_and_2.pdf)")
		(tags "capacitor 0402")
		(property "Reference" "C30"
			(at 30 10.9 0)
			(layer "B.SilkS")
			(effects
				(font
					(size 0.7 0.7)
					(thickness 0.15)
				)
				(justify left bottom mirror)
			)
		)
		(property "Value" "C_10u_10V_0402"
			(at 0 -1.169 0)
			(layer "B.Fab")
			(effects
				(font
					(size 0.7 0.7)
					(thickness 0.15)
				)
				(justify left bottom mirror)
			)
		)
		(property "Datasheet" "https://www.murata.com/products/productdetail?partno=GRM155R61A106ME11%23"
			(at 0 0 180)
			(layer "F.Fab")
			(hide yes)
			(effects
				(font
					(size 1.27 1.27)
					(thickness 0.15)
				)
			)
		)
		(property "MPN" "GRM155R61A106ME11D"
			(at 0 0 180)
			(unlocked yes)
			(layer "B.Fab")
			(hide yes)
			(effects
				(font
					(size 1 1)
					(thickness 0.15)
				)
				(justify mirror)
			)
		)
		(property "Manufacturer" "Murata"
			(at 0 0 180)
			(unlocked yes)
			(layer "B.Fab")
			(hide yes)
			(effects
				(font
					(size 1 1)
					(thickness 0.15)
				)
				(justify mirror)
			)
		)
		(property "License" "Apache-2.0"
			(at 0 0 180)
			(unlocked yes)
			(layer "B.Fab")
			(hide yes)
			(effects
				(font
					(size 1 1)
					(thickness 0.15)
				)
				(justify mirror)
			)
		)
		(property "Author" "Antmicro"
			(at 0 0 180)
			(unlocked yes)
			(layer "B.Fab")
			(hide yes)
			(effects
				(font
					(size 1 1)
					(thickness 0.15)
				)
				(justify mirror)
			)
		)
		(property "Val" "10u"
			(at 0 0 180)
			(unlocked yes)
			(layer "B.Fab")
			(hide yes)
			(effects
				(font
					(size 1 1)
					(thickness 0.15)
				)
				(justify mirror)
			)
		)
		(property "Voltage" "10V"
			(at 0 0 180)
			(unlocked yes)
			(layer "B.Fab")
			(hide yes)
			(effects
				(font
					(size 1 1)
					(thickness 0.15)
				)
				(justify mirror)
			)
		)
		(property "Dielectric" "X5R"
			(at 0 0 180)
			(unlocked yes)
			(layer "B.Fab")
			(hide yes)
			(effects
				(font
					(size 1 1)
					(thickness 0.15)
				)
				(justify mirror)
			)
		)
		(sheetname "/FPGA power/")
		(sheetfile "fpga-power.kicad_sch")
		(attr smd)
		(fp_rect
			(start -0.95 0.45)
			(end 0.95 -0.45)
			(stroke
				(width 0.05)
				(type default)
			)
			(fill no)
			(layer "B.CrtYd")
		)
		(fp_line
			(start 0.498 0.25)
			(end 0.498 -0.248)
			(stroke
				(width 0.15)
				(type solid)
			)
			(layer "B.Fab")
		)
		(fp_line
			(start 0.498 -0.248)
			(end -0.5 -0.248)
			(stroke
				(width 0.15)
				(type solid)
			)
			(layer "B.Fab")
		)
		(fp_line
			(start -0.5 0.25)
			(end 0.498 0.25)
			(stroke
				(width 0.15)
				(type solid)
			)
			(layer "B.Fab")
		)
		(fp_line
			(start -0.5 -0.248)
			(end -0.5 0.25)
			(stroke
				(width 0.15)
				(type solid)
			)
			(layer "B.Fab")
		)
		(fp_text user "License: Apache-2.0"
			(at -0.9656 -4.369 0)
			(layer "B.Fab")
			(effects
				(font
					(size 0.7 0.7)
					(thickness 0.15)
				)
				(justify left bottom mirror)
			)
		)
		(fp_text user "Author: Antmicro"
			(at -0.9656 -5.569 0)
			(layer "B.Fab")
			(effects
				(font
					(size 0.7 0.7)
					(thickness 0.15)
				)
				(justify left bottom mirror)
			)
		)
		(fp_text user "${REFERENCE}"
			(at -0.9656 -3.169 0)
			(layer "B.Fab")
			(effects
				(font
					(size 0.7 0.7)
					(thickness 0.15)
				)
				(justify left bottom mirror)
			)
		)
		(pad "1" smd roundrect
			(at -0.5 0 90)
			(size 0.6 0.6)
			(layers "B.Cu" "B.Mask" "B.Paste")
			(roundrect_rratio 0.25)
			(net 1 "GND")
			(pintype "passive")
		)
		(pad "2" smd roundrect
			(at 0.498 0 180)
			(size 0.6 0.6)
			(layers "B.Cu" "B.Mask" "B.Paste")
			(roundrect_rratio 0.25)
			(net 797 "+1V8")
			(pintype "passive")
		)
	)
	(footprint "antmicro-footprints:C_0603_1608Metric"
		(layer "B.Cu")
		(at 162.725 154.3 -90)
		(descr "Capacitor SMD 0603")
		(tags "capacitor 0603")
		(property "Reference" "C1"
			(at -2.7 -0.375 90)
			(layer "B.SilkS")
			(effects
				(font
					(size 0.7 0.7)
					(thickness 0.15)
				)
				(justify left bottom mirror)
			)
		)
		(property "Value" "C_47u_0603"
			(at -1.42757 -1.770288 90)
			(layer "B.Fab")
			(effects
				(font
					(size 0.7 0.7)
					(thickness 0.15)
				)
				(justify left bottom mirror)
			)
		)
		(property "Datasheet" "https://www.murata.com/products/productdetail?partno=GRM188R60J476ME15%23"
			(at 0 0 270)
			(layer "F.Fab")
			(hide yes)
			(effects
				(font
					(size 1.27 1.27)
					(thickness 0.15)
				)
			)
		)
		(property "Manufacturer" "Murata"
			(at 0 0 270)
			(unlocked yes)
			(layer "B.Fab")
			(hide yes)
			(effects
				(font
					(size 1 1)
					(thickness 0.15)
				)
				(justify mirror)
			)
		)
		(property "MPN" "GRM188R60J476ME15D"
			(at 0 0 270)
			(unlocked yes)
			(layer "B.Fab")
			(hide yes)
			(effects
				(font
					(size 1 1)
					(thickness 0.15)
				)
				(justify mirror)
			)
		)
		(property "Val" "47u"
			(at 0 0 270)
			(unlocked yes)
			(layer "B.Fab")
			(hide yes)
			(effects
				(font
					(size 1 1)
					(thickness 0.15)
				)
				(justify mirror)
			)
		)
		(property "License" "Apache-2.0"
			(at 0 0 270)
			(unlocked yes)
			(layer "B.Fab")
			(hide yes)
			(effects
				(font
					(size 1 1)
					(thickness 0.15)
				)
				(justify mirror)
			)
		)
		(property "Author" "Antmicro"
			(at 0 0 270)
			(unlocked yes)
			(layer "B.Fab")
			(hide yes)
			(effects
				(font
					(size 1 1)
					(thickness 0.15)
				)
				(justify mirror)
			)
		)
		(property "Voltage" ""
			(at 0 0 270)
			(unlocked yes)
			(layer "B.Fab")
			(hide yes)
			(effects
				(font
					(size 1 1)
					(thickness 0.15)
				)
				(justify mirror)
			)
		)
		(property "Dielectric" ""
			(at 0 0 270)
			(unlocked yes)
			(layer "B.Fab")
			(hide yes)
			(effects
				(font
					(size 1 1)
					(thickness 0.15)
				)
				(justify mirror)
			)
		)
		(sheetname "/HyperRAM + QSPI Flash/")
		(sheetfile "hyperram-flash.kicad_sch")
		(attr smd)
		(fp_line
			(start -0.15 0.4)
			(end 0.15 0.4)
			(stroke
				(width 0.15)
				(type solid)
			)
			(layer "B.SilkS")
		)
		(fp_line
			(start -0.15 -0.4)
			(end 0.15 -0.4)
			(stroke
				(width 0.15)
				(type solid)
			)
			(layer "B.SilkS")
		)
		(fp_rect
			(start -1.25 0.65)
			(end 1.25 -0.65)
			(stroke
				(width 0.05)
				(type solid)
			)
			(fill no)
			(layer "B.CrtYd")
		)
		(fp_rect
			(start -0.8 0.4)
			(end 0.8 -0.4)
			(stroke
				(width 0.15)
				(type solid)
			)
			(fill no)
			(layer "B.Fab")
		)
		(fp_text user "License: Apache-2.0"
			(at -1.682 -5.895 90)
			(layer "B.Fab")
			(effects
				(font
					(size 0.7 0.7)
					(thickness 0.15)
				)
				(justify left bottom mirror)
			)
		)
		(fp_text user "Author: Antmicro"
			(at -1.682 -4.894 90)
			(layer "B.Fab")
			(effects
				(font
					(size 0.7 0.7)
					(thickness 0.15)
				)
				(justify left bottom mirror)
			)
		)
		(fp_text user "${REFERENCE}"
			(at -1.682 -3.895 90)
			(layer "B.Fab")
			(effects
				(font
					(size 0.7 0.7)
					(thickness 0.15)
				)
				(justify left bottom mirror)
			)
		)
		(pad "1" smd roundrect
			(at -0.7 0 270)
			(size 0.8 1)
			(layers "B.Cu" "B.Mask" "B.Paste")
			(roundrect_rratio 0.2)
			(net 797 "+1V8")
			(pintype "passive")
		)
		(pad "2" smd roundrect
			(at 0.7 0 270)
			(size 0.8 1)
			(layers "B.Cu" "B.Mask" "B.Paste")
			(roundrect_rratio 0.2)
			(net 1 "GND")
			(pintype "passive")
		)
	)
	(footprint "antmicro-footprints:C_0402_1005Metric"
		(layer "B.Cu")
		(at 252.2 187.338)
		(descr "Capacitor SMD 0402")
		(tags "capacitor SMD 0402")
		(property "Reference" "C324"
			(at 1 0.449 0)
			(layer "B.SilkS")
			(effects
				(font
					(size 0.7 0.7)
					(thickness 0.15)
				)
				(justify right bottom mirror)
			)
		)
		(property "Value" "C_100n_0402"
			(at -1.022927 -2.155213 0)
			(layer "B.Fab")
			(effects
				(font
					(size 0.7 0.7)
					(thickness 0.15)
				)
				(justify right bottom mirror)
			)
		)
		(property "Datasheet" "https://www.murata.com/products/productdetail?partno=GRM155R61H104KE14%23"
			(at 0 0 0)
			(layer "F.Fab")
			(hide yes)
			(effects
				(font
					(size 1.27 1.27)
					(thickness 0.15)
				)
			)
		)
		(property "MPN" "GRM155R61H104KE14D"
			(at 0 0 0)
			(unlocked yes)
			(layer "B.Fab")
			(hide yes)
			(effects
				(font
					(size 1 1)
					(thickness 0.15)
				)
				(justify mirror)
			)
		)
		(property "Manufacturer" "Murata"
			(at 0 0 0)
			(unlocked yes)
			(layer "B.Fab")
			(hide yes)
			(effects
				(font
					(size 1 1)
					(thickness 0.15)
				)
				(justify mirror)
			)
		)
		(property "License" "Apache-2.0"
			(at 0 0 0)
			(unlocked yes)
			(layer "B.Fab")
			(hide yes)
			(effects
				(font
					(size 1 1)
					(thickness 0.15)
				)
				(justify mirror)
			)
		)
		(property "Author" "Antmicro"
			(at 0 0 0)
			(unlocked yes)
			(layer "B.Fab")
			(hide yes)
			(effects
				(font
					(size 1 1)
					(thickness 0.15)
				)
				(justify mirror)
			)
		)
		(property "Val" "100n"
			(at 0 0 0)
			(unlocked yes)
			(layer "B.Fab")
			(hide yes)
			(effects
				(font
					(size 1 1)
					(thickness 0.15)
				)
				(justify mirror)
			)
		)
		(property "Voltage" "50V"
			(at 0 0 0)
			(unlocked yes)
			(layer "B.Fab")
			(hide yes)
			(effects
				(font
					(size 1 1)
					(thickness 0.15)
				)
				(justify mirror)
			)
		)
		(property "Dielectric" "X5R"
			(at 0 0 0)
			(unlocked yes)
			(layer "B.Fab")
			(hide yes)
			(effects
				(font
					(size 1 1)
					(thickness 0.15)
				)
				(justify mirror)
			)
		)
		(sheetname "/I^{2}C + I3C/")
		(sheetfile "i2c.kicad_sch")
		(attr smd)
		(fp_rect
			(start -0.925 0.47)
			(end 0.925 -0.47)
			(stroke
				(width 0.05)
				(type default)
			)
			(fill no)
			(layer "B.CrtYd")
		)
		(fp_line
			(start -0.494 -0.248)
			(end -0.494 0.25)
			(stroke
				(width 0.15)
				(type solid)
			)
			(layer "B.Fab")
		)
		(fp_line
			(start -0.494 0.25)
			(end 0.504 0.25)
			(stroke
				(width 0.15)
				(type solid)
			)
			(layer "B.Fab")
		)
		(fp_line
			(start 0.504 -0.248)
			(end -0.494 -0.248)
			(stroke
				(width 0.15)
				(type solid)
			)
			(layer "B.Fab")
		)
		(fp_line
			(start 0.504 0.25)
			(end 0.504 -0.248)
			(stroke
				(width 0.15)
				(type solid)
			)
			(layer "B.Fab")
		)
		(fp_text user "${REFERENCE}"
			(at -0.939 -4.599 180)
			(layer "B.Fab")
			(effects
				(font
					(size 0.7 0.7)
					(thickness 0.15)
				)
				(justify left bottom mirror)
			)
		)
		(fp_text user "Author: Antmicro"
			(at -0.939 -3.399 180)
			(layer "B.Fab")
			(effects
				(font
					(size 0.7 0.7)
					(thickness 0.15)
				)
				(justify left bottom mirror)
			)
		)
		(fp_text user "License: Apache-2.0"
			(at -0.939 -5.799 180)
			(layer "B.Fab")
			(effects
				(font
					(size 0.7 0.7)
					(thickness 0.15)
				)
				(justify left bottom mirror)
			)
		)
		(pad "1" smd roundrect
			(at -0.48 0)
			(size 0.59 0.64)
			(layers "B.Cu" "B.Mask" "B.Paste")
			(roundrect_rratio 0.25)
			(net 1 "GND")
			(pintype "passive")
		)
		(pad "2" smd roundrect
			(at 0.48 0)
			(size 0.59 0.64)
			(layers "B.Cu" "B.Mask" "B.Paste")
			(roundrect_rratio 0.25)
			(net 782 "Net-(Q24-D)")
			(pintype "passive")
		)
	)
	(footprint "antmicro-footprints:C_0402_1005Metric_EIA"
		(layer "B.Cu")
		(at 191 158.5 90)
		(descr "Capacitor SMD 0402 (1005 Metric), square (rectangular) end terminal, IPC_7351 nominal, (Body size source: IPC-SM-782 page 76, https://www.pcb-3d.com/wordpress/wp-content/uploads/ipc-sm-782a_amendment_1_and_2.pdf)")
		(tags "capacitor 0402")
		(property "Reference" "C248"
			(at 9.225 -30.6 90)
			(layer "B.SilkS")
			(effects
				(font
					(size 0.7 0.7)
					(thickness 0.15)
				)
				(justify right bottom mirror)
			)
		)
		(property "Value" "C_1u_25V_0402"
			(at 0 -1.169 90)
			(layer "B.Fab")
			(effects
				(font
					(size 0.7 0.7)
					(thickness 0.15)
				)
				(justify right bottom mirror)
			)
		)
		(property "Datasheet" "https://www.murata.com/products/productdetail?partno=GRM155R61E105KE11%23"
			(at 0 0 90)
			(layer "F.Fab")
			(hide yes)
			(effects
				(font
					(size 1.27 1.27)
					(thickness 0.15)
				)
			)
		)
		(property "MPN" "GRM155R61E105KE11J"
			(at 0 0 90)
			(unlocked yes)
			(layer "B.Fab")
			(hide yes)
			(effects
				(font
					(size 1 1)
					(thickness 0.15)
				)
				(justify mirror)
			)
		)
		(property "Manufacturer" "Murata"
			(at 0 0 90)
			(unlocked yes)
			(layer "B.Fab")
			(hide yes)
			(effects
				(font
					(size 1 1)
					(thickness 0.15)
				)
				(justify mirror)
			)
		)
		(property "License" "Apache-2.0"
			(at 0 0 90)
			(unlocked yes)
			(layer "B.Fab")
			(hide yes)
			(effects
				(font
					(size 1 1)
					(thickness 0.15)
				)
				(justify mirror)
			)
		)
		(property "Author" "Antmicro"
			(at 0 0 90)
			(unlocked yes)
			(layer "B.Fab")
			(hide yes)
			(effects
				(font
					(size 1 1)
					(thickness 0.15)
				)
				(justify mirror)
			)
		)
		(property "Val" "1u"
			(at 0 0 90)
			(unlocked yes)
			(layer "B.Fab")
			(hide yes)
			(effects
				(font
					(size 1 1)
					(thickness 0.15)
				)
				(justify mirror)
			)
		)
		(property "Voltage" "25V"
			(at 0 0 90)
			(unlocked yes)
			(layer "B.Fab")
			(hide yes)
			(effects
				(font
					(size 1 1)
					(thickness 0.15)
				)
				(justify mirror)
			)
		)
		(property "Dielectric" "X5R"
			(at 0 0 90)
			(unlocked yes)
			(layer "B.Fab")
			(hide yes)
			(effects
				(font
					(size 1 1)
					(thickness 0.15)
				)
				(justify mirror)
			)
		)
		(sheetname "/FPGA power/")
		(sheetfile "fpga-power.kicad_sch")
		(attr smd)
		(fp_rect
			(start -0.95 0.45)
			(end 0.95 -0.45)
			(stroke
				(width 0.05)
				(type default)
			)
			(fill no)
			(layer "B.CrtYd")
		)
		(fp_line
			(start 0.498 -0.248)
			(end -0.5 -0.248)
			(stroke
				(width 0.15)
				(type solid)
			)
			(layer "B.Fab")
		)
		(fp_line
			(start -0.5 -0.248)
			(end -0.5 0.25)
			(stroke
				(width 0.15)
				(type solid)
			)
			(layer "B.Fab")
		)
		(fp_line
			(start 0.498 0.25)
			(end 0.498 -0.248)
			(stroke
				(width 0.15)
				(type solid)
			)
			(layer "B.Fab")
		)
		(fp_line
			(start -0.5 0.25)
			(end 0.498 0.25)
			(stroke
				(width 0.15)
				(type solid)
			)
			(layer "B.Fab")
		)
		(fp_text user "${REFERENCE}"
			(at -0.9656 -3.169 270)
			(layer "B.Fab")
			(effects
				(font
					(size 0.7 0.7)
					(thickness 0.15)
				)
				(justify left bottom mirror)
			)
		)
		(fp_text user "Author: Antmicro"
			(at -0.9656 -5.569 270)
			(layer "B.Fab")
			(effects
				(font
					(size 0.7 0.7)
					(thickness 0.15)
				)
				(justify left bottom mirror)
			)
		)
		(fp_text user "License: Apache-2.0"
			(at -0.9656 -4.369 270)
			(layer "B.Fab")
			(effects
				(font
					(size 0.7 0.7)
					(thickness 0.15)
				)
				(justify left bottom mirror)
			)
		)
		(pad "1" smd roundrect
			(at -0.5 0)
			(size 0.6 0.6)
			(layers "B.Cu" "B.Mask" "B.Paste")
			(roundrect_rratio 0.25)
			(net 1 "GND")
			(pintype "passive")
		)
		(pad "2" smd roundrect
			(at 0.498 0 90)
			(size 0.6 0.6)
			(layers "B.Cu" "B.Mask" "B.Paste")
			(roundrect_rratio 0.25)
			(net 553 "+0V85")
			(pintype "passive")
		)
	)
	(footprint "antmicro-footprints:R_0402_1005Metric_EIA"
		(layer "B.Cu")
		(at 179 145.505 -90)
		(descr "Resistor SMD 0402 (1005 Metric), square (rectangular) end terminal, IPC_7351 nominal, (Body size source: IPC-SM-782 page 76, https://www.pcb-3d.com/wordpress/wp-content/uploads/ipc-sm-782a_amendment_1_and_2.pdf)")
		(tags "resistor 0402")
		(property "Reference" "R35"
			(at -1.03 -1.475 90)
			(layer "B.SilkS")
			(effects
				(font
					(size 0.7 0.7)
					(thickness 0.15)
				)
				(justify left bottom mirror)
			)
		)
		(property "Value" "R_100R_0402"
			(at 0 -1.169 90)
			(layer "B.Fab")
			(effects
				(font
					(size 0.7 0.7)
					(thickness 0.15)
				)
				(justify left bottom mirror)
			)
		)
		(property "Datasheet" "https://www.bourns.com/docs/product-datasheets/cr.pdf"
			(at 0 0 270)
			(layer "F.Fab")
			(hide yes)
			(effects
				(font
					(size 1.27 1.27)
					(thickness 0.15)
				)
			)
		)
		(property "MPN" "CR0402-FX-1000GLF"
			(at 0 0 270)
			(unlocked yes)
			(layer "B.Fab")
			(hide yes)
			(effects
				(font
					(size 1 1)
					(thickness 0.15)
				)
				(justify mirror)
			)
		)
		(property "Manufacturer" "Bourns"
			(at 0 0 270)
			(unlocked yes)
			(layer "B.Fab")
			(hide yes)
			(effects
				(font
					(size 1 1)
					(thickness 0.15)
				)
				(justify mirror)
			)
		)
		(property "License" "Apache-2.0"
			(at 0 0 270)
			(unlocked yes)
			(layer "B.Fab")
			(hide yes)
			(effects
				(font
					(size 1 1)
					(thickness 0.15)
				)
				(justify mirror)
			)
		)
		(property "Author" "Antmicro"
			(at 0 0 270)
			(unlocked yes)
			(layer "B.Fab")
			(hide yes)
			(effects
				(font
					(size 1 1)
					(thickness 0.15)
				)
				(justify mirror)
			)
		)
		(property "Val" "100R"
			(at 0 0 270)
			(unlocked yes)
			(layer "B.Fab")
			(hide yes)
			(effects
				(font
					(size 1 1)
					(thickness 0.15)
				)
				(justify mirror)
			)
		)
		(property "Tolerance" "1%"
			(at 0 0 270)
			(unlocked yes)
			(layer "B.Fab")
			(hide yes)
			(effects
				(font
					(size 1 1)
					(thickness 0.15)
				)
				(justify mirror)
			)
		)
		(sheetname "/FPGA MGT Interface/")
		(sheetfile "fpga-mgt.kicad_sch")
		(attr smd)
		(fp_rect
			(start -0.95 0.45)
			(end 0.95 -0.45)
			(stroke
				(width 0.05)
				(type default)
			)
			(fill no)
			(layer "B.CrtYd")
		)
		(fp_line
			(start -0.5 0.25)
			(end 0.499 0.25)
			(stroke
				(width 0.15)
				(type solid)
			)
			(layer "B.Fab")
		)
		(fp_line
			(start 0.499 0.25)
			(end 0.499 -0.249)
			(stroke
				(width 0.15)
				(type solid)
			)
			(layer "B.Fab")
		)
		(fp_line
			(start -0.5 -0.249)
			(end -0.5 0.25)
			(stroke
				(width 0.15)
				(type solid)
			)
			(layer "B.Fab")
		)
		(fp_line
			(start 0.499 -0.249)
			(end -0.5 -0.249)
			(stroke
				(width 0.15)
				(type solid)
			)
			(layer "B.Fab")
		)
		(fp_text user "${REFERENCE}"
			(at -0.95 -3.169 90)
			(layer "B.Fab")
			(effects
				(font
					(size 0.7 0.7)
					(thickness 0.15)
				)
				(justify left bottom mirror)
			)
		)
		(fp_text user "License: Apache-2.0"
			(at -0.95 -4.369 90)
			(layer "B.Fab")
			(effects
				(font
					(size 0.7 0.7)
					(thickness 0.15)
				)
				(justify left bottom mirror)
			)
		)
		(fp_text user "Author: Antmicro"
			(at -0.95 -5.569 90)
			(layer "B.Fab")
			(effects
				(font
					(size 0.7 0.7)
					(thickness 0.15)
				)
				(justify left bottom mirror)
			)
		)
		(pad "1" smd roundrect
			(at -0.5 0 180)
			(size 0.6 0.6)
			(layers "B.Cu" "B.Mask" "B.Paste")
			(roundrect_rratio 0.25)
			(net 458 "HDMI_REC_CLK_N")
			(pintype "passive")
		)
		(pad "2" smd roundrect
			(at 0.499 0 270)
			(size 0.6 0.6)
			(layers "B.Cu" "B.Mask" "B.Paste")
			(roundrect_rratio 0.25)
			(net 403 "HDMI_REC_CLK_P")
			(pintype "passive")
		)
	)
	(footprint "antmicro-footprints:R_0402_1005Metric"
		(layer "B.Cu")
		(at 260.549499 170.849 90)
		(descr "Resistor SMD 0402")
		(tags "resistor SMD 0402")
		(property "Reference" "R164"
			(at 0.999 0.350501 90)
			(layer "B.SilkS")
			(effects
				(font
					(size 0.7 0.7)
					(thickness 0.15)
				)
				(justify right bottom mirror)
			)
		)
		(property "Value" "R_0R_0402"
			(at -1.011843 -1.772047 90)
			(layer "B.Fab")
			(effects
				(font
					(size 0.7 0.7)
					(thickness 0.15)
				)
				(justify right bottom mirror)
			)
		)
		(property "Datasheet" "https://industrial.panasonic.com/cdbs/www-data/pdf/RDA0000/AOA0000C301.pdf"
			(at 0 0 90)
			(layer "F.Fab")
			(hide yes)
			(effects
				(font
					(size 1.27 1.27)
					(thickness 0.15)
				)
			)
		)
		(property "Manufacturer" "Panasonic"
			(at 0 0 90)
			(unlocked yes)
			(layer "B.Fab")
			(hide yes)
			(effects
				(font
					(size 1 1)
					(thickness 0.15)
				)
				(justify mirror)
			)
		)
		(property "MPN" "ERJ2GE0R00X"
			(at 0 0 90)
			(unlocked yes)
			(layer "B.Fab")
			(hide yes)
			(effects
				(font
					(size 1 1)
					(thickness 0.15)
				)
				(justify mirror)
			)
		)
		(property "Val" "0R"
			(at 0 0 90)
			(unlocked yes)
			(layer "B.Fab")
			(hide yes)
			(effects
				(font
					(size 1 1)
					(thickness 0.15)
				)
				(justify mirror)
			)
		)
		(property "License" "Apache-2.0"
			(at 0 0 90)
			(unlocked yes)
			(layer "B.Fab")
			(hide yes)
			(effects
				(font
					(size 1 1)
					(thickness 0.15)
				)
				(justify mirror)
			)
		)
		(property "Author" "Antmicro"
			(at 0 0 90)
			(unlocked yes)
			(layer "B.Fab")
			(hide yes)
			(effects
				(font
					(size 1 1)
					(thickness 0.15)
				)
				(justify mirror)
			)
		)
		(property "Tolerance" "~"
			(at 0 0 90)
			(unlocked yes)
			(layer "B.Fab")
			(hide yes)
			(effects
				(font
					(size 1 1)
					(thickness 0.15)
				)
				(justify mirror)
			)
		)
		(property "Current" "1A"
			(at 0 0 90)
			(unlocked yes)
			(layer "B.Fab")
			(hide yes)
			(effects
				(font
					(size 1 1)
					(thickness 0.15)
				)
				(justify mirror)
			)
		)
		(sheetname "/Supply/DC-DC AUX, MGT/")
		(sheetfile "dc-dc-aux-mgt.kicad_sch")
		(attr smd exclude_from_bom dnp)
		(fp_rect
			(start -0.925 0.47)
			(end 0.925 -0.47)
			(stroke
				(width 0.05)
				(type default)
			)
			(fill no)
			(layer "B.CrtYd")
		)
		(fp_rect
			(start -0.5 0.25)
			(end 0.5 -0.25)
			(stroke
				(width 0.15)
				(type solid)
			)
			(fill no)
			(layer "B.Fab")
		)
		(fp_text user "License: Apache-2.0"
			(at -0.95 -5.169 270)
			(layer "B.Fab")
			(effects
				(font
					(size 0.7 0.7)
					(thickness 0.15)
				)
				(justify left bottom mirror)
			)
		)
		(fp_text user "${REFERENCE}"
			(at -0.95 -3.168 270)
			(layer "B.Fab")
			(effects
				(font
					(size 0.7 0.7)
					(thickness 0.15)
				)
				(justify left bottom mirror)
			)
		)
		(fp_text user "Author: Antmicro"
			(at -0.95 -4.169 270)
			(layer "B.Fab")
			(effects
				(font
					(size 0.7 0.7)
					(thickness 0.15)
				)
				(justify left bottom mirror)
			)
		)
		(pad "1" smd roundrect
			(at -0.48 0 90)
			(size 0.59 0.64)
			(layers "B.Cu" "B.Mask" "B.Paste")
			(roundrect_rratio 0.25)
			(net 1 "GND")
			(pintype "passive")
		)
		(pad "2" smd roundrect
			(at 0.48 0 90)
			(size 0.59 0.64)
			(layers "B.Cu" "B.Mask" "B.Paste")
			(roundrect_rratio 0.25)
			(net 716 "/Supply/DC-DC AUX, MGT/FB3")
			(pintype "passive")
		)
	)
	(footprint "antmicro-footprints:C_0402_1005Metric_EIA"
		(layer "B.Cu")
		(at 193 150.5 90)
		(descr "Capacitor SMD 0402 (1005 Metric), square (rectangular) end terminal, IPC_7351 nominal, (Body size source: IPC-SM-782 page 76, https://www.pcb-3d.com/wordpress/wp-content/uploads/ipc-sm-782a_amendment_1_and_2.pdf)")
		(tags "capacitor 0402")
		(property "Reference" "C59"
			(at 9.8 -30.675 90)
			(layer "B.SilkS")
			(effects
				(font
					(size 0.7 0.7)
					(thickness 0.15)
				)
				(justify right bottom mirror)
			)
		)
		(property "Value" "C_1u_25V_0402"
			(at 0 -1.169 90)
			(layer "B.Fab")
			(effects
				(font
					(size 0.7 0.7)
					(thickness 0.15)
				)
				(justify right bottom mirror)
			)
		)
		(property "Datasheet" "https://www.murata.com/products/productdetail?partno=GRM155R61E105KE11%23"
			(at 0 0 90)
			(layer "F.Fab")
			(hide yes)
			(effects
				(font
					(size 1.27 1.27)
					(thickness 0.15)
				)
			)
		)
		(property "MPN" "GRM155R61E105KE11J"
			(at 0 0 90)
			(unlocked yes)
			(layer "B.Fab")
			(hide yes)
			(effects
				(font
					(size 1 1)
					(thickness 0.15)
				)
				(justify mirror)
			)
		)
		(property "Manufacturer" "Murata"
			(at 0 0 90)
			(unlocked yes)
			(layer "B.Fab")
			(hide yes)
			(effects
				(font
					(size 1 1)
					(thickness 0.15)
				)
				(justify mirror)
			)
		)
		(property "License" "Apache-2.0"
			(at 0 0 90)
			(unlocked yes)
			(layer "B.Fab")
			(hide yes)
			(effects
				(font
					(size 1 1)
					(thickness 0.15)
				)
				(justify mirror)
			)
		)
		(property "Author" "Antmicro"
			(at 0 0 90)
			(unlocked yes)
			(layer "B.Fab")
			(hide yes)
			(effects
				(font
					(size 1 1)
					(thickness 0.15)
				)
				(justify mirror)
			)
		)
		(property "Val" "1u"
			(at 0 0 90)
			(unlocked yes)
			(layer "B.Fab")
			(hide yes)
			(effects
				(font
					(size 1 1)
					(thickness 0.15)
				)
				(justify mirror)
			)
		)
		(property "Voltage" "25V"
			(at 0 0 90)
			(unlocked yes)
			(layer "B.Fab")
			(hide yes)
			(effects
				(font
					(size 1 1)
					(thickness 0.15)
				)
				(justify mirror)
			)
		)
		(property "Dielectric" "X5R"
			(at 0 0 90)
			(unlocked yes)
			(layer "B.Fab")
			(hide yes)
			(effects
				(font
					(size 1 1)
					(thickness 0.15)
				)
				(justify mirror)
			)
		)
		(sheetname "/FPGA power/")
		(sheetfile "fpga-power.kicad_sch")
		(attr smd)
		(fp_rect
			(start -0.95 0.45)
			(end 0.95 -0.45)
			(stroke
				(width 0.05)
				(type default)
			)
			(fill no)
			(layer "B.CrtYd")
		)
		(fp_line
			(start 0.498 -0.248)
			(end -0.5 -0.248)
			(stroke
				(width 0.15)
				(type solid)
			)
			(layer "B.Fab")
		)
		(fp_line
			(start -0.5 -0.248)
			(end -0.5 0.25)
			(stroke
				(width 0.15)
				(type solid)
			)
			(layer "B.Fab")
		)
		(fp_line
			(start 0.498 0.25)
			(end 0.498 -0.248)
			(stroke
				(width 0.15)
				(type solid)
			)
			(layer "B.Fab")
		)
		(fp_line
			(start -0.5 0.25)
			(end 0.498 0.25)
			(stroke
				(width 0.15)
				(type solid)
			)
			(layer "B.Fab")
		)
		(fp_text user "Author: Antmicro"
			(at -0.9656 -5.569 270)
			(layer "B.Fab")
			(effects
				(font
					(size 0.7 0.7)
					(thickness 0.15)
				)
				(justify left bottom mirror)
			)
		)
		(fp_text user "${REFERENCE}"
			(at -0.9656 -3.169 270)
			(layer "B.Fab")
			(effects
				(font
					(size 0.7 0.7)
					(thickness 0.15)
				)
				(justify left bottom mirror)
			)
		)
		(fp_text user "License: Apache-2.0"
			(at -0.9656 -4.369 270)
			(layer "B.Fab")
			(effects
				(font
					(size 0.7 0.7)
					(thickness 0.15)
				)
				(justify left bottom mirror)
			)
		)
		(pad "1" smd roundrect
			(at -0.5 0)
			(size 0.6 0.6)
			(layers "B.Cu" "B.Mask" "B.Paste")
			(roundrect_rratio 0.25)
			(net 1 "GND")
			(pintype "passive")
		)
		(pad "2" smd roundrect
			(at 0.498 0 90)
			(size 0.6 0.6)
			(layers "B.Cu" "B.Mask" "B.Paste")
			(roundrect_rratio 0.25)
			(net 553 "+0V85")
			(pintype "passive")
		)
	)
	(footprint "antmicro-footprints:C_0805_2012Metric"
		(layer "B.Cu")
		(at 219.315001 187.679999)
		(descr "Capacitor SMD 0805")
		(tags "capacitor SMD 0805")
		(property "Reference" "C177"
			(at 2.134999 1.120001 0)
			(layer "B.SilkS")
			(effects
				(font
					(size 0.7 0.7)
					(thickness 0.15)
				)
				(justify right bottom mirror)
			)
		)
		(property "Value" "C_22u_25V_0805"
			(at -2.055717 -1.963152 0)
			(layer "B.Fab")
			(effects
				(font
					(size 0.7 0.7)
					(thickness 0.15)
				)
				(justify right bottom mirror)
			)
		)
		(property "Datasheet" "https://product.samsungsem.com/mlcc/CL21A226MAYNNN.do"
			(at 0 0 0)
			(layer "F.Fab")
			(hide yes)
			(effects
				(font
					(size 1.27 1.27)
					(thickness 0.15)
				)
			)
		)
		(property "MPN" "CL21A226MAYNNNE"
			(at 0 0 0)
			(unlocked yes)
			(layer "B.Fab")
			(hide yes)
			(effects
				(font
					(size 1 1)
					(thickness 0.15)
				)
				(justify mirror)
			)
		)
		(property "Manufacturer" "Samsung Electro-Mechanics"
			(at 0 0 0)
			(unlocked yes)
			(layer "B.Fab")
			(hide yes)
			(effects
				(font
					(size 1 1)
					(thickness 0.15)
				)
				(justify mirror)
			)
		)
		(property "License" "Apache-2.0"
			(at 0 0 0)
			(unlocked yes)
			(layer "B.Fab")
			(hide yes)
			(effects
				(font
					(size 1 1)
					(thickness 0.15)
				)
				(justify mirror)
			)
		)
		(property "Author" "Antmicro"
			(at 0 0 0)
			(unlocked yes)
			(layer "B.Fab")
			(hide yes)
			(effects
				(font
					(size 1 1)
					(thickness 0.15)
				)
				(justify mirror)
			)
		)
		(property "Val" "22u"
			(at 0 0 0)
			(unlocked yes)
			(layer "B.Fab")
			(hide yes)
			(effects
				(font
					(size 1 1)
					(thickness 0.15)
				)
				(justify mirror)
			)
		)
		(property "Voltage" "25V"
			(at 0 0 0)
			(unlocked yes)
			(layer "B.Fab")
			(hide yes)
			(effects
				(font
					(size 1 1)
					(thickness 0.15)
				)
				(justify mirror)
			)
		)
		(property "Dielectric" "X5R"
			(at 0 0 0)
			(unlocked yes)
			(layer "B.Fab")
			(hide yes)
			(effects
				(font
					(size 1 1)
					(thickness 0.15)
				)
				(justify mirror)
			)
		)
		(property "Public" "False"
			(at 0 0 0)
			(unlocked yes)
			(layer "B.Fab")
			(hide yes)
			(effects
				(font
					(size 1 1)
					(thickness 0.15)
				)
				(justify mirror)
			)
		)
		(sheetname "/Supply/DC-DC VCCINT/")
		(sheetfile "dc-dc-vccint.kicad_sch")
		(attr smd)
		(fp_line
			(start -0.3 -0.7)
			(end 0.3 -0.7)
			(stroke
				(width 0.15)
				(type solid)
			)
			(layer "B.SilkS")
		)
		(fp_line
			(start -0.3 0.7)
			(end 0.3 0.7)
			(stroke
				(width 0.15)
				(type solid)
			)
			(layer "B.SilkS")
		)
		(fp_rect
			(start 1.95 0.9)
			(end -1.95 -0.9)
			(stroke
				(width 0.05)
				(type default)
			)
			(fill no)
			(layer "B.CrtYd")
		)
		(fp_rect
			(start -0.95 0.675)
			(end 0.95 -0.675)
			(stroke
				(width 0.15)
				(type solid)
			)
			(fill no)
			(layer "B.Fab")
		)
		(fp_text user "License: Apache-2.0"
			(at -1.9 -4.947 180)
			(layer "B.Fab")
			(effects
				(font
					(size 0.7 0.7)
					(thickness 0.15)
				)
				(justify left bottom mirror)
			)
		)
		(fp_text user "${REFERENCE}"
			(at -1.9 -3.947 180)
			(layer "B.Fab")
			(effects
				(font
					(size 0.7 0.7)
					(thickness 0.15)
				)
				(justify left bottom mirror)
			)
		)
		(fp_text user "Author: Antmicro"
			(at -1.9 -5.947 180)
			(layer "B.Fab")
			(effects
				(font
					(size 0.7 0.7)
					(thickness 0.15)
				)
				(justify left bottom mirror)
			)
		)
		(pad "1" smd roundrect
			(at -1.1 0)
			(size 1.2 1.3)
			(layers "B.Cu" "B.Mask" "B.Paste")
			(roundrect_rratio 0.25)
			(net 1 "GND")
			(pintype "passive")
		)
		(pad "2" smd roundrect
			(at 1.1 0)
			(size 1.2 1.3)
			(layers "B.Cu" "B.Mask" "B.Paste")
			(roundrect_rratio 0.25)
			(net 35 "VDC")
			(pintype "passive")
		)
	)
	(footprint "antmicro-footprints:C_0402_1005Metric_EIA"
		(layer "B.Cu")
		(at 190 148.498 90)
		(descr "Capacitor SMD 0402 (1005 Metric), square (rectangular) end terminal, IPC_7351 nominal, (Body size source: IPC-SM-782 page 76, https://www.pcb-3d.com/wordpress/wp-content/uploads/ipc-sm-782a_amendment_1_and_2.pdf)")
		(tags "capacitor 0402")
		(property "Reference" "C56"
			(at 9.823 -30.675 90)
			(layer "B.SilkS")
			(effects
				(font
					(size 0.7 0.7)
					(thickness 0.15)
				)
				(justify right bottom mirror)
			)
		)
		(property "Value" "C_1u_25V_0402"
			(at 0 -1.169 90)
			(layer "B.Fab")
			(effects
				(font
					(size 0.7 0.7)
					(thickness 0.15)
				)
				(justify right bottom mirror)
			)
		)
		(property "Datasheet" "https://www.murata.com/products/productdetail?partno=GRM155R61E105KE11%23"
			(at 0 0 90)
			(layer "F.Fab")
			(hide yes)
			(effects
				(font
					(size 1.27 1.27)
					(thickness 0.15)
				)
			)
		)
		(property "MPN" "GRM155R61E105KE11J"
			(at 0 0 90)
			(unlocked yes)
			(layer "B.Fab")
			(hide yes)
			(effects
				(font
					(size 1 1)
					(thickness 0.15)
				)
				(justify mirror)
			)
		)
		(property "Manufacturer" "Murata"
			(at 0 0 90)
			(unlocked yes)
			(layer "B.Fab")
			(hide yes)
			(effects
				(font
					(size 1 1)
					(thickness 0.15)
				)
				(justify mirror)
			)
		)
		(property "License" "Apache-2.0"
			(at 0 0 90)
			(unlocked yes)
			(layer "B.Fab")
			(hide yes)
			(effects
				(font
					(size 1 1)
					(thickness 0.15)
				)
				(justify mirror)
			)
		)
		(property "Author" "Antmicro"
			(at 0 0 90)
			(unlocked yes)
			(layer "B.Fab")
			(hide yes)
			(effects
				(font
					(size 1 1)
					(thickness 0.15)
				)
				(justify mirror)
			)
		)
		(property "Val" "1u"
			(at 0 0 90)
			(unlocked yes)
			(layer "B.Fab")
			(hide yes)
			(effects
				(font
					(size 1 1)
					(thickness 0.15)
				)
				(justify mirror)
			)
		)
		(property "Voltage" "25V"
			(at 0 0 90)
			(unlocked yes)
			(layer "B.Fab")
			(hide yes)
			(effects
				(font
					(size 1 1)
					(thickness 0.15)
				)
				(justify mirror)
			)
		)
		(property "Dielectric" "X5R"
			(at 0 0 90)
			(unlocked yes)
			(layer "B.Fab")
			(hide yes)
			(effects
				(font
					(size 1 1)
					(thickness 0.15)
				)
				(justify mirror)
			)
		)
		(sheetname "/FPGA power/")
		(sheetfile "fpga-power.kicad_sch")
		(attr smd)
		(fp_rect
			(start -0.95 0.45)
			(end 0.95 -0.45)
			(stroke
				(width 0.05)
				(type default)
			)
			(fill no)
			(layer "B.CrtYd")
		)
		(fp_line
			(start 0.498 -0.248)
			(end -0.5 -0.248)
			(stroke
				(width 0.15)
				(type solid)
			)
			(layer "B.Fab")
		)
		(fp_line
			(start -0.5 -0.248)
			(end -0.5 0.25)
			(stroke
				(width 0.15)
				(type solid)
			)
			(layer "B.Fab")
		)
		(fp_line
			(start 0.498 0.25)
			(end 0.498 -0.248)
			(stroke
				(width 0.15)
				(type solid)
			)
			(layer "B.Fab")
		)
		(fp_line
			(start -0.5 0.25)
			(end 0.498 0.25)
			(stroke
				(width 0.15)
				(type solid)
			)
			(layer "B.Fab")
		)
		(fp_text user "Author: Antmicro"
			(at -0.9656 -5.569 270)
			(layer "B.Fab")
			(effects
				(font
					(size 0.7 0.7)
					(thickness 0.15)
				)
				(justify left bottom mirror)
			)
		)
		(fp_text user "${REFERENCE}"
			(at -0.9656 -3.169 270)
			(layer "B.Fab")
			(effects
				(font
					(size 0.7 0.7)
					(thickness 0.15)
				)
				(justify left bottom mirror)
			)
		)
		(fp_text user "License: Apache-2.0"
			(at -0.9656 -4.369 270)
			(layer "B.Fab")
			(effects
				(font
					(size 0.7 0.7)
					(thickness 0.15)
				)
				(justify left bottom mirror)
			)
		)
		(pad "1" smd roundrect
			(at -0.5 0)
			(size 0.6 0.6)
			(layers "B.Cu" "B.Mask" "B.Paste")
			(roundrect_rratio 0.25)
			(net 1 "GND")
			(pintype "passive")
		)
		(pad "2" smd roundrect
			(at 0.498 0 90)
			(size 0.6 0.6)
			(layers "B.Cu" "B.Mask" "B.Paste")
			(roundrect_rratio 0.25)
			(net 553 "+0V85")
			(pintype "passive")
		)
	)
	(footprint "antmicro-footprints:C_0402_1005Metric"
		(layer "B.Cu")
		(at 186.672499 193.2285 -90)
		(descr "Capacitor SMD 0402")
		(tags "capacitor SMD 0402")
		(property "Reference" "C250"
			(at -3.8725 -0.372002 90)
			(layer "B.SilkS")
			(effects
				(font
					(size 0.7 0.7)
					(thickness 0.15)
				)
				(justify left bottom mirror)
			)
		)
		(property "Value" "C_100n_0402"
			(at -1.022927 -2.155213 90)
			(layer "B.Fab")
			(effects
				(font
					(size 0.7 0.7)
					(thickness 0.15)
				)
				(justify left bottom mirror)
			)
		)
		(property "Datasheet" "https://www.murata.com/products/productdetail?partno=GRM155R61H104KE14%23"
			(at 0 0 270)
			(layer "F.Fab")
			(hide yes)
			(effects
				(font
					(size 1.27 1.27)
					(thickness 0.15)
				)
			)
		)
		(property "Manufacturer" "Murata"
			(at 0 0 270)
			(unlocked yes)
			(layer "B.Fab")
			(hide yes)
			(effects
				(font
					(size 1 1)
					(thickness 0.15)
				)
				(justify mirror)
			)
		)
		(property "MPN" "GRM155R61H104KE14D"
			(at 0 0 270)
			(unlocked yes)
			(layer "B.Fab")
			(hide yes)
			(effects
				(font
					(size 1 1)
					(thickness 0.15)
				)
				(justify mirror)
			)
		)
		(property "Val" "100n"
			(at 0 0 270)
			(unlocked yes)
			(layer "B.Fab")
			(hide yes)
			(effects
				(font
					(size 1 1)
					(thickness 0.15)
				)
				(justify mirror)
			)
		)
		(property "License" "Apache-2.0"
			(at 0 0 270)
			(unlocked yes)
			(layer "B.Fab")
			(hide yes)
			(effects
				(font
					(size 1 1)
					(thickness 0.15)
				)
				(justify mirror)
			)
		)
		(property "Author" "Antmicro"
			(at 0 0 270)
			(unlocked yes)
			(layer "B.Fab")
			(hide yes)
			(effects
				(font
					(size 1 1)
					(thickness 0.15)
				)
				(justify mirror)
			)
		)
		(property "Voltage" "50V"
			(at 0 0 270)
			(unlocked yes)
			(layer "B.Fab")
			(hide yes)
			(effects
				(font
					(size 1 1)
					(thickness 0.15)
				)
				(justify mirror)
			)
		)
		(property "Dielectric" "X5R"
			(at 0 0 270)
			(unlocked yes)
			(layer "B.Fab")
			(hide yes)
			(effects
				(font
					(size 1 1)
					(thickness 0.15)
				)
				(justify mirror)
			)
		)
		(sheetname "/FPGA MGT Interface/")
		(sheetfile "fpga-mgt.kicad_sch")
		(attr smd)
		(fp_rect
			(start -0.925 0.47)
			(end 0.925 -0.47)
			(stroke
				(width 0.05)
				(type default)
			)
			(fill no)
			(layer "B.CrtYd")
		)
		(fp_line
			(start -0.494 0.25)
			(end 0.504 0.25)
			(stroke
				(width 0.15)
				(type solid)
			)
			(layer "B.Fab")
		)
		(fp_line
			(start 0.504 0.25)
			(end 0.504 -0.248)
			(stroke
				(width 0.15)
				(type solid)
			)
			(layer "B.Fab")
		)
		(fp_line
			(start -0.494 -0.248)
			(end -0.494 0.25)
			(stroke
				(width 0.15)
				(type solid)
			)
			(layer "B.Fab")
		)
		(fp_line
			(start 0.504 -0.248)
			(end -0.494 -0.248)
			(stroke
				(width 0.15)
				(type solid)
			)
			(layer "B.Fab")
		)
		(fp_text user "License: Apache-2.0"
			(at -0.939 -5.799 90)
			(layer "B.Fab")
			(effects
				(font
					(size 0.7 0.7)
					(thickness 0.15)
				)
				(justify left bottom mirror)
			)
		)
		(fp_text user "Author: Antmicro"
			(at -0.939 -3.399 90)
			(layer "B.Fab")
			(effects
				(font
					(size 0.7 0.7)
					(thickness 0.15)
				)
				(justify left bottom mirror)
			)
		)
		(fp_text user "${REFERENCE}"
			(at -0.939 -4.599 90)
			(layer "B.Fab")
			(effects
				(font
					(size 0.7 0.7)
					(thickness 0.15)
				)
				(justify left bottom mirror)
			)
		)
		(pad "1" smd roundrect
			(at -0.48 0 270)
			(size 0.59 0.64)
			(layers "B.Cu" "B.Mask" "B.Paste")
			(roundrect_rratio 0.25)
			(net 470 "/FPGA MGT Interface/GTY_224_TX2_N")
			(pintype "passive")
		)
		(pad "2" smd roundrect
			(at 0.48 0 270)
			(size 0.59 0.64)
			(layers "B.Cu" "B.Mask" "B.Paste")
			(roundrect_rratio 0.25)
			(net 252 "/FPGA MGT Interface/PCIE.TXD5_N")
			(pintype "passive")
		)
	)
	(footprint "antmicro-footprints:R_0402_1005Metric_EIA"
		(layer "B.Cu")
		(at 184.5 146 180)
		(descr "Resistor SMD 0402 (1005 Metric), square (rectangular) end terminal, IPC_7351 nominal, (Body size source: IPC-SM-782 page 76, https://www.pcb-3d.com/wordpress/wp-content/uploads/ipc-sm-782a_amendment_1_and_2.pdf)")
		(tags "resistor 0402")
		(property "Reference" "R131"
			(at 0.9 -0.3 0)
			(layer "B.SilkS")
			(effects
				(font
					(size 0.7 0.7)
					(thickness 0.15)
				)
				(justify left bottom mirror)
			)
		)
		(property "Value" "R_1k_0402"
			(at 0 -1.169 0)
			(layer "B.Fab")
			(effects
				(font
					(size 0.7 0.7)
					(thickness 0.15)
				)
				(justify left bottom mirror)
			)
		)
		(property "Datasheet" "https://www.bourns.com/docs/product-datasheets/cr.pdf"
			(at 0 0 0)
			(layer "F.Fab")
			(hide yes)
			(effects
				(font
					(size 1.27 1.27)
					(thickness 0.15)
				)
			)
		)
		(property "MPN" "CR0402-FX-1001GLF"
			(at 0 0 180)
			(unlocked yes)
			(layer "B.Fab")
			(hide yes)
			(effects
				(font
					(size 1 1)
					(thickness 0.15)
				)
				(justify mirror)
			)
		)
		(property "Manufacturer" "Bourns"
			(at 0 0 180)
			(unlocked yes)
			(layer "B.Fab")
			(hide yes)
			(effects
				(font
					(size 1 1)
					(thickness 0.15)
				)
				(justify mirror)
			)
		)
		(property "License" "Apache-2.0"
			(at 0 0 180)
			(unlocked yes)
			(layer "B.Fab")
			(hide yes)
			(effects
				(font
					(size 1 1)
					(thickness 0.15)
				)
				(justify mirror)
			)
		)
		(property "Author" "Antmicro"
			(at 0 0 180)
			(unlocked yes)
			(layer "B.Fab")
			(hide yes)
			(effects
				(font
					(size 1 1)
					(thickness 0.15)
				)
				(justify mirror)
			)
		)
		(property "Val" "1k"
			(at 0 0 180)
			(unlocked yes)
			(layer "B.Fab")
			(hide yes)
			(effects
				(font
					(size 1 1)
					(thickness 0.15)
				)
				(justify mirror)
			)
		)
		(property "Tolerance" "1%"
			(at 0 0 180)
			(unlocked yes)
			(layer "B.Fab")
			(hide yes)
			(effects
				(font
					(size 1 1)
					(thickness 0.15)
				)
				(justify mirror)
			)
		)
		(sheetname "/FPGA banks HP/")
		(sheetfile "fpga-hp-banks.kicad_sch")
		(attr smd exclude_from_bom dnp)
		(fp_rect
			(start -0.95 0.45)
			(end 0.95 -0.45)
			(stroke
				(width 0.05)
				(type default)
			)
			(fill no)
			(layer "B.CrtYd")
		)
		(fp_line
			(start 0.499 0.25)
			(end 0.499 -0.249)
			(stroke
				(width 0.15)
				(type solid)
			)
			(layer "B.Fab")
		)
		(fp_line
			(start 0.499 -0.249)
			(end -0.5 -0.249)
			(stroke
				(width 0.15)
				(type solid)
			)
			(layer "B.Fab")
		)
		(fp_line
			(start -0.5 0.25)
			(end 0.499 0.25)
			(stroke
				(width 0.15)
				(type solid)
			)
			(layer "B.Fab")
		)
		(fp_line
			(start -0.5 -0.249)
			(end -0.5 0.25)
			(stroke
				(width 0.15)
				(type solid)
			)
			(layer "B.Fab")
		)
		(fp_text user "License: Apache-2.0"
			(at -0.95 -4.369 0)
			(layer "B.Fab")
			(effects
				(font
					(size 0.7 0.7)
					(thickness 0.15)
				)
				(justify left bottom mirror)
			)
		)
		(fp_text user "Author: Antmicro"
			(at -0.95 -5.569 0)
			(layer "B.Fab")
			(effects
				(font
					(size 0.7 0.7)
					(thickness 0.15)
				)
				(justify left bottom mirror)
			)
		)
		(fp_text user "${REFERENCE}"
			(at -0.95 -3.169 0)
			(layer "B.Fab")
			(effects
				(font
					(size 0.7 0.7)
					(thickness 0.15)
				)
				(justify left bottom mirror)
			)
		)
		(pad "1" smd roundrect
			(at -0.5 0 90)
			(size 0.6 0.6)
			(layers "B.Cu" "B.Mask" "B.Paste")
			(roundrect_rratio 0.25)
			(net 1 "GND")
			(pintype "passive")
		)
		(pad "2" smd roundrect
			(at 0.499 0 180)
			(size 0.6 0.6)
			(layers "B.Cu" "B.Mask" "B.Paste")
			(roundrect_rratio 0.25)
			(net 545 "/FPGA banks HP/VREF_66")
			(pintype "passive")
		)
	)
	(footprint "antmicro-footprints:C_0402_1005Metric"
		(layer "B.Cu")
		(at 185.49 167.45 90)
		(descr "Capacitor SMD 0402")
		(tags "capacitor SMD 0402")
		(property "Reference" "C290"
			(at -4 0.401999 90)
			(layer "B.SilkS")
			(effects
				(font
					(size 0.7 0.7)
					(thickness 0.15)
				)
				(justify right bottom mirror)
			)
		)
		(property "Value" "C_100n_0402"
			(at -1.022927 -2.155213 90)
			(layer "B.Fab")
			(effects
				(font
					(size 0.7 0.7)
					(thickness 0.15)
				)
				(justify right bottom mirror)
			)
		)
		(property "Datasheet" "https://www.murata.com/products/productdetail?partno=GRM155R61H104KE14%23"
			(at 0 0 90)
			(layer "F.Fab")
			(hide yes)
			(effects
				(font
					(size 1.27 1.27)
					(thickness 0.15)
				)
			)
		)
		(property "Manufacturer" "Murata"
			(at 0 0 90)
			(unlocked yes)
			(layer "B.Fab")
			(hide yes)
			(effects
				(font
					(size 1 1)
					(thickness 0.15)
				)
				(justify mirror)
			)
		)
		(property "MPN" "GRM155R61H104KE14D"
			(at 0 0 90)
			(unlocked yes)
			(layer "B.Fab")
			(hide yes)
			(effects
				(font
					(size 1 1)
					(thickness 0.15)
				)
				(justify mirror)
			)
		)
		(property "Val" "100n"
			(at 0 0 90)
			(unlocked yes)
			(layer "B.Fab")
			(hide yes)
			(effects
				(font
					(size 1 1)
					(thickness 0.15)
				)
				(justify mirror)
			)
		)
		(property "License" "Apache-2.0"
			(at 0 0 90)
			(unlocked yes)
			(layer "B.Fab")
			(hide yes)
			(effects
				(font
					(size 1 1)
					(thickness 0.15)
				)
				(justify mirror)
			)
		)
		(property "Author" "Antmicro"
			(at 0 0 90)
			(unlocked yes)
			(layer "B.Fab")
			(hide yes)
			(effects
				(font
					(size 1 1)
					(thickness 0.15)
				)
				(justify mirror)
			)
		)
		(property "Voltage" "50V"
			(at 0 0 90)
			(unlocked yes)
			(layer "B.Fab")
			(hide yes)
			(effects
				(font
					(size 1 1)
					(thickness 0.15)
				)
				(justify mirror)
			)
		)
		(property "Dielectric" "X5R"
			(at 0 0 90)
			(unlocked yes)
			(layer "B.Fab")
			(hide yes)
			(effects
				(font
					(size 1 1)
					(thickness 0.15)
				)
				(justify mirror)
			)
		)
		(sheetname "/FPGA MGT Interface/")
		(sheetfile "fpga-mgt.kicad_sch")
		(attr smd)
		(fp_rect
			(start -0.925 0.47)
			(end 0.925 -0.47)
			(stroke
				(width 0.05)
				(type default)
			)
			(fill no)
			(layer "B.CrtYd")
		)
		(fp_line
			(start 0.504 -0.248)
			(end -0.494 -0.248)
			(stroke
				(width 0.15)
				(type solid)
			)
			(layer "B.Fab")
		)
		(fp_line
			(start -0.494 -0.248)
			(end -0.494 0.25)
			(stroke
				(width 0.15)
				(type solid)
			)
			(layer "B.Fab")
		)
		(fp_line
			(start 0.504 0.25)
			(end 0.504 -0.248)
			(stroke
				(width 0.15)
				(type solid)
			)
			(layer "B.Fab")
		)
		(fp_line
			(start -0.494 0.25)
			(end 0.504 0.25)
			(stroke
				(width 0.15)
				(type solid)
			)
			(layer "B.Fab")
		)
		(fp_text user "Author: Antmicro"
			(at -0.939 -3.399 270)
			(layer "B.Fab")
			(effects
				(font
					(size 0.7 0.7)
					(thickness 0.15)
				)
				(justify left bottom mirror)
			)
		)
		(fp_text user "License: Apache-2.0"
			(at -0.939 -5.799 270)
			(layer "B.Fab")
			(effects
				(font
					(size 0.7 0.7)
					(thickness 0.15)
				)
				(justify left bottom mirror)
			)
		)
		(fp_text user "${REFERENCE}"
			(at -0.939 -4.599 270)
			(layer "B.Fab")
			(effects
				(font
					(size 0.7 0.7)
					(thickness 0.15)
				)
				(justify left bottom mirror)
			)
		)
		(pad "1" smd roundrect
			(at -0.48 0 90)
			(size 0.59 0.64)
			(layers "B.Cu" "B.Mask" "B.Paste")
			(roundrect_rratio 0.25)
			(net 290 "/FPGA MGT Interface/HDMI_OUT.D1_N")
			(pintype "passive")
		)
		(pad "2" smd roundrect
			(at 0.48 0 90)
			(size 0.59 0.64)
			(layers "B.Cu" "B.Mask" "B.Paste")
			(roundrect_rratio 0.25)
			(net 629 "/FPGA MGT Interface/HDMI_FPGA.TX1_N")
			(pintype "passive")
		)
	)
	(footprint "antmicro-footprints:C_0402_1005Metric_EIA"
		(layer "B.Cu")
		(at 193 154.5 -90)
		(descr "Capacitor SMD 0402 (1005 Metric), square (rectangular) end terminal, IPC_7351 nominal, (Body size source: IPC-SM-782 page 76, https://www.pcb-3d.com/wordpress/wp-content/uploads/ipc-sm-782a_amendment_1_and_2.pdf)")
		(tags "capacitor 0402")
		(property "Reference" "C247"
			(at -12.825 30.625 90)
			(layer "B.SilkS")
			(effects
				(font
					(size 0.7 0.7)
					(thickness 0.15)
				)
				(justify left bottom mirror)
			)
		)
		(property "Value" "C_1u_25V_0402"
			(at 0 -1.169 90)
			(layer "B.Fab")
			(effects
				(font
					(size 0.7 0.7)
					(thickness 0.15)
				)
				(justify left bottom mirror)
			)
		)
		(property "Datasheet" "https://www.murata.com/products/productdetail?partno=GRM155R61E105KE11%23"
			(at 0 0 270)
			(layer "F.Fab")
			(hide yes)
			(effects
				(font
					(size 1.27 1.27)
					(thickness 0.15)
				)
			)
		)
		(property "MPN" "GRM155R61E105KE11J"
			(at 0 0 270)
			(unlocked yes)
			(layer "B.Fab")
			(hide yes)
			(effects
				(font
					(size 1 1)
					(thickness 0.15)
				)
				(justify mirror)
			)
		)
		(property "Manufacturer" "Murata"
			(at 0 0 270)
			(unlocked yes)
			(layer "B.Fab")
			(hide yes)
			(effects
				(font
					(size 1 1)
					(thickness 0.15)
				)
				(justify mirror)
			)
		)
		(property "License" "Apache-2.0"
			(at 0 0 270)
			(unlocked yes)
			(layer "B.Fab")
			(hide yes)
			(effects
				(font
					(size 1 1)
					(thickness 0.15)
				)
				(justify mirror)
			)
		)
		(property "Author" "Antmicro"
			(at 0 0 270)
			(unlocked yes)
			(layer "B.Fab")
			(hide yes)
			(effects
				(font
					(size 1 1)
					(thickness 0.15)
				)
				(justify mirror)
			)
		)
		(property "Val" "1u"
			(at 0 0 270)
			(unlocked yes)
			(layer "B.Fab")
			(hide yes)
			(effects
				(font
					(size 1 1)
					(thickness 0.15)
				)
				(justify mirror)
			)
		)
		(property "Voltage" "25V"
			(at 0 0 270)
			(unlocked yes)
			(layer "B.Fab")
			(hide yes)
			(effects
				(font
					(size 1 1)
					(thickness 0.15)
				)
				(justify mirror)
			)
		)
		(property "Dielectric" "X5R"
			(at 0 0 270)
			(unlocked yes)
			(layer "B.Fab")
			(hide yes)
			(effects
				(font
					(size 1 1)
					(thickness 0.15)
				)
				(justify mirror)
			)
		)
		(sheetname "/FPGA power/")
		(sheetfile "fpga-power.kicad_sch")
		(attr smd)
		(fp_rect
			(start -0.95 0.45)
			(end 0.95 -0.45)
			(stroke
				(width 0.05)
				(type default)
			)
			(fill no)
			(layer "B.CrtYd")
		)
		(fp_line
			(start -0.5 0.25)
			(end 0.498 0.25)
			(stroke
				(width 0.15)
				(type solid)
			)
			(layer "B.Fab")
		)
		(fp_line
			(start 0.498 0.25)
			(end 0.498 -0.248)
			(stroke
				(width 0.15)
				(type solid)
			)
			(layer "B.Fab")
		)
		(fp_line
			(start -0.5 -0.248)
			(end -0.5 0.25)
			(stroke
				(width 0.15)
				(type solid)
			)
			(layer "B.Fab")
		)
		(fp_line
			(start 0.498 -0.248)
			(end -0.5 -0.248)
			(stroke
				(width 0.15)
				(type solid)
			)
			(layer "B.Fab")
		)
		(fp_text user "${REFERENCE}"
			(at -0.9656 -3.169 90)
			(layer "B.Fab")
			(effects
				(font
					(size 0.7 0.7)
					(thickness 0.15)
				)
				(justify left bottom mirror)
			)
		)
		(fp_text user "Author: Antmicro"
			(at -0.9656 -5.569 90)
			(layer "B.Fab")
			(effects
				(font
					(size 0.7 0.7)
					(thickness 0.15)
				)
				(justify left bottom mirror)
			)
		)
		(fp_text user "License: Apache-2.0"
			(at -0.9656 -4.369 90)
			(layer "B.Fab")
			(effects
				(font
					(size 0.7 0.7)
					(thickness 0.15)
				)
				(justify left bottom mirror)
			)
		)
		(pad "1" smd roundrect
			(at -0.5 0 180)
			(size 0.6 0.6)
			(layers "B.Cu" "B.Mask" "B.Paste")
			(roundrect_rratio 0.25)
			(net 1 "GND")
			(pintype "passive")
		)
		(pad "2" smd roundrect
			(at 0.498 0 270)
			(size 0.6 0.6)
			(layers "B.Cu" "B.Mask" "B.Paste")
			(roundrect_rratio 0.25)
			(net 553 "+0V85")
			(pintype "passive")
		)
	)
	(footprint "antmicro-footprints:SC70-3"
		(layer "B.Cu")
		(at 254.05 120.275 90)
		(property "Reference" "Q26"
			(at -0.375 -1.4 270)
			(layer "B.SilkS")
			(effects
				(font
					(size 0.7 0.7)
					(thickness 0.15)
				)
				(justify right bottom mirror)
			)
		)
		(property "Value" "BSS138PW"
			(at 0 -2.3 90)
			(layer "B.Fab")
			(effects
				(font
					(size 0.7 0.7)
					(thickness 0.15)
				)
				(justify right bottom mirror)
			)
		)
		(property "Datasheet" "https://assets.nexperia.com/documents/data-sheet/BSS138PW.pdf"
			(at 0 0 90)
			(layer "F.Fab")
			(hide yes)
			(effects
				(font
					(size 1.27 1.27)
					(thickness 0.15)
				)
			)
		)
		(property "MPN" "BSS138PW"
			(at 0 0 90)
			(unlocked yes)
			(layer "B.Fab")
			(hide yes)
			(effects
				(font
					(size 1 1)
					(thickness 0.15)
				)
				(justify mirror)
			)
		)
		(property "Manufacturer" "Nexperia"
			(at 0 0 90)
			(unlocked yes)
			(layer "B.Fab")
			(hide yes)
			(effects
				(font
					(size 1 1)
					(thickness 0.15)
				)
				(justify mirror)
			)
		)
		(property "Author" "Antmicro"
			(at 0 0 90)
			(unlocked yes)
			(layer "B.Fab")
			(hide yes)
			(effects
				(font
					(size 1 1)
					(thickness 0.15)
				)
				(justify mirror)
			)
		)
		(property "License" "Apache-2.0"
			(at 0 0 90)
			(unlocked yes)
			(layer "B.Fab")
			(hide yes)
			(effects
				(font
					(size 1 1)
					(thickness 0.15)
				)
				(justify mirror)
			)
		)
		(sheetname "/DDR5 RDIMM/")
		(sheetfile "ddr5-rdimm.kicad_sch")
		(attr smd)
		(fp_line
			(start -0.3 -1)
			(end 0.627 -1.001)
			(stroke
				(width 0.15)
				(type solid)
			)
			(layer "B.SilkS")
		)
		(fp_line
			(start 0.627 -0.6)
			(end 0.627 -1.001)
			(stroke
				(width 0.15)
				(type solid)
			)
			(layer "B.SilkS")
		)
		(fp_line
			(start 0.627 0.6)
			(end 0.627 0.999)
			(stroke
				(width 0.15)
				(type solid)
			)
			(layer "B.SilkS")
		)
		(fp_line
			(start -0.3 1)
			(end 0.627 0.999)
			(stroke
				(width 0.15)
				(type solid)
			)
			(layer "B.SilkS")
		)
		(fp_line
			(start 0.9 -1.3)
			(end -0.9 -1.3)
			(stroke
				(width 0.05)
				(type solid)
			)
			(layer "B.CrtYd")
		)
		(fp_line
			(start -0.9 -1.3)
			(end -0.9 -1)
			(stroke
				(width 0.05)
				(type solid)
			)
			(layer "B.CrtYd")
		)
		(fp_line
			(start -0.9 -1)
			(end -1.4 -1)
			(stroke
				(width 0.05)
				(type solid)
			)
			(layer "B.CrtYd")
		)
		(fp_line
			(start -1.4 -1)
			(end -1.4 1)
			(stroke
				(width 0.05)
				(type solid)
			)
			(layer "B.CrtYd")
		)
		(fp_line
			(start 1.4 -0.4)
			(end 0.9 -0.4)
			(stroke
				(width 0.05)
				(type solid)
			)
			(layer "B.CrtYd")
		)
		(fp_line
			(start 0.9 -0.4)
			(end 0.9 -1.3)
			(stroke
				(width 0.05)
				(type solid)
			)
			(layer "B.CrtYd")
		)
		(fp_line
			(start 1.4 0.4)
			(end 1.4 -0.4)
			(stroke
				(width 0.05)
				(type solid)
			)
			(layer "B.CrtYd")
		)
		(fp_line
			(start 0.9 0.4)
			(end 1.4 0.4)
			(stroke
				(width 0.05)
				(type solid)
			)
			(layer "B.CrtYd")
		)
		(fp_line
			(start -0.9 1)
			(end -1.4 1)
			(stroke
				(width 0.05)
				(type solid)
			)
			(layer "B.CrtYd")
		)
		(fp_line
			(start 0.9 1.3)
			(end 0.9 0.4)
			(stroke
				(width 0.05)
				(type solid)
			)
			(layer "B.CrtYd")
		)
		(fp_line
			(start -0.9 1.3)
			(end -0.9 1)
			(stroke
				(width 0.05)
				(type solid)
			)
			(layer "B.CrtYd")
		)
		(fp_line
			(start -0.9 1.3)
			(end 0.9 1.3)
			(stroke
				(width 0.05)
				(type solid)
			)
			(layer "B.CrtYd")
		)
		(fp_rect
			(start -0.623 0.999)
			(end 0.627 -1.001)
			(stroke
				(width 0.15)
				(type solid)
			)
			(fill no)
			(layer "B.Fab")
		)
		(fp_text user "License: Apache-2.0"
			(at -1.45 -6.782 270)
			(layer "B.Fab")
			(effects
				(font
					(size 0.7 0.7)
					(thickness 0.15)
				)
				(justify left bottom mirror)
			)
		)
		(fp_text user "Author: Antmicro"
			(at -1.45 -5.782 270)
			(layer "B.Fab")
			(effects
				(font
					(size 0.7 0.7)
					(thickness 0.15)
				)
				(justify left bottom mirror)
			)
		)
		(fp_text user "${REFERENCE}"
			(at -1.45 -4.783 270)
			(layer "B.Fab")
			(effects
				(font
					(size 0.7 0.7)
					(thickness 0.15)
				)
				(justify left bottom mirror)
			)
		)
		(pad "1" smd rect
			(at -1.051 0.65)
			(size 0.6 0.6)
			(layers "B.Cu" "B.Mask" "B.Paste")
			(net 809 "VIN_MGMT_EN")
			(pinfunction "G")
			(pintype "passive")
		)
		(pad "2" smd rect
			(at -1.051 -0.65)
			(size 0.6 0.6)
			(layers "B.Cu" "B.Mask" "B.Paste")
			(net 1 "GND")
			(pinfunction "S")
			(pintype "passive")
		)
		(pad "3" smd rect
			(at 1.05 0)
			(size 0.6 0.6)
			(layers "B.Cu" "B.Mask" "B.Paste")
			(net 807 "Net-(Q26-D)")
			(pinfunction "D")
			(pintype "passive")
		)
	)
	(footprint "antmicro-footprints:C_0402_1005Metric"
		(layer "B.Cu")
		(at 120.411 166.36)
		(descr "Capacitor SMD 0402")
		(tags "capacitor SMD 0402")
		(property "Reference" "C93"
			(at 0.839 0.44 0)
			(layer "B.SilkS")
			(effects
				(font
					(size 0.7 0.7)
					(thickness 0.15)
				)
				(justify right bottom mirror)
			)
		)
		(property "Value" "C_100n_0402"
			(at -1.022927 -2.155213 0)
			(layer "B.Fab")
			(effects
				(font
					(size 0.7 0.7)
					(thickness 0.15)
				)
				(justify right bottom mirror)
			)
		)
		(property "Datasheet" "https://www.murata.com/products/productdetail?partno=GRM155R61H104KE14%23"
			(at 0 0 0)
			(layer "F.Fab")
			(hide yes)
			(effects
				(font
					(size 1.27 1.27)
					(thickness 0.15)
				)
			)
		)
		(property "MPN" "GRM155R61H104KE14D"
			(at 0 0 0)
			(unlocked yes)
			(layer "B.Fab")
			(hide yes)
			(effects
				(font
					(size 1 1)
					(thickness 0.15)
				)
				(justify mirror)
			)
		)
		(property "Manufacturer" "Murata"
			(at 0 0 0)
			(unlocked yes)
			(layer "B.Fab")
			(hide yes)
			(effects
				(font
					(size 1 1)
					(thickness 0.15)
				)
				(justify mirror)
			)
		)
		(property "License" "Apache-2.0"
			(at 0 0 0)
			(unlocked yes)
			(layer "B.Fab")
			(hide yes)
			(effects
				(font
					(size 1 1)
					(thickness 0.15)
				)
				(justify mirror)
			)
		)
		(property "Author" "Antmicro"
			(at 0 0 0)
			(unlocked yes)
			(layer "B.Fab")
			(hide yes)
			(effects
				(font
					(size 1 1)
					(thickness 0.15)
				)
				(justify mirror)
			)
		)
		(property "Val" "100n"
			(at 0 0 0)
			(unlocked yes)
			(layer "B.Fab")
			(hide yes)
			(effects
				(font
					(size 1 1)
					(thickness 0.15)
				)
				(justify mirror)
			)
		)
		(property "Voltage" "50V"
			(at 0 0 0)
			(unlocked yes)
			(layer "B.Fab")
			(hide yes)
			(effects
				(font
					(size 1 1)
					(thickness 0.15)
				)
				(justify mirror)
			)
		)
		(property "Dielectric" "X5R"
			(at 0 0 0)
			(unlocked yes)
			(layer "B.Fab")
			(hide yes)
			(effects
				(font
					(size 1 1)
					(thickness 0.15)
				)
				(justify mirror)
			)
		)
		(property "Public" ""
			(at 0 0 0)
			(unlocked yes)
			(layer "B.Fab")
			(hide yes)
			(effects
				(font
					(size 1 1)
					(thickness 0.15)
				)
				(justify mirror)
			)
		)
		(sheetname "/HDMI + SD Card/")
		(sheetfile "hdmi-sd-card.kicad_sch")
		(attr smd)
		(fp_rect
			(start -0.925 0.47)
			(end 0.925 -0.47)
			(stroke
				(width 0.05)
				(type default)
			)
			(fill no)
			(layer "B.CrtYd")
		)
		(fp_line
			(start -0.494 -0.248)
			(end -0.494 0.25)
			(stroke
				(width 0.15)
				(type solid)
			)
			(layer "B.Fab")
		)
		(fp_line
			(start -0.494 0.25)
			(end 0.504 0.25)
			(stroke
				(width 0.15)
				(type solid)
			)
			(layer "B.Fab")
		)
		(fp_line
			(start 0.504 -0.248)
			(end -0.494 -0.248)
			(stroke
				(width 0.15)
				(type solid)
			)
			(layer "B.Fab")
		)
		(fp_line
			(start 0.504 0.25)
			(end 0.504 -0.248)
			(stroke
				(width 0.15)
				(type solid)
			)
			(layer "B.Fab")
		)
		(fp_text user "${REFERENCE}"
			(at -0.939 -4.599 180)
			(layer "B.Fab")
			(effects
				(font
					(size 0.7 0.7)
					(thickness 0.15)
				)
				(justify left bottom mirror)
			)
		)
		(fp_text user "Author: Antmicro"
			(at -0.939 -3.399 180)
			(layer "B.Fab")
			(effects
				(font
					(size 0.7 0.7)
					(thickness 0.15)
				)
				(justify left bottom mirror)
			)
		)
		(fp_text user "License: Apache-2.0"
			(at -0.939 -5.799 180)
			(layer "B.Fab")
			(effects
				(font
					(size 0.7 0.7)
					(thickness 0.15)
				)
				(justify left bottom mirror)
			)
		)
		(pad "1" smd roundrect
			(at -0.48 0)
			(size 0.59 0.64)
			(layers "B.Cu" "B.Mask" "B.Paste")
			(roundrect_rratio 0.25)
			(net 297 "/HDMI + SD Card/HDMI_IN_5V")
			(pintype "passive")
		)
		(pad "2" smd roundrect
			(at 0.48 0)
			(size 0.59 0.64)
			(layers "B.Cu" "B.Mask" "B.Paste")
			(roundrect_rratio 0.25)
			(net 1 "GND")
			(pintype "passive")
		)
	)
	(footprint "antmicro-footprints:C_0805_2012Metric"
		(layer "B.Cu")
		(at 203.5 162.4 90)
		(descr "Capacitor SMD 0805")
		(tags "capacitor SMD 0805")
		(property "Reference" "C240"
			(at -1.49 2.09 90)
			(layer "B.SilkS")
			(effects
				(font
					(size 0.7 0.7)
					(thickness 0.15)
				)
				(justify right bottom mirror)
			)
		)
		(property "Value" "C_100u_0805"
			(at -2.055717 -1.963152 90)
			(layer "B.Fab")
			(effects
				(font
					(size 0.7 0.7)
					(thickness 0.15)
				)
				(justify right bottom mirror)
			)
		)
		(property "Datasheet" "https://www.murata.com/products/productdetail?partno=GRM21BR60J107ME15%23"
			(at 0 0 90)
			(layer "F.Fab")
			(hide yes)
			(effects
				(font
					(size 1.27 1.27)
					(thickness 0.15)
				)
			)
		)
		(property "MPN" "GRM21BR60J107ME15L"
			(at 0 0 90)
			(unlocked yes)
			(layer "B.Fab")
			(hide yes)
			(effects
				(font
					(size 1 1)
					(thickness 0.15)
				)
				(justify mirror)
			)
		)
		(property "Manufacturer" "Murata"
			(at 0 0 90)
			(unlocked yes)
			(layer "B.Fab")
			(hide yes)
			(effects
				(font
					(size 1 1)
					(thickness 0.15)
				)
				(justify mirror)
			)
		)
		(property "License" "Apache-2.0"
			(at 0 0 90)
			(unlocked yes)
			(layer "B.Fab")
			(hide yes)
			(effects
				(font
					(size 1 1)
					(thickness 0.15)
				)
				(justify mirror)
			)
		)
		(property "Author" "Antmicro"
			(at 0 0 90)
			(unlocked yes)
			(layer "B.Fab")
			(hide yes)
			(effects
				(font
					(size 1 1)
					(thickness 0.15)
				)
				(justify mirror)
			)
		)
		(property "Val" "100u"
			(at 0 0 90)
			(unlocked yes)
			(layer "B.Fab")
			(hide yes)
			(effects
				(font
					(size 1 1)
					(thickness 0.15)
				)
				(justify mirror)
			)
		)
		(property "Voltage" ""
			(at 0 0 90)
			(unlocked yes)
			(layer "B.Fab")
			(hide yes)
			(effects
				(font
					(size 1 1)
					(thickness 0.15)
				)
				(justify mirror)
			)
		)
		(property "Dielectric" ""
			(at 0 0 90)
			(unlocked yes)
			(layer "B.Fab")
			(hide yes)
			(effects
				(font
					(size 1 1)
					(thickness 0.15)
				)
				(justify mirror)
			)
		)
		(property "Public" "False"
			(at 0 0 90)
			(unlocked yes)
			(layer "B.Fab")
			(hide yes)
			(effects
				(font
					(size 1 1)
					(thickness 0.15)
				)
				(justify mirror)
			)
		)
		(sheetname "/FPGA power/")
		(sheetfile "fpga-power.kicad_sch")
		(attr smd)
		(fp_line
			(start -0.3 -0.7)
			(end 0.3 -0.7)
			(stroke
				(width 0.15)
				(type solid)
			)
			(layer "B.SilkS")
		)
		(fp_line
			(start -0.3 0.7)
			(end 0.3 0.7)
			(stroke
				(width 0.15)
				(type solid)
			)
			(layer "B.SilkS")
		)
		(fp_rect
			(start 1.95 0.9)
			(end -1.95 -0.9)
			(stroke
				(width 0.05)
				(type default)
			)
			(fill no)
			(layer "B.CrtYd")
		)
		(fp_rect
			(start -0.95 0.675)
			(end 0.95 -0.675)
			(stroke
				(width 0.15)
				(type solid)
			)
			(fill no)
			(layer "B.Fab")
		)
		(fp_text user "License: Apache-2.0"
			(at -1.9 -4.947 270)
			(layer "B.Fab")
			(effects
				(font
					(size 0.7 0.7)
					(thickness 0.15)
				)
				(justify left bottom mirror)
			)
		)
		(fp_text user "${REFERENCE}"
			(at -1.9 -3.947 270)
			(layer "B.Fab")
			(effects
				(font
					(size 0.7 0.7)
					(thickness 0.15)
				)
				(justify left bottom mirror)
			)
		)
		(fp_text user "Author: Antmicro"
			(at -1.9 -5.947 270)
			(layer "B.Fab")
			(effects
				(font
					(size 0.7 0.7)
					(thickness 0.15)
				)
				(justify left bottom mirror)
			)
		)
		(pad "1" smd roundrect
			(at -1.1 0 90)
			(size 1.2 1.3)
			(layers "B.Cu" "B.Mask" "B.Paste")
			(roundrect_rratio 0.25)
			(net 1 "GND")
			(pintype "passive")
		)
		(pad "2" smd roundrect
			(at 1.1 0 90)
			(size 1.2 1.3)
			(layers "B.Cu" "B.Mask" "B.Paste")
			(roundrect_rratio 0.25)
			(net 553 "+0V85")
			(pintype "passive")
		)
	)
	(footprint "antmicro-footprints:C_0402_1005Metric"
		(layer "B.Cu")
		(at 122.95 150.61)
		(descr "Capacitor SMD 0402")
		(tags "capacitor SMD 0402")
		(property "Reference" "C304"
			(at 2.3 1.242 0)
			(layer "B.SilkS")
			(effects
				(font
					(size 0.7 0.7)
					(thickness 0.15)
				)
				(justify right bottom mirror)
			)
		)
		(property "Value" "C_100n_0402"
			(at -1.022927 -2.155213 0)
			(layer "B.Fab")
			(effects
				(font
					(size 0.7 0.7)
					(thickness 0.15)
				)
				(justify right bottom mirror)
			)
		)
		(property "Datasheet" "https://www.murata.com/products/productdetail?partno=GRM155R61H104KE14%23"
			(at 0 0 0)
			(layer "F.Fab")
			(hide yes)
			(effects
				(font
					(size 1.27 1.27)
					(thickness 0.15)
				)
			)
		)
		(property "Manufacturer" "Murata"
			(at 0 0 0)
			(unlocked yes)
			(layer "B.Fab")
			(hide yes)
			(effects
				(font
					(size 1 1)
					(thickness 0.15)
				)
				(justify mirror)
			)
		)
		(property "MPN" "GRM155R61H104KE14D"
			(at 0 0 0)
			(unlocked yes)
			(layer "B.Fab")
			(hide yes)
			(effects
				(font
					(size 1 1)
					(thickness 0.15)
				)
				(justify mirror)
			)
		)
		(property "Val" "100n"
			(at 0 0 0)
			(unlocked yes)
			(layer "B.Fab")
			(hide yes)
			(effects
				(font
					(size 1 1)
					(thickness 0.15)
				)
				(justify mirror)
			)
		)
		(property "License" "Apache-2.0"
			(at 0 0 0)
			(unlocked yes)
			(layer "B.Fab")
			(hide yes)
			(effects
				(font
					(size 1 1)
					(thickness 0.15)
				)
				(justify mirror)
			)
		)
		(property "Author" "Antmicro"
			(at 0 0 0)
			(unlocked yes)
			(layer "B.Fab")
			(hide yes)
			(effects
				(font
					(size 1 1)
					(thickness 0.15)
				)
				(justify mirror)
			)
		)
		(property "Voltage" "50V"
			(at 0 0 0)
			(unlocked yes)
			(layer "B.Fab")
			(hide yes)
			(effects
				(font
					(size 1 1)
					(thickness 0.15)
				)
				(justify mirror)
			)
		)
		(property "Dielectric" "X5R"
			(at 0 0 0)
			(unlocked yes)
			(layer "B.Fab")
			(hide yes)
			(effects
				(font
					(size 1 1)
					(thickness 0.15)
				)
				(justify mirror)
			)
		)
		(sheetname "/FPGA MGT Interface/")
		(sheetfile "fpga-mgt.kicad_sch")
		(attr smd)
		(fp_rect
			(start -0.925 0.47)
			(end 0.925 -0.47)
			(stroke
				(width 0.05)
				(type default)
			)
			(fill no)
			(layer "B.CrtYd")
		)
		(fp_line
			(start -0.494 -0.248)
			(end -0.494 0.25)
			(stroke
				(width 0.15)
				(type solid)
			)
			(layer "B.Fab")
		)
		(fp_line
			(start -0.494 0.25)
			(end 0.504 0.25)
			(stroke
				(width 0.15)
				(type solid)
			)
			(layer "B.Fab")
		)
		(fp_line
			(start 0.504 -0.248)
			(end -0.494 -0.248)
			(stroke
				(width 0.15)
				(type solid)
			)
			(layer "B.Fab")
		)
		(fp_line
			(start 0.504 0.25)
			(end 0.504 -0.248)
			(stroke
				(width 0.15)
				(type solid)
			)
			(layer "B.Fab")
		)
		(fp_text user "License: Apache-2.0"
			(at -0.939 -5.799 180)
			(layer "B.Fab")
			(effects
				(font
					(size 0.7 0.7)
					(thickness 0.15)
				)
				(justify left bottom mirror)
			)
		)
		(fp_text user "Author: Antmicro"
			(at -0.939 -3.399 180)
			(layer "B.Fab")
			(effects
				(font
					(size 0.7 0.7)
					(thickness 0.15)
				)
				(justify left bottom mirror)
			)
		)
		(fp_text user "${REFERENCE}"
			(at -0.939 -4.599 180)
			(layer "B.Fab")
			(effects
				(font
					(size 0.7 0.7)
					(thickness 0.15)
				)
				(justify left bottom mirror)
			)
		)
		(pad "1" smd roundrect
			(at -0.48 0)
			(size 0.59 0.64)
			(layers "B.Cu" "B.Mask" "B.Paste")
			(roundrect_rratio 0.25)
			(net 346 "/FPGA MGT Interface/HDMI_IN.D1_N")
			(pintype "passive")
		)
		(pad "2" smd roundrect
			(at 0.48 0)
			(size 0.59 0.64)
			(layers "B.Cu" "B.Mask" "B.Paste")
			(roundrect_rratio 0.25)
			(net 650 "/FPGA MGT Interface/HDMI_FPGA.RX1_N")
			(pintype "passive")
		)
	)
	(footprint "antmicro-footprints:R_0402_1005Metric"
		(layer "B.Cu")
		(at 211.91 151.875)
		(descr "Resistor SMD 0402")
		(tags "resistor SMD 0402")
		(property "Reference" "R10"
			(at 0.99 0.485 0)
			(layer "B.SilkS")
			(effects
				(font
					(size 0.7 0.7)
					(thickness 0.15)
				)
				(justify right bottom mirror)
			)
		)
		(property "Value" "R_100R_0402"
			(at -1.011843 -1.772047 0)
			(layer "B.Fab")
			(effects
				(font
					(size 0.7 0.7)
					(thickness 0.15)
				)
				(justify right bottom mirror)
			)
		)
		(property "Datasheet" "https://www.bourns.com/docs/product-datasheets/cr.pdf"
			(at 0 0 0)
			(layer "F.Fab")
			(hide yes)
			(effects
				(font
					(size 1.27 1.27)
					(thickness 0.15)
				)
			)
		)
		(property "Manufacturer" "Bourns"
			(at 0 0 0)
			(unlocked yes)
			(layer "B.Fab")
			(hide yes)
			(effects
				(font
					(size 1 1)
					(thickness 0.15)
				)
				(justify mirror)
			)
		)
		(property "MPN" "CR0402-FX-1000GLF"
			(at 0 0 0)
			(unlocked yes)
			(layer "B.Fab")
			(hide yes)
			(effects
				(font
					(size 1 1)
					(thickness 0.15)
				)
				(justify mirror)
			)
		)
		(property "Val" "100R"
			(at 0 0 0)
			(unlocked yes)
			(layer "B.Fab")
			(hide yes)
			(effects
				(font
					(size 1 1)
					(thickness 0.15)
				)
				(justify mirror)
			)
		)
		(property "License" "Apache-2.0"
			(at 0 0 0)
			(unlocked yes)
			(layer "B.Fab")
			(hide yes)
			(effects
				(font
					(size 1 1)
					(thickness 0.15)
				)
				(justify mirror)
			)
		)
		(property "Author" "Antmicro"
			(at 0 0 0)
			(unlocked yes)
			(layer "B.Fab")
			(hide yes)
			(effects
				(font
					(size 1 1)
					(thickness 0.15)
				)
				(justify mirror)
			)
		)
		(property "Tolerance" "1%"
			(at 0 0 0)
			(unlocked yes)
			(layer "B.Fab")
			(hide yes)
			(effects
				(font
					(size 1 1)
					(thickness 0.15)
				)
				(justify mirror)
			)
		)
		(sheetname "/HyperRAM + QSPI Flash/")
		(sheetfile "hyperram-flash.kicad_sch")
		(attr smd exclude_from_bom dnp)
		(fp_rect
			(start -0.925 0.47)
			(end 0.925 -0.47)
			(stroke
				(width 0.05)
				(type default)
			)
			(fill no)
			(layer "B.CrtYd")
		)
		(fp_rect
			(start -0.5 0.25)
			(end 0.5 -0.25)
			(stroke
				(width 0.15)
				(type solid)
			)
			(fill no)
			(layer "B.Fab")
		)
		(fp_text user "Author: Antmicro"
			(at -0.95 -4.169 180)
			(layer "B.Fab")
			(effects
				(font
					(size 0.7 0.7)
					(thickness 0.15)
				)
				(justify left bottom mirror)
			)
		)
		(fp_text user "${REFERENCE}"
			(at -0.95 -3.168 180)
			(layer "B.Fab")
			(effects
				(font
					(size 0.7 0.7)
					(thickness 0.15)
				)
				(justify left bottom mirror)
			)
		)
		(fp_text user "License: Apache-2.0"
			(at -0.95 -5.169 180)
			(layer "B.Fab")
			(effects
				(font
					(size 0.7 0.7)
					(thickness 0.15)
				)
				(justify left bottom mirror)
			)
		)
		(pad "1" smd roundrect
			(at -0.48 0)
			(size 0.59 0.64)
			(layers "B.Cu" "B.Mask" "B.Paste")
			(roundrect_rratio 0.25)
			(net 355 "/FPGA Config/FLASH.SCK")
			(pintype "passive")
		)
		(pad "2" smd roundrect
			(at 0.48 0)
			(size 0.59 0.64)
			(layers "B.Cu" "B.Mask" "B.Paste")
			(roundrect_rratio 0.25)
			(net 1 "GND")
			(pintype "passive")
		)
	)
	(footprint "antmicro-footprints:C_0603_1608Metric"
		(layer "B.Cu")
		(at 177.2 152.5 180)
		(descr "Capacitor SMD 0603")
		(tags "capacitor 0603")
		(property "Reference" "C73"
			(at -1.25 -1.925 0)
			(layer "B.SilkS")
			(effects
				(font
					(size 0.7 0.7)
					(thickness 0.15)
				)
				(justify left bottom mirror)
			)
		)
		(property "Value" "C_47u_0603"
			(at -1.42757 -1.770288 0)
			(layer "B.Fab")
			(effects
				(font
					(size 0.7 0.7)
					(thickness 0.15)
				)
				(justify left bottom mirror)
			)
		)
		(property "Datasheet" "https://www.murata.com/products/productdetail?partno=GRM188R60J476ME15%23"
			(at 0 0 180)
			(layer "F.Fab")
			(hide yes)
			(effects
				(font
					(size 1.27 1.27)
					(thickness 0.15)
				)
			)
		)
		(property "Manufacturer" "Murata"
			(at 0 0 180)
			(unlocked yes)
			(layer "B.Fab")
			(hide yes)
			(effects
				(font
					(size 1 1)
					(thickness 0.15)
				)
				(justify mirror)
			)
		)
		(property "MPN" "GRM188R60J476ME15D"
			(at 0 0 180)
			(unlocked yes)
			(layer "B.Fab")
			(hide yes)
			(effects
				(font
					(size 1 1)
					(thickness 0.15)
				)
				(justify mirror)
			)
		)
		(property "Val" "47u"
			(at 0 0 180)
			(unlocked yes)
			(layer "B.Fab")
			(hide yes)
			(effects
				(font
					(size 1 1)
					(thickness 0.15)
				)
				(justify mirror)
			)
		)
		(property "License" "Apache-2.0"
			(at 0 0 180)
			(unlocked yes)
			(layer "B.Fab")
			(hide yes)
			(effects
				(font
					(size 1 1)
					(thickness 0.15)
				)
				(justify mirror)
			)
		)
		(property "Author" "Antmicro"
			(at 0 0 180)
			(unlocked yes)
			(layer "B.Fab")
			(hide yes)
			(effects
				(font
					(size 1 1)
					(thickness 0.15)
				)
				(justify mirror)
			)
		)
		(property "Voltage" ""
			(at 0 0 180)
			(unlocked yes)
			(layer "B.Fab")
			(hide yes)
			(effects
				(font
					(size 1 1)
					(thickness 0.15)
				)
				(justify mirror)
			)
		)
		(property "Dielectric" ""
			(at 0 0 180)
			(unlocked yes)
			(layer "B.Fab")
			(hide yes)
			(effects
				(font
					(size 1 1)
					(thickness 0.15)
				)
				(justify mirror)
			)
		)
		(sheetname "/FPGA power/")
		(sheetfile "fpga-power.kicad_sch")
		(attr smd)
		(fp_line
			(start -0.15 0.4)
			(end 0.15 0.4)
			(stroke
				(width 0.15)
				(type solid)
			)
			(layer "B.SilkS")
		)
		(fp_line
			(start -0.15 -0.4)
			(end 0.15 -0.4)
			(stroke
				(width 0.15)
				(type solid)
			)
			(layer "B.SilkS")
		)
		(fp_rect
			(start -1.25 0.65)
			(end 1.25 -0.65)
			(stroke
				(width 0.05)
				(type solid)
			)
			(fill no)
			(layer "B.CrtYd")
		)
		(fp_rect
			(start -0.8 0.4)
			(end 0.8 -0.4)
			(stroke
				(width 0.15)
				(type solid)
			)
			(fill no)
			(layer "B.Fab")
		)
		(fp_text user "License: Apache-2.0"
			(at -1.682 -5.895 0)
			(layer "B.Fab")
			(effects
				(font
					(size 0.7 0.7)
					(thickness 0.15)
				)
				(justify left bottom mirror)
			)
		)
		(fp_text user "Author: Antmicro"
			(at -1.682 -4.894 0)
			(layer "B.Fab")
			(effects
				(font
					(size 0.7 0.7)
					(thickness 0.15)
				)
				(justify left bottom mirror)
			)
		)
		(fp_text user "${REFERENCE}"
			(at -1.682 -3.895 0)
			(layer "B.Fab")
			(effects
				(font
					(size 0.7 0.7)
					(thickness 0.15)
				)
				(justify left bottom mirror)
			)
		)
		(pad "1" smd roundrect
			(at -0.7 0 180)
			(size 0.8 1)
			(layers "B.Cu" "B.Mask" "B.Paste")
			(roundrect_rratio 0.2)
			(net 797 "+1V8")
			(pintype "passive")
		)
		(pad "2" smd roundrect
			(at 0.7 0 180)
			(size 0.8 1)
			(layers "B.Cu" "B.Mask" "B.Paste")
			(roundrect_rratio 0.2)
			(net 1 "GND")
			(pintype "passive")
		)
	)
	(footprint "antmicro-footprints:R_0402_1005Metric"
		(layer "B.Cu")
		(at 235.579999 132.805001 -90)
		(descr "Resistor SMD 0402")
		(tags "resistor SMD 0402")
		(property "Reference" "R125"
			(at -4.055001 -0.470001 90)
			(layer "B.SilkS")
			(effects
				(font
					(size 0.7 0.7)
					(thickness 0.15)
				)
				(justify left bottom mirror)
			)
		)
		(property "Value" "R_4k7_0402"
			(at -1.085 2.05 90)
			(layer "B.Fab")
			(effects
				(font
					(size 0.7 0.7)
					(thickness 0.15)
				)
				(justify left bottom mirror)
			)
		)
		(property "Datasheet" "https://www.bourns.com/docs/product-datasheets/cr.pdf"
			(at 0 0 270)
			(layer "F.Fab")
			(hide yes)
			(effects
				(font
					(size 1.27 1.27)
					(thickness 0.15)
				)
			)
		)
		(property "Manufacturer" "Bourns"
			(at 0 0 270)
			(unlocked yes)
			(layer "B.Fab")
			(hide yes)
			(effects
				(font
					(size 1 1)
					(thickness 0.15)
				)
				(justify mirror)
			)
		)
		(property "MPN" "CR0402-FX-4701GLF"
			(at 0 0 270)
			(unlocked yes)
			(layer "B.Fab")
			(hide yes)
			(effects
				(font
					(size 1 1)
					(thickness 0.15)
				)
				(justify mirror)
			)
		)
		(property "Val" "4k7"
			(at 0 0 270)
			(unlocked yes)
			(layer "B.Fab")
			(hide yes)
			(effects
				(font
					(size 1 1)
					(thickness 0.15)
				)
				(justify mirror)
			)
		)
		(property "License" "Apache-2.0"
			(at 0 0 270)
			(unlocked yes)
			(layer "B.Fab")
			(hide yes)
			(effects
				(font
					(size 1 1)
					(thickness 0.15)
				)
				(justify mirror)
			)
		)
		(property "Author" "Antmicro"
			(at 0 0 270)
			(unlocked yes)
			(layer "B.Fab")
			(hide yes)
			(effects
				(font
					(size 1 1)
					(thickness 0.15)
				)
				(justify mirror)
			)
		)
		(property "Tolerance" "1%"
			(at 0 0 270)
			(unlocked yes)
			(layer "B.Fab")
			(hide yes)
			(effects
				(font
					(size 1 1)
					(thickness 0.15)
				)
				(justify mirror)
			)
		)
		(sheetname "/I^{2}C + I3C/")
		(sheetfile "i2c.kicad_sch")
		(attr smd)
		(fp_rect
			(start -0.925 0.47)
			(end 0.925 -0.47)
			(stroke
				(width 0.05)
				(type default)
			)
			(fill no)
			(layer "B.CrtYd")
		)
		(fp_rect
			(start -0.5 0.25)
			(end 0.5 -0.25)
			(stroke
				(width 0.15)
				(type solid)
			)
			(fill no)
			(layer "B.Fab")
		)
		(fp_text user "${REFERENCE}"
			(at -0.95 -3.168 90)
			(layer "B.Fab")
			(effects
				(font
					(size 0.7 0.7)
					(thickness 0.15)
				)
				(justify left bottom mirror)
			)
		)
		(fp_text user "License: Apache-2.0"
			(at -0.95 -5.169 90)
			(layer "B.Fab")
			(effects
				(font
					(size 0.7 0.7)
					(thickness 0.15)
				)
				(justify left bottom mirror)
			)
		)
		(fp_text user "Author: Antmicro"
			(at -0.95 -4.169 90)
			(layer "B.Fab")
			(effects
				(font
					(size 0.7 0.7)
					(thickness 0.15)
				)
				(justify left bottom mirror)
			)
		)
		(pad "1" smd roundrect
			(at -0.48 0 270)
			(size 0.59 0.64)
			(layers "B.Cu" "B.Mask" "B.Paste")
			(roundrect_rratio 0.25)
			(net 201 "VDDSPD")
			(pintype "passive")
		)
		(pad "2" smd roundrect
			(at 0.48 0 270)
			(size 0.59 0.64)
			(layers "B.Cu" "B.Mask" "B.Paste")
			(roundrect_rratio 0.25)
			(net 460 "/DDR5 RDIMM/DDR.SCL")
			(pintype "passive")
		)
	)
	(footprint "antmicro-footprints:R_0402_1005Metric"
		(layer "B.Cu")
		(at 156.124499 191.299)
		(descr "Resistor SMD 0402")
		(tags "resistor SMD 0402")
		(property "Reference" "R191"
			(at -3.864499 0.441 0)
			(layer "B.SilkS")
			(effects
				(font
					(size 0.7 0.7)
					(thickness 0.15)
				)
				(justify right bottom mirror)
			)
		)
		(property "Value" "R_10k_0402"
			(at -1.011843 -1.772047 0)
			(layer "B.Fab")
			(effects
				(font
					(size 0.7 0.7)
					(thickness 0.15)
				)
				(justify right bottom mirror)
			)
		)
		(property "Datasheet" "https://www.bourns.com/docs/product-datasheets/cr.pdf"
			(at 0 0 0)
			(layer "F.Fab")
			(hide yes)
			(effects
				(font
					(size 1.27 1.27)
					(thickness 0.15)
				)
			)
		)
		(property "MPN" "CR0402-FX-1002GLF"
			(at 0 0 0)
			(unlocked yes)
			(layer "B.Fab")
			(hide yes)
			(effects
				(font
					(size 1 1)
					(thickness 0.15)
				)
				(justify mirror)
			)
		)
		(property "Manufacturer" "Bourns"
			(at 0 0 0)
			(unlocked yes)
			(layer "B.Fab")
			(hide yes)
			(effects
				(font
					(size 1 1)
					(thickness 0.15)
				)
				(justify mirror)
			)
		)
		(property "License" "Apache-2.0"
			(at 0 0 0)
			(unlocked yes)
			(layer "B.Fab")
			(hide yes)
			(effects
				(font
					(size 1 1)
					(thickness 0.15)
				)
				(justify mirror)
			)
		)
		(property "Author" "Antmicro"
			(at 0 0 0)
			(unlocked yes)
			(layer "B.Fab")
			(hide yes)
			(effects
				(font
					(size 1 1)
					(thickness 0.15)
				)
				(justify mirror)
			)
		)
		(property "Val" "10k"
			(at 0 0 0)
			(unlocked yes)
			(layer "B.Fab")
			(hide yes)
			(effects
				(font
					(size 1 1)
					(thickness 0.15)
				)
				(justify mirror)
			)
		)
		(property "Tolerance" "1%"
			(at 0 0 0)
			(unlocked yes)
			(layer "B.Fab")
			(hide yes)
			(effects
				(font
					(size 1 1)
					(thickness 0.15)
				)
				(justify mirror)
			)
		)
		(sheetname "/PCIe connector/")
		(sheetfile "pcie-connector.kicad_sch")
		(attr smd exclude_from_bom dnp)
		(fp_rect
			(start -0.925 0.47)
			(end 0.925 -0.47)
			(stroke
				(width 0.05)
				(type default)
			)
			(fill no)
			(layer "B.CrtYd")
		)
		(fp_rect
			(start -0.5 0.25)
			(end 0.5 -0.25)
			(stroke
				(width 0.15)
				(type solid)
			)
			(fill no)
			(layer "B.Fab")
		)
		(fp_text user "License: Apache-2.0"
			(at -0.95 -5.169 180)
			(layer "B.Fab")
			(effects
				(font
					(size 0.7 0.7)
					(thickness 0.15)
				)
				(justify left bottom mirror)
			)
		)
		(fp_text user "Author: Antmicro"
			(at -0.95 -4.169 180)
			(layer "B.Fab")
			(effects
				(font
					(size 0.7 0.7)
					(thickness 0.15)
				)
				(justify left bottom mirror)
			)
		)
		(fp_text user "${REFERENCE}"
			(at -0.95 -3.168 180)
			(layer "B.Fab")
			(effects
				(font
					(size 0.7 0.7)
					(thickness 0.15)
				)
				(justify left bottom mirror)
			)
		)
		(pad "1" smd roundrect
			(at -0.48 0)
			(size 0.59 0.64)
			(layers "B.Cu" "B.Mask" "B.Paste")
			(roundrect_rratio 0.25)
			(net 98 "PCIE.PWRGD")
			(pintype "passive")
		)
		(pad "2" smd roundrect
			(at 0.48 0)
			(size 0.59 0.64)
			(layers "B.Cu" "B.Mask" "B.Paste")
			(roundrect_rratio 0.25)
			(net 151 "+3V3")
			(pintype "passive")
		)
	)
	(footprint "antmicro-footprints:R_0402_1005Metric_EIA"
		(layer "B.Cu")
		(at 186 144.5 -90)
		(descr "Resistor SMD 0402 (1005 Metric), square (rectangular) end terminal, IPC_7351 nominal, (Body size source: IPC-SM-782 page 76, https://www.pcb-3d.com/wordpress/wp-content/uploads/ipc-sm-782a_amendment_1_and_2.pdf)")
		(tags "resistor 0402")
		(property "Reference" "R180"
			(at -1.94 -1.475 90)
			(layer "B.SilkS")
			(effects
				(font
					(size 0.7 0.7)
					(thickness 0.15)
				)
				(justify left bottom mirror)
			)
		)
		(property "Value" "R_240R_0402"
			(at 0 -1.169 90)
			(layer "B.Fab")
			(effects
				(font
					(size 0.7 0.7)
					(thickness 0.15)
				)
				(justify left bottom mirror)
			)
		)
		(property "Datasheet" "https://www.bourns.com/docs/product-datasheets/cr.pdf"
			(at 0 0 270)
			(layer "F.Fab")
			(hide yes)
			(effects
				(font
					(size 1.27 1.27)
					(thickness 0.15)
				)
			)
		)
		(property "MPN" "CR0402-FX-2400GLF"
			(at 0 0 270)
			(unlocked yes)
			(layer "B.Fab")
			(hide yes)
			(effects
				(font
					(size 1 1)
					(thickness 0.15)
				)
				(justify mirror)
			)
		)
		(property "Manufacturer" "Bourns"
			(at 0 0 270)
			(unlocked yes)
			(layer "B.Fab")
			(hide yes)
			(effects
				(font
					(size 1 1)
					(thickness 0.15)
				)
				(justify mirror)
			)
		)
		(property "License" "Apache-2.0"
			(at 0 0 270)
			(unlocked yes)
			(layer "B.Fab")
			(hide yes)
			(effects
				(font
					(size 1 1)
					(thickness 0.15)
				)
				(justify mirror)
			)
		)
		(property "Author" "Antmicro"
			(at 0 0 270)
			(unlocked yes)
			(layer "B.Fab")
			(hide yes)
			(effects
				(font
					(size 1 1)
					(thickness 0.15)
				)
				(justify mirror)
			)
		)
		(property "Val" "240R"
			(at 0 0 270)
			(unlocked yes)
			(layer "B.Fab")
			(hide yes)
			(effects
				(font
					(size 1 1)
					(thickness 0.15)
				)
				(justify mirror)
			)
		)
		(property "Tolerance" "1%"
			(at 0 0 270)
			(unlocked yes)
			(layer "B.Fab")
			(hide yes)
			(effects
				(font
					(size 1 1)
					(thickness 0.15)
				)
				(justify mirror)
			)
		)
		(sheetname "/FPGA banks HP/")
		(sheetfile "fpga-hp-banks.kicad_sch")
		(attr smd)
		(fp_rect
			(start -0.95 0.45)
			(end 0.95 -0.45)
			(stroke
				(width 0.05)
				(type default)
			)
			(fill no)
			(layer "B.CrtYd")
		)
		(fp_line
			(start -0.5 0.25)
			(end 0.499 0.25)
			(stroke
				(width 0.15)
				(type solid)
			)
			(layer "B.Fab")
		)
		(fp_line
			(start 0.499 0.25)
			(end 0.499 -0.249)
			(stroke
				(width 0.15)
				(type solid)
			)
			(layer "B.Fab")
		)
		(fp_line
			(start -0.5 -0.249)
			(end -0.5 0.25)
			(stroke
				(width 0.15)
				(type solid)
			)
			(layer "B.Fab")
		)
		(fp_line
			(start 0.499 -0.249)
			(end -0.5 -0.249)
			(stroke
				(width 0.15)
				(type solid)
			)
			(layer "B.Fab")
		)
		(fp_text user "License: Apache-2.0"
			(at -0.95 -4.369 90)
			(layer "B.Fab")
			(effects
				(font
					(size 0.7 0.7)
					(thickness 0.15)
				)
				(justify left bottom mirror)
			)
		)
		(fp_text user "Author: Antmicro"
			(at -0.95 -5.569 90)
			(layer "B.Fab")
			(effects
				(font
					(size 0.7 0.7)
					(thickness 0.15)
				)
				(justify left bottom mirror)
			)
		)
		(fp_text user "${REFERENCE}"
			(at -0.95 -3.169 90)
			(layer "B.Fab")
			(effects
				(font
					(size 0.7 0.7)
					(thickness 0.15)
				)
				(justify left bottom mirror)
			)
		)
		(pad "1" smd roundrect
			(at -0.5 0 180)
			(size 0.6 0.6)
			(layers "B.Cu" "B.Mask" "B.Paste")
			(roundrect_rratio 0.25)
			(net 600 "/FPGA banks HP/VRP_66")
			(pintype "passive")
		)
		(pad "2" smd roundrect
			(at 0.499 0 270)
			(size 0.6 0.6)
			(layers "B.Cu" "B.Mask" "B.Paste")
			(roundrect_rratio 0.25)
			(net 1 "GND")
			(pintype "passive")
		)
	)
	(footprint "antmicro-footprints:R_0402_1005Metric"
		(layer "B.Cu")
		(at 247.475 186.299)
		(descr "Resistor SMD 0402")
		(tags "resistor SMD 0402")
		(property "Reference" "R97"
			(at 1.47 0.551 0)
			(layer "B.SilkS")
			(effects
				(font
					(size 0.7 0.7)
					(thickness 0.15)
				)
				(justify right bottom mirror)
			)
		)
		(property "Value" "R_4k7_0402"
			(at -1.011843 -1.772047 0)
			(layer "B.Fab")
			(effects
				(font
					(size 0.7 0.7)
					(thickness 0.15)
				)
				(justify right bottom mirror)
			)
		)
		(property "Datasheet" "https://www.bourns.com/docs/product-datasheets/cr.pdf"
			(at 0 0 0)
			(layer "F.Fab")
			(hide yes)
			(effects
				(font
					(size 1.27 1.27)
					(thickness 0.15)
				)
			)
		)
		(property "MPN" "CR0402-FX-4701GLF"
			(at 0 0 0)
			(unlocked yes)
			(layer "B.Fab")
			(hide yes)
			(effects
				(font
					(size 1 1)
					(thickness 0.15)
				)
				(justify mirror)
			)
		)
		(property "Manufacturer" "Bourns"
			(at 0 0 0)
			(unlocked yes)
			(layer "B.Fab")
			(hide yes)
			(effects
				(font
					(size 1 1)
					(thickness 0.15)
				)
				(justify mirror)
			)
		)
		(property "License" "Apache-2.0"
			(at 0 0 0)
			(unlocked yes)
			(layer "B.Fab")
			(hide yes)
			(effects
				(font
					(size 1 1)
					(thickness 0.15)
				)
				(justify mirror)
			)
		)
		(property "Author" "Antmicro"
			(at 0 0 0)
			(unlocked yes)
			(layer "B.Fab")
			(hide yes)
			(effects
				(font
					(size 1 1)
					(thickness 0.15)
				)
				(justify mirror)
			)
		)
		(property "Val" "4k7"
			(at 0 0 0)
			(unlocked yes)
			(layer "B.Fab")
			(hide yes)
			(effects
				(font
					(size 1 1)
					(thickness 0.15)
				)
				(justify mirror)
			)
		)
		(property "Tolerance" "1%"
			(at 0 0 0)
			(unlocked yes)
			(layer "B.Fab")
			(hide yes)
			(effects
				(font
					(size 1 1)
					(thickness 0.15)
				)
				(justify mirror)
			)
		)
		(sheetname "/I^{2}C + I3C/")
		(sheetfile "i2c.kicad_sch")
		(attr smd)
		(fp_rect
			(start -0.925 0.47)
			(end 0.925 -0.47)
			(stroke
				(width 0.05)
				(type default)
			)
			(fill no)
			(layer "B.CrtYd")
		)
		(fp_rect
			(start -0.5 0.25)
			(end 0.5 -0.25)
			(stroke
				(width 0.15)
				(type solid)
			)
			(fill no)
			(layer "B.Fab")
		)
		(fp_text user "Author: Antmicro"
			(at -0.95 -4.169 180)
			(layer "B.Fab")
			(effects
				(font
					(size 0.7 0.7)
					(thickness 0.15)
				)
				(justify left bottom mirror)
			)
		)
		(fp_text user "${REFERENCE}"
			(at -0.95 -3.168 180)
			(layer "B.Fab")
			(effects
				(font
					(size 0.7 0.7)
					(thickness 0.15)
				)
				(justify left bottom mirror)
			)
		)
		(fp_text user "License: Apache-2.0"
			(at -0.95 -5.169 180)
			(layer "B.Fab")
			(effects
				(font
					(size 0.7 0.7)
					(thickness 0.15)
				)
				(justify left bottom mirror)
			)
		)
		(pad "1" smd roundrect
			(at -0.48 0)
			(size 0.59 0.64)
			(layers "B.Cu" "B.Mask" "B.Paste")
			(roundrect_rratio 0.25)
			(net 771 "/FPGA banks HD/FPGA_I3C.SCL")
			(pintype "passive")
		)
		(pad "2" smd roundrect
			(at 0.48 0)
			(size 0.59 0.64)
			(layers "B.Cu" "B.Mask" "B.Paste")
			(roundrect_rratio 0.25)
			(net 662 "Net-(Q22-D)")
			(pintype "passive")
		)
	)
	(footprint "antmicro-footprints:C_0805_2012Metric"
		(layer "B.Cu")
		(at 203.5 154.4 90)
		(descr "Capacitor SMD 0805")
		(tags "capacitor SMD 0805")
		(property "Reference" "C242"
			(at -1.91 1.91 90)
			(layer "B.SilkS")
			(effects
				(font
					(size 0.7 0.7)
					(thickness 0.15)
				)
				(justify right bottom mirror)
			)
		)
		(property "Value" "C_100u_0805"
			(at -2.055717 -1.963152 90)
			(layer "B.Fab")
			(effects
				(font
					(size 0.7 0.7)
					(thickness 0.15)
				)
				(justify right bottom mirror)
			)
		)
		(property "Datasheet" "https://www.murata.com/products/productdetail?partno=GRM21BR60J107ME15%23"
			(at 0 0 90)
			(layer "F.Fab")
			(hide yes)
			(effects
				(font
					(size 1.27 1.27)
					(thickness 0.15)
				)
			)
		)
		(property "MPN" "GRM21BR60J107ME15L"
			(at 0 0 90)
			(unlocked yes)
			(layer "B.Fab")
			(hide yes)
			(effects
				(font
					(size 1 1)
					(thickness 0.15)
				)
				(justify mirror)
			)
		)
		(property "Manufacturer" "Murata"
			(at 0 0 90)
			(unlocked yes)
			(layer "B.Fab")
			(hide yes)
			(effects
				(font
					(size 1 1)
					(thickness 0.15)
				)
				(justify mirror)
			)
		)
		(property "License" "Apache-2.0"
			(at 0 0 90)
			(unlocked yes)
			(layer "B.Fab")
			(hide yes)
			(effects
				(font
					(size 1 1)
					(thickness 0.15)
				)
				(justify mirror)
			)
		)
		(property "Author" "Antmicro"
			(at 0 0 90)
			(unlocked yes)
			(layer "B.Fab")
			(hide yes)
			(effects
				(font
					(size 1 1)
					(thickness 0.15)
				)
				(justify mirror)
			)
		)
		(property "Val" "100u"
			(at 0 0 90)
			(unlocked yes)
			(layer "B.Fab")
			(hide yes)
			(effects
				(font
					(size 1 1)
					(thickness 0.15)
				)
				(justify mirror)
			)
		)
		(property "Voltage" ""
			(at 0 0 90)
			(unlocked yes)
			(layer "B.Fab")
			(hide yes)
			(effects
				(font
					(size 1 1)
					(thickness 0.15)
				)
				(justify mirror)
			)
		)
		(property "Dielectric" ""
			(at 0 0 90)
			(unlocked yes)
			(layer "B.Fab")
			(hide yes)
			(effects
				(font
					(size 1 1)
					(thickness 0.15)
				)
				(justify mirror)
			)
		)
		(property "Public" "False"
			(at 0 0 90)
			(unlocked yes)
			(layer "B.Fab")
			(hide yes)
			(effects
				(font
					(size 1 1)
					(thickness 0.15)
				)
				(justify mirror)
			)
		)
		(sheetname "/FPGA power/")
		(sheetfile "fpga-power.kicad_sch")
		(attr smd)
		(fp_line
			(start -0.3 -0.7)
			(end 0.3 -0.7)
			(stroke
				(width 0.15)
				(type solid)
			)
			(layer "B.SilkS")
		)
		(fp_line
			(start -0.3 0.7)
			(end 0.3 0.7)
			(stroke
				(width 0.15)
				(type solid)
			)
			(layer "B.SilkS")
		)
		(fp_rect
			(start 1.95 0.9)
			(end -1.95 -0.9)
			(stroke
				(width 0.05)
				(type default)
			)
			(fill no)
			(layer "B.CrtYd")
		)
		(fp_rect
			(start -0.95 0.675)
			(end 0.95 -0.675)
			(stroke
				(width 0.15)
				(type solid)
			)
			(fill no)
			(layer "B.Fab")
		)
		(fp_text user "Author: Antmicro"
			(at -1.9 -5.947 270)
			(layer "B.Fab")
			(effects
				(font
					(size 0.7 0.7)
					(thickness 0.15)
				)
				(justify left bottom mirror)
			)
		)
		(fp_text user "License: Apache-2.0"
			(at -1.9 -4.947 270)
			(layer "B.Fab")
			(effects
				(font
					(size 0.7 0.7)
					(thickness 0.15)
				)
				(justify left bottom mirror)
			)
		)
		(fp_text user "${REFERENCE}"
			(at -1.9 -3.947 270)
			(layer "B.Fab")
			(effects
				(font
					(size 0.7 0.7)
					(thickness 0.15)
				)
				(justify left bottom mirror)
			)
		)
		(pad "1" smd roundrect
			(at -1.1 0 90)
			(size 1.2 1.3)
			(layers "B.Cu" "B.Mask" "B.Paste")
			(roundrect_rratio 0.25)
			(net 1 "GND")
			(pintype "passive")
		)
		(pad "2" smd roundrect
			(at 1.1 0 90)
			(size 1.2 1.3)
			(layers "B.Cu" "B.Mask" "B.Paste")
			(roundrect_rratio 0.25)
			(net 553 "+0V85")
			(pintype "passive")
		)
	)
	(footprint "antmicro-footprints:C_0402_1005Metric"
		(layer "B.Cu")
		(at 122.95 152.61)
		(descr "Capacitor SMD 0402")
		(tags "capacitor SMD 0402")
		(property "Reference" "C306"
			(at 2.44 1.504 0)
			(layer "B.SilkS")
			(effects
				(font
					(size 0.7 0.7)
					(thickness 0.15)
				)
				(justify right bottom mirror)
			)
		)
		(property "Value" "C_100n_0402"
			(at -1.022927 -2.155213 0)
			(layer "B.Fab")
			(effects
				(font
					(size 0.7 0.7)
					(thickness 0.15)
				)
				(justify right bottom mirror)
			)
		)
		(property "Datasheet" "https://www.murata.com/products/productdetail?partno=GRM155R61H104KE14%23"
			(at 0 0 0)
			(layer "F.Fab")
			(hide yes)
			(effects
				(font
					(size 1.27 1.27)
					(thickness 0.15)
				)
			)
		)
		(property "Manufacturer" "Murata"
			(at 0 0 0)
			(unlocked yes)
			(layer "B.Fab")
			(hide yes)
			(effects
				(font
					(size 1 1)
					(thickness 0.15)
				)
				(justify mirror)
			)
		)
		(property "MPN" "GRM155R61H104KE14D"
			(at 0 0 0)
			(unlocked yes)
			(layer "B.Fab")
			(hide yes)
			(effects
				(font
					(size 1 1)
					(thickness 0.15)
				)
				(justify mirror)
			)
		)
		(property "Val" "100n"
			(at 0 0 0)
			(unlocked yes)
			(layer "B.Fab")
			(hide yes)
			(effects
				(font
					(size 1 1)
					(thickness 0.15)
				)
				(justify mirror)
			)
		)
		(property "License" "Apache-2.0"
			(at 0 0 0)
			(unlocked yes)
			(layer "B.Fab")
			(hide yes)
			(effects
				(font
					(size 1 1)
					(thickness 0.15)
				)
				(justify mirror)
			)
		)
		(property "Author" "Antmicro"
			(at 0 0 0)
			(unlocked yes)
			(layer "B.Fab")
			(hide yes)
			(effects
				(font
					(size 1 1)
					(thickness 0.15)
				)
				(justify mirror)
			)
		)
		(property "Voltage" "50V"
			(at 0 0 0)
			(unlocked yes)
			(layer "B.Fab")
			(hide yes)
			(effects
				(font
					(size 1 1)
					(thickness 0.15)
				)
				(justify mirror)
			)
		)
		(property "Dielectric" "X5R"
			(at 0 0 0)
			(unlocked yes)
			(layer "B.Fab")
			(hide yes)
			(effects
				(font
					(size 1 1)
					(thickness 0.15)
				)
				(justify mirror)
			)
		)
		(sheetname "/FPGA MGT Interface/")
		(sheetfile "fpga-mgt.kicad_sch")
		(attr smd)
		(fp_rect
			(start -0.925 0.47)
			(end 0.925 -0.47)
			(stroke
				(width 0.05)
				(type default)
			)
			(fill no)
			(layer "B.CrtYd")
		)
		(fp_line
			(start -0.494 -0.248)
			(end -0.494 0.25)
			(stroke
				(width 0.15)
				(type solid)
			)
			(layer "B.Fab")
		)
		(fp_line
			(start -0.494 0.25)
			(end 0.504 0.25)
			(stroke
				(width 0.15)
				(type solid)
			)
			(layer "B.Fab")
		)
		(fp_line
			(start 0.504 -0.248)
			(end -0.494 -0.248)
			(stroke
				(width 0.15)
				(type solid)
			)
			(layer "B.Fab")
		)
		(fp_line
			(start 0.504 0.25)
			(end 0.504 -0.248)
			(stroke
				(width 0.15)
				(type solid)
			)
			(layer "B.Fab")
		)
		(fp_text user "${REFERENCE}"
			(at -0.939 -4.599 180)
			(layer "B.Fab")
			(effects
				(font
					(size 0.7 0.7)
					(thickness 0.15)
				)
				(justify left bottom mirror)
			)
		)
		(fp_text user "License: Apache-2.0"
			(at -0.939 -5.799 180)
			(layer "B.Fab")
			(effects
				(font
					(size 0.7 0.7)
					(thickness 0.15)
				)
				(justify left bottom mirror)
			)
		)
		(fp_text user "Author: Antmicro"
			(at -0.939 -3.399 180)
			(layer "B.Fab")
			(effects
				(font
					(size 0.7 0.7)
					(thickness 0.15)
				)
				(justify left bottom mirror)
			)
		)
		(pad "1" smd roundrect
			(at -0.48 0)
			(size 0.59 0.64)
			(layers "B.Cu" "B.Mask" "B.Paste")
			(roundrect_rratio 0.25)
			(net 349 "/FPGA MGT Interface/HDMI_IN.D0_N")
			(pintype "passive")
		)
		(pad "2" smd roundrect
			(at 0.48 0)
			(size 0.59 0.64)
			(layers "B.Cu" "B.Mask" "B.Paste")
			(roundrect_rratio 0.25)
			(net 652 "/FPGA MGT Interface/HDMI_FPGA.RX0_N")
			(pintype "passive")
		)
	)
	(footprint "antmicro-footprints:C_0402_1005Metric_EIA"
		(layer "B.Cu")
		(at 180.5 147)
		(descr "Capacitor SMD 0402 (1005 Metric), square (rectangular) end terminal, IPC_7351 nominal, (Body size source: IPC-SM-782 page 76, https://www.pcb-3d.com/wordpress/wp-content/uploads/ipc-sm-782a_amendment_1_and_2.pdf)")
		(tags "capacitor 0402")
		(property "Reference" "C89"
			(at -3.15 0.525 0)
			(layer "B.SilkS")
			(effects
				(font
					(size 0.7 0.7)
					(thickness 0.15)
				)
				(justify right bottom mirror)
			)
		)
		(property "Value" "C_100n_0402"
			(at 0 -1.169 0)
			(layer "B.Fab")
			(effects
				(font
					(size 0.7 0.7)
					(thickness 0.15)
				)
				(justify right bottom mirror)
			)
		)
		(property "Datasheet" "https://www.murata.com/products/productdetail?partno=GRM155R61H104KE14%23"
			(at 0 0 0)
			(layer "F.Fab")
			(hide yes)
			(effects
				(font
					(size 1.27 1.27)
					(thickness 0.15)
				)
			)
		)
		(property "MPN" "GRM155R61H104KE14D"
			(at 0 0 0)
			(unlocked yes)
			(layer "B.Fab")
			(hide yes)
			(effects
				(font
					(size 1 1)
					(thickness 0.15)
				)
				(justify mirror)
			)
		)
		(property "Manufacturer" "Murata"
			(at 0 0 0)
			(unlocked yes)
			(layer "B.Fab")
			(hide yes)
			(effects
				(font
					(size 1 1)
					(thickness 0.15)
				)
				(justify mirror)
			)
		)
		(property "License" "Apache-2.0"
			(at 0 0 0)
			(unlocked yes)
			(layer "B.Fab")
			(hide yes)
			(effects
				(font
					(size 1 1)
					(thickness 0.15)
				)
				(justify mirror)
			)
		)
		(property "Author" "Antmicro"
			(at 0 0 0)
			(unlocked yes)
			(layer "B.Fab")
			(hide yes)
			(effects
				(font
					(size 1 1)
					(thickness 0.15)
				)
				(justify mirror)
			)
		)
		(property "Val" "100n"
			(at 0 0 0)
			(unlocked yes)
			(layer "B.Fab")
			(hide yes)
			(effects
				(font
					(size 1 1)
					(thickness 0.15)
				)
				(justify mirror)
			)
		)
		(property "Voltage" "50V"
			(at 0 0 0)
			(unlocked yes)
			(layer "B.Fab")
			(hide yes)
			(effects
				(font
					(size 1 1)
					(thickness 0.15)
				)
				(justify mirror)
			)
		)
		(property "Dielectric" "X5R"
			(at 0 0 0)
			(unlocked yes)
			(layer "B.Fab")
			(hide yes)
			(effects
				(font
					(size 1 1)
					(thickness 0.15)
				)
				(justify mirror)
			)
		)
		(sheetname "/FPGA power/")
		(sheetfile "fpga-power.kicad_sch")
		(attr smd)
		(fp_rect
			(start -0.95 0.45)
			(end 0.95 -0.45)
			(stroke
				(width 0.05)
				(type default)
			)
			(fill no)
			(layer "B.CrtYd")
		)
		(fp_line
			(start -0.5 -0.248)
			(end -0.5 0.25)
			(stroke
				(width 0.15)
				(type solid)
			)
			(layer "B.Fab")
		)
		(fp_line
			(start -0.5 0.25)
			(end 0.498 0.25)
			(stroke
				(width 0.15)
				(type solid)
			)
			(layer "B.Fab")
		)
		(fp_line
			(start 0.498 -0.248)
			(end -0.5 -0.248)
			(stroke
				(width 0.15)
				(type solid)
			)
			(layer "B.Fab")
		)
		(fp_line
			(start 0.498 0.25)
			(end 0.498 -0.248)
			(stroke
				(width 0.15)
				(type solid)
			)
			(layer "B.Fab")
		)
		(fp_text user "License: Apache-2.0"
			(at -0.9656 -4.369 180)
			(layer "B.Fab")
			(effects
				(font
					(size 0.7 0.7)
					(thickness 0.15)
				)
				(justify left bottom mirror)
			)
		)
		(fp_text user "${REFERENCE}"
			(at -0.9656 -3.169 180)
			(layer "B.Fab")
			(effects
				(font
					(size 0.7 0.7)
					(thickness 0.15)
				)
				(justify left bottom mirror)
			)
		)
		(fp_text user "Author: Antmicro"
			(at -0.9656 -5.569 180)
			(layer "B.Fab")
			(effects
				(font
					(size 0.7 0.7)
					(thickness 0.15)
				)
				(justify left bottom mirror)
			)
		)
		(pad "1" smd roundrect
			(at -0.5 0 270)
			(size 0.6 0.6)
			(layers "B.Cu" "B.Mask" "B.Paste")
			(roundrect_rratio 0.25)
			(net 1 "GND")
			(pintype "passive")
		)
		(pad "2" smd roundrect
			(at 0.498 0)
			(size 0.6 0.6)
			(layers "B.Cu" "B.Mask" "B.Paste")
			(roundrect_rratio 0.25)
			(net 797 "+1V8")
			(pintype "passive")
		)
	)
	(footprint "antmicro-footprints:R_0402_1005Metric"
		(layer "B.Cu")
		(at 116.26 164.45 -90)
		(descr "Resistor SMD 0402")
		(tags "resistor SMD 0402")
		(property "Reference" "R86"
			(at -1 -1.54 90)
			(layer "B.SilkS")
			(effects
				(font
					(size 0.7 0.7)
					(thickness 0.15)
				)
				(justify left bottom mirror)
			)
		)
		(property "Value" "R_10k_0402"
			(at -1.011843 -1.772047 90)
			(layer "B.Fab")
			(effects
				(font
					(size 0.7 0.7)
					(thickness 0.15)
				)
				(justify left bottom mirror)
			)
		)
		(property "Datasheet" "https://www.bourns.com/docs/product-datasheets/cr.pdf"
			(at 0 0 270)
			(layer "F.Fab")
			(hide yes)
			(effects
				(font
					(size 1.27 1.27)
					(thickness 0.15)
				)
			)
		)
		(property "MPN" "CR0402-FX-1002GLF"
			(at 0 0 270)
			(unlocked yes)
			(layer "B.Fab")
			(hide yes)
			(effects
				(font
					(size 1 1)
					(thickness 0.15)
				)
				(justify mirror)
			)
		)
		(property "Manufacturer" "Bourns"
			(at 0 0 270)
			(unlocked yes)
			(layer "B.Fab")
			(hide yes)
			(effects
				(font
					(size 1 1)
					(thickness 0.15)
				)
				(justify mirror)
			)
		)
		(property "License" "Apache-2.0"
			(at 0 0 270)
			(unlocked yes)
			(layer "B.Fab")
			(hide yes)
			(effects
				(font
					(size 1 1)
					(thickness 0.15)
				)
				(justify mirror)
			)
		)
		(property "Author" "Antmicro"
			(at 0 0 270)
			(unlocked yes)
			(layer "B.Fab")
			(hide yes)
			(effects
				(font
					(size 1 1)
					(thickness 0.15)
				)
				(justify mirror)
			)
		)
		(property "Val" "10k"
			(at 0 0 270)
			(unlocked yes)
			(layer "B.Fab")
			(hide yes)
			(effects
				(font
					(size 1 1)
					(thickness 0.15)
				)
				(justify mirror)
			)
		)
		(property "Tolerance" "1%"
			(at 0 0 270)
			(unlocked yes)
			(layer "B.Fab")
			(hide yes)
			(effects
				(font
					(size 1 1)
					(thickness 0.15)
				)
				(justify mirror)
			)
		)
		(sheetname "/HDMI + SD Card/")
		(sheetfile "hdmi-sd-card.kicad_sch")
		(attr smd)
		(fp_rect
			(start -0.925 0.47)
			(end 0.925 -0.47)
			(stroke
				(width 0.05)
				(type default)
			)
			(fill no)
			(layer "B.CrtYd")
		)
		(fp_rect
			(start -0.5 0.25)
			(end 0.5 -0.25)
			(stroke
				(width 0.15)
				(type solid)
			)
			(fill no)
			(layer "B.Fab")
		)
		(fp_text user "License: Apache-2.0"
			(at -0.95 -5.169 90)
			(layer "B.Fab")
			(effects
				(font
					(size 0.7 0.7)
					(thickness 0.15)
				)
				(justify left bottom mirror)
			)
		)
		(fp_text user "Author: Antmicro"
			(at -0.95 -4.169 90)
			(layer "B.Fab")
			(effects
				(font
					(size 0.7 0.7)
					(thickness 0.15)
				)
				(justify left bottom mirror)
			)
		)
		(fp_text user "${REFERENCE}"
			(at -0.95 -3.168 90)
			(layer "B.Fab")
			(effects
				(font
					(size 0.7 0.7)
					(thickness 0.15)
				)
				(justify left bottom mirror)
			)
		)
		(pad "1" smd roundrect
			(at -0.48 0 270)
			(size 0.59 0.64)
			(layers "B.Cu" "B.Mask" "B.Paste")
			(roundrect_rratio 0.25)
			(net 507 "HDMI_IN_CD")
			(pintype "passive")
		)
		(pad "2" smd roundrect
			(at 0.48 0 270)
			(size 0.59 0.64)
			(layers "B.Cu" "B.Mask" "B.Paste")
			(roundrect_rratio 0.25)
			(net 151 "+3V3")
			(pintype "passive")
		)
	)
	(footprint "antmicro-footprints:C_0402_1005Metric_EIA"
		(layer "B.Cu")
		(at 186 154.500001 90)
		(descr "Capacitor SMD 0402 (1005 Metric), square (rectangular) end terminal, IPC_7351 nominal, (Body size source: IPC-SM-782 page 76, https://www.pcb-3d.com/wordpress/wp-content/uploads/ipc-sm-782a_amendment_1_and_2.pdf)")
		(tags "capacitor 0402")
		(property "Reference" "C43"
			(at 9.950001 -30.675 90)
			(layer "B.SilkS")
			(effects
				(font
					(size 0.7 0.7)
					(thickness 0.15)
				)
				(justify right bottom mirror)
			)
		)
		(property "Value" "C_1u_25V_0402"
			(at 0 -1.169 90)
			(layer "B.Fab")
			(effects
				(font
					(size 0.7 0.7)
					(thickness 0.15)
				)
				(justify right bottom mirror)
			)
		)
		(property "Datasheet" "https://www.murata.com/products/productdetail?partno=GRM155R61E105KE11%23"
			(at 0 0 90)
			(layer "F.Fab")
			(hide yes)
			(effects
				(font
					(size 1.27 1.27)
					(thickness 0.15)
				)
			)
		)
		(property "MPN" "GRM155R61E105KE11J"
			(at 0 0 90)
			(unlocked yes)
			(layer "B.Fab")
			(hide yes)
			(effects
				(font
					(size 1 1)
					(thickness 0.15)
				)
				(justify mirror)
			)
		)
		(property "Manufacturer" "Murata"
			(at 0 0 90)
			(unlocked yes)
			(layer "B.Fab")
			(hide yes)
			(effects
				(font
					(size 1 1)
					(thickness 0.15)
				)
				(justify mirror)
			)
		)
		(property "License" "Apache-2.0"
			(at 0 0 90)
			(unlocked yes)
			(layer "B.Fab")
			(hide yes)
			(effects
				(font
					(size 1 1)
					(thickness 0.15)
				)
				(justify mirror)
			)
		)
		(property "Author" "Antmicro"
			(at 0 0 90)
			(unlocked yes)
			(layer "B.Fab")
			(hide yes)
			(effects
				(font
					(size 1 1)
					(thickness 0.15)
				)
				(justify mirror)
			)
		)
		(property "Val" "1u"
			(at 0 0 90)
			(unlocked yes)
			(layer "B.Fab")
			(hide yes)
			(effects
				(font
					(size 1 1)
					(thickness 0.15)
				)
				(justify mirror)
			)
		)
		(property "Voltage" "25V"
			(at 0 0 90)
			(unlocked yes)
			(layer "B.Fab")
			(hide yes)
			(effects
				(font
					(size 1 1)
					(thickness 0.15)
				)
				(justify mirror)
			)
		)
		(property "Dielectric" "X5R"
			(at 0 0 90)
			(unlocked yes)
			(layer "B.Fab")
			(hide yes)
			(effects
				(font
					(size 1 1)
					(thickness 0.15)
				)
				(justify mirror)
			)
		)
		(sheetname "/FPGA power/")
		(sheetfile "fpga-power.kicad_sch")
		(attr smd)
		(fp_rect
			(start -0.95 0.45)
			(end 0.95 -0.45)
			(stroke
				(width 0.05)
				(type default)
			)
			(fill no)
			(layer "B.CrtYd")
		)
		(fp_line
			(start 0.498 -0.248)
			(end -0.5 -0.248)
			(stroke
				(width 0.15)
				(type solid)
			)
			(layer "B.Fab")
		)
		(fp_line
			(start -0.5 -0.248)
			(end -0.5 0.25)
			(stroke
				(width 0.15)
				(type solid)
			)
			(layer "B.Fab")
		)
		(fp_line
			(start 0.498 0.25)
			(end 0.498 -0.248)
			(stroke
				(width 0.15)
				(type solid)
			)
			(layer "B.Fab")
		)
		(fp_line
			(start -0.5 0.25)
			(end 0.498 0.25)
			(stroke
				(width 0.15)
				(type solid)
			)
			(layer "B.Fab")
		)
		(fp_text user "Author: Antmicro"
			(at -0.9656 -5.569 270)
			(layer "B.Fab")
			(effects
				(font
					(size 0.7 0.7)
					(thickness 0.15)
				)
				(justify left bottom mirror)
			)
		)
		(fp_text user "${REFERENCE}"
			(at -0.9656 -3.169 270)
			(layer "B.Fab")
			(effects
				(font
					(size 0.7 0.7)
					(thickness 0.15)
				)
				(justify left bottom mirror)
			)
		)
		(fp_text user "License: Apache-2.0"
			(at -0.9656 -4.369 270)
			(layer "B.Fab")
			(effects
				(font
					(size 0.7 0.7)
					(thickness 0.15)
				)
				(justify left bottom mirror)
			)
		)
		(pad "1" smd roundrect
			(at -0.5 0)
			(size 0.6 0.6)
			(layers "B.Cu" "B.Mask" "B.Paste")
			(roundrect_rratio 0.25)
			(net 1 "GND")
			(pintype "passive")
		)
		(pad "2" smd roundrect
			(at 0.498 0 90)
			(size 0.6 0.6)
			(layers "B.Cu" "B.Mask" "B.Paste")
			(roundrect_rratio 0.25)
			(net 553 "+0V85")
			(pintype "passive")
		)
	)
	(footprint "antmicro-footprints:C_0402_1005Metric"
		(layer "B.Cu")
		(at 122.95 149.61)
		(descr "Capacitor SMD 0402")
		(tags "capacitor SMD 0402")
		(property "Reference" "C305"
			(at 2.31 1.262 0)
			(layer "B.SilkS")
			(effects
				(font
					(size 0.7 0.7)
					(thickness 0.15)
				)
				(justify right bottom mirror)
			)
		)
		(property "Value" "C_100n_0402"
			(at -1.022927 -2.155213 0)
			(layer "B.Fab")
			(effects
				(font
					(size 0.7 0.7)
					(thickness 0.15)
				)
				(justify right bottom mirror)
			)
		)
		(property "Datasheet" "https://www.murata.com/products/productdetail?partno=GRM155R61H104KE14%23"
			(at 0 0 0)
			(layer "F.Fab")
			(hide yes)
			(effects
				(font
					(size 1.27 1.27)
					(thickness 0.15)
				)
			)
		)
		(property "Manufacturer" "Murata"
			(at 0 0 0)
			(unlocked yes)
			(layer "B.Fab")
			(hide yes)
			(effects
				(font
					(size 1 1)
					(thickness 0.15)
				)
				(justify mirror)
			)
		)
		(property "MPN" "GRM155R61H104KE14D"
			(at 0 0 0)
			(unlocked yes)
			(layer "B.Fab")
			(hide yes)
			(effects
				(font
					(size 1 1)
					(thickness 0.15)
				)
				(justify mirror)
			)
		)
		(property "Val" "100n"
			(at 0 0 0)
			(unlocked yes)
			(layer "B.Fab")
			(hide yes)
			(effects
				(font
					(size 1 1)
					(thickness 0.15)
				)
				(justify mirror)
			)
		)
		(property "License" "Apache-2.0"
			(at 0 0 0)
			(unlocked yes)
			(layer "B.Fab")
			(hide yes)
			(effects
				(font
					(size 1 1)
					(thickness 0.15)
				)
				(justify mirror)
			)
		)
		(property "Author" "Antmicro"
			(at 0 0 0)
			(unlocked yes)
			(layer "B.Fab")
			(hide yes)
			(effects
				(font
					(size 1 1)
					(thickness 0.15)
				)
				(justify mirror)
			)
		)
		(property "Voltage" "50V"
			(at 0 0 0)
			(unlocked yes)
			(layer "B.Fab")
			(hide yes)
			(effects
				(font
					(size 1 1)
					(thickness 0.15)
				)
				(justify mirror)
			)
		)
		(property "Dielectric" "X5R"
			(at 0 0 0)
			(unlocked yes)
			(layer "B.Fab")
			(hide yes)
			(effects
				(font
					(size 1 1)
					(thickness 0.15)
				)
				(justify mirror)
			)
		)
		(sheetname "/FPGA MGT Interface/")
		(sheetfile "fpga-mgt.kicad_sch")
		(attr smd)
		(fp_rect
			(start -0.925 0.47)
			(end 0.925 -0.47)
			(stroke
				(width 0.05)
				(type default)
			)
			(fill no)
			(layer "B.CrtYd")
		)
		(fp_line
			(start -0.494 -0.248)
			(end -0.494 0.25)
			(stroke
				(width 0.15)
				(type solid)
			)
			(layer "B.Fab")
		)
		(fp_line
			(start -0.494 0.25)
			(end 0.504 0.25)
			(stroke
				(width 0.15)
				(type solid)
			)
			(layer "B.Fab")
		)
		(fp_line
			(start 0.504 -0.248)
			(end -0.494 -0.248)
			(stroke
				(width 0.15)
				(type solid)
			)
			(layer "B.Fab")
		)
		(fp_line
			(start 0.504 0.25)
			(end 0.504 -0.248)
			(stroke
				(width 0.15)
				(type solid)
			)
			(layer "B.Fab")
		)
		(fp_text user "Author: Antmicro"
			(at -0.939 -3.399 180)
			(layer "B.Fab")
			(effects
				(font
					(size 0.7 0.7)
					(thickness 0.15)
				)
				(justify left bottom mirror)
			)
		)
		(fp_text user "${REFERENCE}"
			(at -0.939 -4.599 180)
			(layer "B.Fab")
			(effects
				(font
					(size 0.7 0.7)
					(thickness 0.15)
				)
				(justify left bottom mirror)
			)
		)
		(fp_text user "License: Apache-2.0"
			(at -0.939 -5.799 180)
			(layer "B.Fab")
			(effects
				(font
					(size 0.7 0.7)
					(thickness 0.15)
				)
				(justify left bottom mirror)
			)
		)
		(pad "1" smd roundrect
			(at -0.48 0)
			(size 0.59 0.64)
			(layers "B.Cu" "B.Mask" "B.Paste")
			(roundrect_rratio 0.25)
			(net 348 "/FPGA MGT Interface/HDMI_IN.D1_P")
			(pintype "passive")
		)
		(pad "2" smd roundrect
			(at 0.48 0)
			(size 0.59 0.64)
			(layers "B.Cu" "B.Mask" "B.Paste")
			(roundrect_rratio 0.25)
			(net 651 "/FPGA MGT Interface/HDMI_FPGA.RX1_P")
			(pintype "passive")
		)
	)
	(footprint "antmicro-footprints:C_0805_2012Metric"
		(layer "B.Cu")
		(at 183.35 152.525)
		(descr "Capacitor SMD 0805")
		(tags "capacitor SMD 0805")
		(property "Reference" "C38"
			(at -32.2 -10.425 0)
			(layer "B.SilkS")
			(effects
				(font
					(size 0.7 0.7)
					(thickness 0.15)
				)
				(justify right bottom mirror)
			)
		)
		(property "Value" "C_100u_0805"
			(at -2.055717 -1.963152 0)
			(layer "B.Fab")
			(effects
				(font
					(size 0.7 0.7)
					(thickness 0.15)
				)
				(justify right bottom mirror)
			)
		)
		(property "Datasheet" "https://www.murata.com/products/productdetail?partno=GRM21BR60J107ME15%23"
			(at 0 0 0)
			(layer "F.Fab")
			(hide yes)
			(effects
				(font
					(size 1.27 1.27)
					(thickness 0.15)
				)
			)
		)
		(property "MPN" "GRM21BR60J107ME15L"
			(at 0 0 0)
			(unlocked yes)
			(layer "B.Fab")
			(hide yes)
			(effects
				(font
					(size 1 1)
					(thickness 0.15)
				)
				(justify mirror)
			)
		)
		(property "Manufacturer" "Murata"
			(at 0 0 0)
			(unlocked yes)
			(layer "B.Fab")
			(hide yes)
			(effects
				(font
					(size 1 1)
					(thickness 0.15)
				)
				(justify mirror)
			)
		)
		(property "License" "Apache-2.0"
			(at 0 0 0)
			(unlocked yes)
			(layer "B.Fab")
			(hide yes)
			(effects
				(font
					(size 1 1)
					(thickness 0.15)
				)
				(justify mirror)
			)
		)
		(property "Author" "Antmicro"
			(at 0 0 0)
			(unlocked yes)
			(layer "B.Fab")
			(hide yes)
			(effects
				(font
					(size 1 1)
					(thickness 0.15)
				)
				(justify mirror)
			)
		)
		(property "Val" "100u"
			(at 0 0 0)
			(unlocked yes)
			(layer "B.Fab")
			(hide yes)
			(effects
				(font
					(size 1 1)
					(thickness 0.15)
				)
				(justify mirror)
			)
		)
		(property "Voltage" ""
			(at 0 0 0)
			(unlocked yes)
			(layer "B.Fab")
			(hide yes)
			(effects
				(font
					(size 1 1)
					(thickness 0.15)
				)
				(justify mirror)
			)
		)
		(property "Dielectric" ""
			(at 0 0 0)
			(unlocked yes)
			(layer "B.Fab")
			(hide yes)
			(effects
				(font
					(size 1 1)
					(thickness 0.15)
				)
				(justify mirror)
			)
		)
		(property "Public" "False"
			(at 0 0 0)
			(unlocked yes)
			(layer "B.Fab")
			(hide yes)
			(effects
				(font
					(size 1 1)
					(thickness 0.15)
				)
				(justify mirror)
			)
		)
		(sheetname "/FPGA power/")
		(sheetfile "fpga-power.kicad_sch")
		(attr smd)
		(fp_line
			(start -0.3 -0.7)
			(end 0.3 -0.7)
			(stroke
				(width 0.15)
				(type solid)
			)
			(layer "B.SilkS")
		)
		(fp_line
			(start -0.3 0.7)
			(end 0.3 0.7)
			(stroke
				(width 0.15)
				(type solid)
			)
			(layer "B.SilkS")
		)
		(fp_rect
			(start 1.95 0.9)
			(end -1.95 -0.9)
			(stroke
				(width 0.05)
				(type default)
			)
			(fill no)
			(layer "B.CrtYd")
		)
		(fp_rect
			(start -0.95 0.675)
			(end 0.95 -0.675)
			(stroke
				(width 0.15)
				(type solid)
			)
			(fill no)
			(layer "B.Fab")
		)
		(fp_text user "License: Apache-2.0"
			(at -1.9 -4.947 180)
			(layer "B.Fab")
			(effects
				(font
					(size 0.7 0.7)
					(thickness 0.15)
				)
				(justify left bottom mirror)
			)
		)
		(fp_text user "${REFERENCE}"
			(at -1.9 -3.947 180)
			(layer "B.Fab")
			(effects
				(font
					(size 0.7 0.7)
					(thickness 0.15)
				)
				(justify left bottom mirror)
			)
		)
		(fp_text user "Author: Antmicro"
			(at -1.9 -5.947 180)
			(layer "B.Fab")
			(effects
				(font
					(size 0.7 0.7)
					(thickness 0.15)
				)
				(justify left bottom mirror)
			)
		)
		(pad "1" smd roundrect
			(at -1.1 0)
			(size 1.2 1.3)
			(layers "B.Cu" "B.Mask" "B.Paste")
			(roundrect_rratio 0.25)
			(net 1 "GND")
			(pintype "passive")
		)
		(pad "2" smd roundrect
			(at 1.1 0)
			(size 1.2 1.3)
			(layers "B.Cu" "B.Mask" "B.Paste")
			(roundrect_rratio 0.25)
			(net 553 "+0V85")
			(pintype "passive")
		)
	)
	(footprint "antmicro-footprints:C_0603_1608Metric"
		(layer "B.Cu")
		(at 248.32 121.47 90)
		(descr "Capacitor SMD 0603")
		(tags "capacitor 0603")
		(property "Reference" "C326"
			(at -4.11 0.48 90)
			(layer "B.SilkS")
			(effects
				(font
					(size 0.7 0.7)
					(thickness 0.15)
				)
				(justify right bottom mirror)
			)
		)
		(property "Value" "C_10u_25V_0603"
			(at -1.42757 -1.770288 90)
			(layer "B.Fab")
			(effects
				(font
					(size 0.7 0.7)
					(thickness 0.15)
				)
				(justify right bottom mirror)
			)
		)
		(property "Datasheet" "https://product.tdk.com/en/search/capacitor/ceramic/mlcc/info?part_no=C1608X5R1E106M080AC"
			(at 0 0 90)
			(layer "F.Fab")
			(hide yes)
			(effects
				(font
					(size 1.27 1.27)
					(thickness 0.15)
				)
			)
		)
		(property "MPN" "C1608X5R1E106M080AC"
			(at 0 0 90)
			(unlocked yes)
			(layer "B.Fab")
			(hide yes)
			(effects
				(font
					(size 1 1)
					(thickness 0.15)
				)
				(justify mirror)
			)
		)
		(property "Manufacturer" "TDK"
			(at 0 0 90)
			(unlocked yes)
			(layer "B.Fab")
			(hide yes)
			(effects
				(font
					(size 1 1)
					(thickness 0.15)
				)
				(justify mirror)
			)
		)
		(property "License" "Apache-2.0"
			(at 0 0 90)
			(unlocked yes)
			(layer "B.Fab")
			(hide yes)
			(effects
				(font
					(size 1 1)
					(thickness 0.15)
				)
				(justify mirror)
			)
		)
		(property "Author" "Antmicro"
			(at 0 0 90)
			(unlocked yes)
			(layer "B.Fab")
			(hide yes)
			(effects
				(font
					(size 1 1)
					(thickness 0.15)
				)
				(justify mirror)
			)
		)
		(property "Val" "10u"
			(at 0 0 90)
			(unlocked yes)
			(layer "B.Fab")
			(hide yes)
			(effects
				(font
					(size 1 1)
					(thickness 0.15)
				)
				(justify mirror)
			)
		)
		(property "Voltage" "25V"
			(at 0 0 90)
			(unlocked yes)
			(layer "B.Fab")
			(hide yes)
			(effects
				(font
					(size 1 1)
					(thickness 0.15)
				)
				(justify mirror)
			)
		)
		(property "Dielectric" ""
			(at 0 0 90)
			(unlocked yes)
			(layer "B.Fab")
			(hide yes)
			(effects
				(font
					(size 1 1)
					(thickness 0.15)
				)
				(justify mirror)
			)
		)
		(sheetname "/Supply/")
		(sheetfile "supply.kicad_sch")
		(attr smd)
		(fp_line
			(start -0.15 -0.4)
			(end 0.15 -0.4)
			(stroke
				(width 0.15)
				(type solid)
			)
			(layer "B.SilkS")
		)
		(fp_line
			(start -0.15 0.4)
			(end 0.15 0.4)
			(stroke
				(width 0.15)
				(type solid)
			)
			(layer "B.SilkS")
		)
		(fp_rect
			(start -1.25 0.65)
			(end 1.25 -0.65)
			(stroke
				(width 0.05)
				(type solid)
			)
			(fill no)
			(layer "B.CrtYd")
		)
		(fp_rect
			(start -0.8 0.4)
			(end 0.8 -0.4)
			(stroke
				(width 0.15)
				(type solid)
			)
			(fill no)
			(layer "B.Fab")
		)
		(fp_text user "${REFERENCE}"
			(at -1.682 -3.895 270)
			(layer "B.Fab")
			(effects
				(font
					(size 0.7 0.7)
					(thickness 0.15)
				)
				(justify left bottom mirror)
			)
		)
		(fp_text user "License: Apache-2.0"
			(at -1.682 -5.895 270)
			(layer "B.Fab")
			(effects
				(font
					(size 0.7 0.7)
					(thickness 0.15)
				)
				(justify left bottom mirror)
			)
		)
		(fp_text user "Author: Antmicro"
			(at -1.682 -4.894 270)
			(layer "B.Fab")
			(effects
				(font
					(size 0.7 0.7)
					(thickness 0.15)
				)
				(justify left bottom mirror)
			)
		)
		(pad "1" smd roundrect
			(at -0.7 0 90)
			(size 0.8 1)
			(layers "B.Cu" "B.Mask" "B.Paste")
			(roundrect_rratio 0.2)
			(net 1 "GND")
			(pintype "passive")
		)
		(pad "2" smd roundrect
			(at 0.7 0 90)
			(size 0.8 1)
			(layers "B.Cu" "B.Mask" "B.Paste")
			(roundrect_rratio 0.2)
			(net 35 "VDC")
			(pintype "passive")
		)
	)
	(footprint "antmicro-footprints:C_0402_1005Metric"
		(layer "B.Cu")
		(at 207.321 136.0045)
		(descr "Capacitor SMD 0402")
		(tags "capacitor SMD 0402")
		(property "Reference" "C331"
			(at 2.279 0 0)
			(layer "B.SilkS")
			(effects
				(font
					(size 0.7 0.7)
					(thickness 0.15)
				)
				(justify mirror)
			)
		)
		(property "Value" "C_10u_6.3V_0402"
			(at -1.022927 -2.155213 0)
			(layer "B.Fab")
			(effects
				(font
					(size 0.7 0.7)
					(thickness 0.15)
				)
				(justify right top mirror)
			)
		)
		(property "Datasheet" "https://www.murata.com/products/productdetail?partno=GRM155R60J106ME15%23"
			(at 0 0 0)
			(layer "B.Fab")
			(hide yes)
			(effects
				(font
					(size 1.27 1.27)
					(thickness 0.15)
				)
				(justify mirror)
			)
		)
		(property "MPN" "GRM155R60J106ME15D"
			(at 0 0 180)
			(unlocked yes)
			(layer "B.Fab")
			(hide yes)
			(effects
				(font
					(size 1 1)
					(thickness 0.15)
				)
				(justify mirror)
			)
		)
		(property "Manufacturer" "Murata"
			(at 0 0 180)
			(unlocked yes)
			(layer "B.Fab")
			(hide yes)
			(effects
				(font
					(size 1 1)
					(thickness 0.15)
				)
				(justify mirror)
			)
		)
		(property "License" "Apache-2.0"
			(at 0 0 180)
			(unlocked yes)
			(layer "B.Fab")
			(hide yes)
			(effects
				(font
					(size 1 1)
					(thickness 0.15)
				)
				(justify mirror)
			)
		)
		(property "Author" "Antmicro"
			(at 0 0 180)
			(unlocked yes)
			(layer "B.Fab")
			(hide yes)
			(effects
				(font
					(size 1 1)
					(thickness 0.15)
				)
				(justify mirror)
			)
		)
		(property "Val" "10u"
			(at 0 0 180)
			(unlocked yes)
			(layer "B.Fab")
			(hide yes)
			(effects
				(font
					(size 1 1)
					(thickness 0.15)
				)
				(justify mirror)
			)
		)
		(property "Voltage" "6.3V"
			(at 0 0 180)
			(unlocked yes)
			(layer "B.Fab")
			(hide yes)
			(effects
				(font
					(size 1 1)
					(thickness 0.15)
				)
				(justify mirror)
			)
		)
		(property "Dielectric" "X5R"
			(at 0 0 180)
			(unlocked yes)
			(layer "B.Fab")
			(hide yes)
			(effects
				(font
					(size 1 1)
					(thickness 0.15)
				)
				(justify mirror)
			)
		)
		(sheetname "/Supply/")
		(sheetfile "supply.kicad_sch")
		(attr smd)
		(fp_rect
			(start -0.925 0.47)
			(end 0.925 -0.47)
			(stroke
				(width 0.05)
				(type default)
			)
			(fill no)
			(layer "B.CrtYd")
		)
		(fp_line
			(start -0.494 -0.248)
			(end -0.494 0.25)
			(stroke
				(width 0.15)
				(type solid)
			)
			(layer "B.Fab")
		)
		(fp_line
			(start -0.494 0.25)
			(end 0.504 0.25)
			(stroke
				(width 0.15)
				(type solid)
			)
			(layer "B.Fab")
		)
		(fp_line
			(start 0.504 -0.248)
			(end -0.494 -0.248)
			(stroke
				(width 0.15)
				(type solid)
			)
			(layer "B.Fab")
		)
		(fp_line
			(start 0.504 0.25)
			(end 0.504 -0.248)
			(stroke
				(width 0.15)
				(type solid)
			)
			(layer "B.Fab")
		)
		(fp_text user "Author: Antmicro"
			(at -0.939 -3.399 0)
			(layer "B.Fab")
			(effects
				(font
					(size 0.7 0.7)
					(thickness 0.15)
				)
				(justify right top mirror)
			)
		)
		(fp_text user "${REFERENCE}"
			(at -0.939 -4.599 0)
			(layer "B.Fab")
			(effects
				(font
					(size 0.7 0.7)
					(thickness 0.15)
				)
				(justify right top mirror)
			)
		)
		(fp_text user "License: Apache-2.0"
			(at -0.939 -5.799 0)
			(layer "B.Fab")
			(effects
				(font
					(size 0.7 0.7)
					(thickness 0.15)
				)
				(justify right top mirror)
			)
		)
		(pad "1" smd roundrect
			(at -0.48 0)
			(size 0.59 0.64)
			(layers "B.Cu" "B.Mask" "B.Paste")
			(roundrect_rratio 0.25)
			(net 1 "GND")
			(pintype "passive")
		)
		(pad "2" smd roundrect
			(at 0.48 0)
			(size 0.59 0.64)
			(layers "B.Cu" "B.Mask" "B.Paste")
			(roundrect_rratio 0.25)
			(net 687 "VDDQ")
			(pintype "passive")
		)
	)
	(footprint "antmicro-footprints:R_0402_1005Metric"
		(layer "B.Cu")
		(at 133.64 174.35 -90)
		(descr "Resistor SMD 0402")
		(tags "resistor SMD 0402")
		(property "Reference" "R239"
			(at -3.8 -0.47 90)
			(layer "B.SilkS")
			(effects
				(font
					(size 0.7 0.7)
					(thickness 0.15)
				)
				(justify left bottom mirror)
			)
		)
		(property "Value" "R_2k2_0402"
			(at -1.011843 -1.772047 90)
			(layer "B.Fab")
			(effects
				(font
					(size 0.7 0.7)
					(thickness 0.15)
				)
				(justify left bottom mirror)
			)
		)
		(property "Datasheet" "https://www.bourns.com/docs/product-datasheets/cr.pdf"
			(at 0 0 270)
			(layer "F.Fab")
			(hide yes)
			(effects
				(font
					(size 1.27 1.27)
					(thickness 0.15)
				)
			)
		)
		(property "MPN" "CR0402-FX-2201GLF"
			(at 0 0 270)
			(unlocked yes)
			(layer "B.Fab")
			(hide yes)
			(effects
				(font
					(size 1 1)
					(thickness 0.15)
				)
				(justify mirror)
			)
		)
		(property "Manufacturer" "Bourns"
			(at 0 0 270)
			(unlocked yes)
			(layer "B.Fab")
			(hide yes)
			(effects
				(font
					(size 1 1)
					(thickness 0.15)
				)
				(justify mirror)
			)
		)
		(property "License" "Apache-2.0"
			(at 0 0 270)
			(unlocked yes)
			(layer "B.Fab")
			(hide yes)
			(effects
				(font
					(size 1 1)
					(thickness 0.15)
				)
				(justify mirror)
			)
		)
		(property "Author" "Antmicro"
			(at 0 0 270)
			(unlocked yes)
			(layer "B.Fab")
			(hide yes)
			(effects
				(font
					(size 1 1)
					(thickness 0.15)
				)
				(justify mirror)
			)
		)
		(property "Val" "2k2"
			(at 0 0 270)
			(unlocked yes)
			(layer "B.Fab")
			(hide yes)
			(effects
				(font
					(size 1 1)
					(thickness 0.15)
				)
				(justify mirror)
			)
		)
		(property "Tolerance" "1%"
			(at 0 0 270)
			(unlocked yes)
			(layer "B.Fab")
			(hide yes)
			(effects
				(font
					(size 1 1)
					(thickness 0.15)
				)
				(justify mirror)
			)
		)
		(property "Public" ""
			(at 0 0 270)
			(unlocked yes)
			(layer "B.Fab")
			(hide yes)
			(effects
				(font
					(size 1 1)
					(thickness 0.15)
				)
				(justify mirror)
			)
		)
		(sheetname "/HDMI + SD Card/")
		(sheetfile "hdmi-sd-card.kicad_sch")
		(attr smd)
		(fp_rect
			(start -0.925 0.47)
			(end 0.925 -0.47)
			(stroke
				(width 0.05)
				(type default)
			)
			(fill no)
			(layer "B.CrtYd")
		)
		(fp_rect
			(start -0.5 0.25)
			(end 0.5 -0.25)
			(stroke
				(width 0.15)
				(type solid)
			)
			(fill no)
			(layer "B.Fab")
		)
		(fp_text user "${REFERENCE}"
			(at -0.95 -3.168 90)
			(layer "B.Fab")
			(effects
				(font
					(size 0.7 0.7)
					(thickness 0.15)
				)
				(justify left bottom mirror)
			)
		)
		(fp_text user "Author: Antmicro"
			(at -0.95 -4.169 90)
			(layer "B.Fab")
			(effects
				(font
					(size 0.7 0.7)
					(thickness 0.15)
				)
				(justify left bottom mirror)
			)
		)
		(fp_text user "License: Apache-2.0"
			(at -0.95 -5.169 90)
			(layer "B.Fab")
			(effects
				(font
					(size 0.7 0.7)
					(thickness 0.15)
				)
				(justify left bottom mirror)
			)
		)
		(pad "1" smd roundrect
			(at -0.48 0 270)
			(size 0.59 0.64)
			(layers "B.Cu" "B.Mask" "B.Paste")
			(roundrect_rratio 0.25)
			(net 768 "/FPGA MGT Interface/HDMI_CTL.SCL")
			(pintype "passive")
		)
		(pad "2" smd roundrect
			(at 0.48 0 270)
			(size 0.59 0.64)
			(layers "B.Cu" "B.Mask" "B.Paste")
			(roundrect_rratio 0.25)
			(net 151 "+3V3")
			(pintype "passive")
		)
	)
	(footprint "antmicro-footprints:C_0402_1005Metric_EIA"
		(layer "B.Cu")
		(at 187 148.499999 -90)
		(descr "Capacitor SMD 0402 (1005 Metric), square (rectangular) end terminal, IPC_7351 nominal, (Body size source: IPC-SM-782 page 76, https://www.pcb-3d.com/wordpress/wp-content/uploads/ipc-sm-782a_amendment_1_and_2.pdf)")
		(tags "capacitor 0402")
		(property "Reference" "C40"
			(at -11.699999 30.625 90)
			(layer "B.SilkS")
			(effects
				(font
					(size 0.7 0.7)
					(thickness 0.15)
				)
				(justify left bottom mirror)
			)
		)
		(property "Value" "C_1u_25V_0402"
			(at 0 -1.169 90)
			(layer "B.Fab")
			(effects
				(font
					(size 0.7 0.7)
					(thickness 0.15)
				)
				(justify left bottom mirror)
			)
		)
		(property "Datasheet" "https://www.murata.com/products/productdetail?partno=GRM155R61E105KE11%23"
			(at 0 0 270)
			(layer "F.Fab")
			(hide yes)
			(effects
				(font
					(size 1.27 1.27)
					(thickness 0.15)
				)
			)
		)
		(property "MPN" "GRM155R61E105KE11J"
			(at 0 0 270)
			(unlocked yes)
			(layer "B.Fab")
			(hide yes)
			(effects
				(font
					(size 1 1)
					(thickness 0.15)
				)
				(justify mirror)
			)
		)
		(property "Manufacturer" "Murata"
			(at 0 0 270)
			(unlocked yes)
			(layer "B.Fab")
			(hide yes)
			(effects
				(font
					(size 1 1)
					(thickness 0.15)
				)
				(justify mirror)
			)
		)
		(property "License" "Apache-2.0"
			(at 0 0 270)
			(unlocked yes)
			(layer "B.Fab")
			(hide yes)
			(effects
				(font
					(size 1 1)
					(thickness 0.15)
				)
				(justify mirror)
			)
		)
		(property "Author" "Antmicro"
			(at 0 0 270)
			(unlocked yes)
			(layer "B.Fab")
			(hide yes)
			(effects
				(font
					(size 1 1)
					(thickness 0.15)
				)
				(justify mirror)
			)
		)
		(property "Val" "1u"
			(at 0 0 270)
			(unlocked yes)
			(layer "B.Fab")
			(hide yes)
			(effects
				(font
					(size 1 1)
					(thickness 0.15)
				)
				(justify mirror)
			)
		)
		(property "Voltage" "25V"
			(at 0 0 270)
			(unlocked yes)
			(layer "B.Fab")
			(hide yes)
			(effects
				(font
					(size 1 1)
					(thickness 0.15)
				)
				(justify mirror)
			)
		)
		(property "Dielectric" "X5R"
			(at 0 0 270)
			(unlocked yes)
			(layer "B.Fab")
			(hide yes)
			(effects
				(font
					(size 1 1)
					(thickness 0.15)
				)
				(justify mirror)
			)
		)
		(sheetname "/FPGA power/")
		(sheetfile "fpga-power.kicad_sch")
		(attr smd)
		(fp_rect
			(start -0.95 0.45)
			(end 0.95 -0.45)
			(stroke
				(width 0.05)
				(type default)
			)
			(fill no)
			(layer "B.CrtYd")
		)
		(fp_line
			(start -0.5 0.25)
			(end 0.498 0.25)
			(stroke
				(width 0.15)
				(type solid)
			)
			(layer "B.Fab")
		)
		(fp_line
			(start 0.498 0.25)
			(end 0.498 -0.248)
			(stroke
				(width 0.15)
				(type solid)
			)
			(layer "B.Fab")
		)
		(fp_line
			(start -0.5 -0.248)
			(end -0.5 0.25)
			(stroke
				(width 0.15)
				(type solid)
			)
			(layer "B.Fab")
		)
		(fp_line
			(start 0.498 -0.248)
			(end -0.5 -0.248)
			(stroke
				(width 0.15)
				(type solid)
			)
			(layer "B.Fab")
		)
		(fp_text user "License: Apache-2.0"
			(at -0.9656 -4.369 90)
			(layer "B.Fab")
			(effects
				(font
					(size 0.7 0.7)
					(thickness 0.15)
				)
				(justify left bottom mirror)
			)
		)
		(fp_text user "Author: Antmicro"
			(at -0.9656 -5.569 90)
			(layer "B.Fab")
			(effects
				(font
					(size 0.7 0.7)
					(thickness 0.15)
				)
				(justify left bottom mirror)
			)
		)
		(fp_text user "${REFERENCE}"
			(at -0.9656 -3.169 90)
			(layer "B.Fab")
			(effects
				(font
					(size 0.7 0.7)
					(thickness 0.15)
				)
				(justify left bottom mirror)
			)
		)
		(pad "1" smd roundrect
			(at -0.5 0 180)
			(size 0.6 0.6)
			(layers "B.Cu" "B.Mask" "B.Paste")
			(roundrect_rratio 0.25)
			(net 1 "GND")
			(pintype "passive")
		)
		(pad "2" smd roundrect
			(at 0.498 0 270)
			(size 0.6 0.6)
			(layers "B.Cu" "B.Mask" "B.Paste")
			(roundrect_rratio 0.25)
			(net 553 "+0V85")
			(pintype "passive")
		)
	)
	(footprint "antmicro-footprints:C_0402_1005Metric"
		(layer "B.Cu")
		(at 124.2 164.05 180)
		(descr "Capacitor SMD 0402")
		(tags "capacitor SMD 0402")
		(property "Reference" "C296"
			(at -4.05 -0.35 0)
			(layer "B.SilkS")
			(effects
				(font
					(size 0.7 0.7)
					(thickness 0.15)
				)
				(justify left bottom mirror)
			)
		)
		(property "Value" "C_100n_0402"
			(at -1.022927 -2.155213 0)
			(layer "B.Fab")
			(effects
				(font
					(size 0.7 0.7)
					(thickness 0.15)
				)
				(justify left bottom mirror)
			)
		)
		(property "Datasheet" "https://www.murata.com/products/productdetail?partno=GRM155R61H104KE14%23"
			(at 0 0 180)
			(layer "F.Fab")
			(hide yes)
			(effects
				(font
					(size 1.27 1.27)
					(thickness 0.15)
				)
			)
		)
		(property "MPN" "GRM155R61H104KE14D"
			(at 0 0 180)
			(unlocked yes)
			(layer "B.Fab")
			(hide yes)
			(effects
				(font
					(size 1 1)
					(thickness 0.15)
				)
				(justify mirror)
			)
		)
		(property "Manufacturer" "Murata"
			(at 0 0 180)
			(unlocked yes)
			(layer "B.Fab")
			(hide yes)
			(effects
				(font
					(size 1 1)
					(thickness 0.15)
				)
				(justify mirror)
			)
		)
		(property "License" "Apache-2.0"
			(at 0 0 180)
			(unlocked yes)
			(layer "B.Fab")
			(hide yes)
			(effects
				(font
					(size 1 1)
					(thickness 0.15)
				)
				(justify mirror)
			)
		)
		(property "Author" "Antmicro"
			(at 0 0 180)
			(unlocked yes)
			(layer "B.Fab")
			(hide yes)
			(effects
				(font
					(size 1 1)
					(thickness 0.15)
				)
				(justify mirror)
			)
		)
		(property "Val" "100n"
			(at 0 0 180)
			(unlocked yes)
			(layer "B.Fab")
			(hide yes)
			(effects
				(font
					(size 1 1)
					(thickness 0.15)
				)
				(justify mirror)
			)
		)
		(property "Voltage" "50V"
			(at 0 0 180)
			(unlocked yes)
			(layer "B.Fab")
			(hide yes)
			(effects
				(font
					(size 1 1)
					(thickness 0.15)
				)
				(justify mirror)
			)
		)
		(property "Dielectric" "X5R"
			(at 0 0 180)
			(unlocked yes)
			(layer "B.Fab")
			(hide yes)
			(effects
				(font
					(size 1 1)
					(thickness 0.15)
				)
				(justify mirror)
			)
		)
		(sheetname "/HDMI + SD Card/")
		(sheetfile "hdmi-sd-card.kicad_sch")
		(attr smd)
		(fp_rect
			(start -0.925 0.47)
			(end 0.925 -0.47)
			(stroke
				(width 0.05)
				(type default)
			)
			(fill no)
			(layer "B.CrtYd")
		)
		(fp_line
			(start 0.504 0.25)
			(end 0.504 -0.248)
			(stroke
				(width 0.15)
				(type solid)
			)
			(layer "B.Fab")
		)
		(fp_line
			(start 0.504 -0.248)
			(end -0.494 -0.248)
			(stroke
				(width 0.15)
				(type solid)
			)
			(layer "B.Fab")
		)
		(fp_line
			(start -0.494 0.25)
			(end 0.504 0.25)
			(stroke
				(width 0.15)
				(type solid)
			)
			(layer "B.Fab")
		)
		(fp_line
			(start -0.494 -0.248)
			(end -0.494 0.25)
			(stroke
				(width 0.15)
				(type solid)
			)
			(layer "B.Fab")
		)
		(fp_text user "${REFERENCE}"
			(at -0.939 -4.599 0)
			(layer "B.Fab")
			(effects
				(font
					(size 0.7 0.7)
					(thickness 0.15)
				)
				(justify left bottom mirror)
			)
		)
		(fp_text user "Author: Antmicro"
			(at -0.939 -3.399 0)
			(layer "B.Fab")
			(effects
				(font
					(size 0.7 0.7)
					(thickness 0.15)
				)
				(justify left bottom mirror)
			)
		)
		(fp_text user "License: Apache-2.0"
			(at -0.939 -5.799 0)
			(layer "B.Fab")
			(effects
				(font
					(size 0.7 0.7)
					(thickness 0.15)
				)
				(justify left bottom mirror)
			)
		)
		(pad "1" smd roundrect
			(at -0.48 0 180)
			(size 0.59 0.64)
			(layers "B.Cu" "B.Mask" "B.Paste")
			(roundrect_rratio 0.25)
			(net 1 "GND")
			(pintype "passive")
		)
		(pad "2" smd roundrect
			(at 0.48 0 180)
			(size 0.59 0.64)
			(layers "B.Cu" "B.Mask" "B.Paste")
			(roundrect_rratio 0.25)
			(net 797 "+1V8")
			(pintype "passive")
		)
	)
	(footprint "antmicro-footprints:C_0402_1005Metric_EIA"
		(layer "B.Cu")
		(at 184.498 157)
		(descr "Capacitor SMD 0402 (1005 Metric), square (rectangular) end terminal, IPC_7351 nominal, (Body size source: IPC-SM-782 page 76, https://www.pcb-3d.com/wordpress/wp-content/uploads/ipc-sm-782a_amendment_1_and_2.pdf)")
		(tags "capacitor 0402")
		(property "Reference" "C53"
			(at -32.248 -10.525 0)
			(layer "B.SilkS")
			(effects
				(font
					(size 0.7 0.7)
					(thickness 0.15)
				)
				(justify right bottom mirror)
			)
		)
		(property "Value" "C_1u_25V_0402"
			(at 0 -1.169 0)
			(layer "B.Fab")
			(effects
				(font
					(size 0.7 0.7)
					(thickness 0.15)
				)
				(justify right bottom mirror)
			)
		)
		(property "Datasheet" "https://www.murata.com/products/productdetail?partno=GRM155R61E105KE11%23"
			(at 0 0 0)
			(layer "F.Fab")
			(hide yes)
			(effects
				(font
					(size 1.27 1.27)
					(thickness 0.15)
				)
			)
		)
		(property "MPN" "GRM155R61E105KE11J"
			(at 0 0 0)
			(unlocked yes)
			(layer "B.Fab")
			(hide yes)
			(effects
				(font
					(size 1 1)
					(thickness 0.15)
				)
				(justify mirror)
			)
		)
		(property "Manufacturer" "Murata"
			(at 0 0 0)
			(unlocked yes)
			(layer "B.Fab")
			(hide yes)
			(effects
				(font
					(size 1 1)
					(thickness 0.15)
				)
				(justify mirror)
			)
		)
		(property "License" "Apache-2.0"
			(at 0 0 0)
			(unlocked yes)
			(layer "B.Fab")
			(hide yes)
			(effects
				(font
					(size 1 1)
					(thickness 0.15)
				)
				(justify mirror)
			)
		)
		(property "Author" "Antmicro"
			(at 0 0 0)
			(unlocked yes)
			(layer "B.Fab")
			(hide yes)
			(effects
				(font
					(size 1 1)
					(thickness 0.15)
				)
				(justify mirror)
			)
		)
		(property "Val" "1u"
			(at 0 0 0)
			(unlocked yes)
			(layer "B.Fab")
			(hide yes)
			(effects
				(font
					(size 1 1)
					(thickness 0.15)
				)
				(justify mirror)
			)
		)
		(property "Voltage" "25V"
			(at 0 0 0)
			(unlocked yes)
			(layer "B.Fab")
			(hide yes)
			(effects
				(font
					(size 1 1)
					(thickness 0.15)
				)
				(justify mirror)
			)
		)
		(property "Dielectric" "X5R"
			(at 0 0 0)
			(unlocked yes)
			(layer "B.Fab")
			(hide yes)
			(effects
				(font
					(size 1 1)
					(thickness 0.15)
				)
				(justify mirror)
			)
		)
		(sheetname "/FPGA power/")
		(sheetfile "fpga-power.kicad_sch")
		(attr smd)
		(fp_rect
			(start -0.95 0.45)
			(end 0.95 -0.45)
			(stroke
				(width 0.05)
				(type default)
			)
			(fill no)
			(layer "B.CrtYd")
		)
		(fp_line
			(start -0.5 -0.248)
			(end -0.5 0.25)
			(stroke
				(width 0.15)
				(type solid)
			)
			(layer "B.Fab")
		)
		(fp_line
			(start -0.5 0.25)
			(end 0.498 0.25)
			(stroke
				(width 0.15)
				(type solid)
			)
			(layer "B.Fab")
		)
		(fp_line
			(start 0.498 -0.248)
			(end -0.5 -0.248)
			(stroke
				(width 0.15)
				(type solid)
			)
			(layer "B.Fab")
		)
		(fp_line
			(start 0.498 0.25)
			(end 0.498 -0.248)
			(stroke
				(width 0.15)
				(type solid)
			)
			(layer "B.Fab")
		)
		(fp_text user "License: Apache-2.0"
			(at -0.9656 -4.369 180)
			(layer "B.Fab")
			(effects
				(font
					(size 0.7 0.7)
					(thickness 0.15)
				)
				(justify left bottom mirror)
			)
		)
		(fp_text user "${REFERENCE}"
			(at -0.9656 -3.169 180)
			(layer "B.Fab")
			(effects
				(font
					(size 0.7 0.7)
					(thickness 0.15)
				)
				(justify left bottom mirror)
			)
		)
		(fp_text user "Author: Antmicro"
			(at -0.9656 -5.569 180)
			(layer "B.Fab")
			(effects
				(font
					(size 0.7 0.7)
					(thickness 0.15)
				)
				(justify left bottom mirror)
			)
		)
		(pad "1" smd roundrect
			(at -0.5 0 270)
			(size 0.6 0.6)
			(layers "B.Cu" "B.Mask" "B.Paste")
			(roundrect_rratio 0.25)
			(net 1 "GND")
			(pintype "passive")
		)
		(pad "2" smd roundrect
			(at 0.498 0)
			(size 0.6 0.6)
			(layers "B.Cu" "B.Mask" "B.Paste")
			(roundrect_rratio 0.25)
			(net 553 "+0V85")
			(pintype "passive")
		)
	)
	(footprint "antmicro-footprints:C_0402_1005Metric"
		(layer "B.Cu")
		(at 159.624499 193.228 -90)
		(descr "Capacitor SMD 0402")
		(tags "capacitor SMD 0402")
		(property "Reference" "C258"
			(at -3.774 -0.435501 90)
			(layer "B.SilkS")
			(effects
				(font
					(size 0.7 0.7)
					(thickness 0.15)
				)
				(justify left bottom mirror)
			)
		)
		(property "Value" "C_10n_0402"
			(at -1.022927 -2.155213 90)
			(layer "B.Fab")
			(effects
				(font
					(size 0.7 0.7)
					(thickness 0.15)
				)
				(justify left bottom mirror)
			)
		)
		(property "Datasheet" "https://www.murata.com/products/productdetail?partno=GRM155R71H103KA88%23"
			(at 0 0 270)
			(layer "F.Fab")
			(hide yes)
			(effects
				(font
					(size 1.27 1.27)
					(thickness 0.15)
				)
			)
		)
		(property "MPN" "GRM155R71H103KA88D"
			(at 0 0 270)
			(unlocked yes)
			(layer "B.Fab")
			(hide yes)
			(effects
				(font
					(size 1 1)
					(thickness 0.15)
				)
				(justify mirror)
			)
		)
		(property "Manufacturer" "Murata"
			(at 0 0 270)
			(unlocked yes)
			(layer "B.Fab")
			(hide yes)
			(effects
				(font
					(size 1 1)
					(thickness 0.15)
				)
				(justify mirror)
			)
		)
		(property "License" "Apache-2.0"
			(at 0 0 270)
			(unlocked yes)
			(layer "B.Fab")
			(hide yes)
			(effects
				(font
					(size 1 1)
					(thickness 0.15)
				)
				(justify mirror)
			)
		)
		(property "Author" "Antmicro"
			(at 0 0 270)
			(unlocked yes)
			(layer "B.Fab")
			(hide yes)
			(effects
				(font
					(size 1 1)
					(thickness 0.15)
				)
				(justify mirror)
			)
		)
		(property "Val" "10n"
			(at 0 0 270)
			(unlocked yes)
			(layer "B.Fab")
			(hide yes)
			(effects
				(font
					(size 1 1)
					(thickness 0.15)
				)
				(justify mirror)
			)
		)
		(property "Voltage" "50V"
			(at 0 0 270)
			(unlocked yes)
			(layer "B.Fab")
			(hide yes)
			(effects
				(font
					(size 1 1)
					(thickness 0.15)
				)
				(justify mirror)
			)
		)
		(property "Dielectric" "X7R"
			(at 0 0 270)
			(unlocked yes)
			(layer "B.Fab")
			(hide yes)
			(effects
				(font
					(size 1 1)
					(thickness 0.15)
				)
				(justify mirror)
			)
		)
		(sheetname "/FPGA MGT Interface/")
		(sheetfile "fpga-mgt.kicad_sch")
		(attr smd)
		(fp_rect
			(start -0.925 0.47)
			(end 0.925 -0.47)
			(stroke
				(width 0.05)
				(type default)
			)
			(fill no)
			(layer "B.CrtYd")
		)
		(fp_line
			(start -0.494 0.25)
			(end 0.504 0.25)
			(stroke
				(width 0.15)
				(type solid)
			)
			(layer "B.Fab")
		)
		(fp_line
			(start 0.504 0.25)
			(end 0.504 -0.248)
			(stroke
				(width 0.15)
				(type solid)
			)
			(layer "B.Fab")
		)
		(fp_line
			(start -0.494 -0.248)
			(end -0.494 0.25)
			(stroke
				(width 0.15)
				(type solid)
			)
			(layer "B.Fab")
		)
		(fp_line
			(start 0.504 -0.248)
			(end -0.494 -0.248)
			(stroke
				(width 0.15)
				(type solid)
			)
			(layer "B.Fab")
		)
		(fp_text user "License: Apache-2.0"
			(at -0.939 -5.799 90)
			(layer "B.Fab")
			(effects
				(font
					(size 0.7 0.7)
					(thickness 0.15)
				)
				(justify left bottom mirror)
			)
		)
		(fp_text user "${REFERENCE}"
			(at -0.939 -4.599 90)
			(layer "B.Fab")
			(effects
				(font
					(size 0.7 0.7)
					(thickness 0.15)
				)
				(justify left bottom mirror)
			)
		)
		(fp_text user "Author: Antmicro"
			(at -0.939 -3.399 90)
			(layer "B.Fab")
			(effects
				(font
					(size 0.7 0.7)
					(thickness 0.15)
				)
				(justify left bottom mirror)
			)
		)
		(pad "1" smd roundrect
			(at -0.48 0 270)
			(size 0.59 0.64)
			(layers "B.Cu" "B.Mask" "B.Paste")
			(roundrect_rratio 0.25)
			(net 12 "/FPGA MGT Interface/GTR_REFCLK0_P")
			(pintype "passive")
		)
		(pad "2" smd roundrect
			(at 0.48 0 270)
			(size 0.59 0.64)
			(layers "B.Cu" "B.Mask" "B.Paste")
			(roundrect_rratio 0.25)
			(net 11 "/FPGA MGT Interface/PCIE.CLK_P")
			(pintype "passive")
		)
	)
	(footprint "antmicro-footprints:C_0402_1005Metric_EIA"
		(layer "B.Cu")
		(at 187 154.499999 -90)
		(descr "Capacitor SMD 0402 (1005 Metric), square (rectangular) end terminal, IPC_7351 nominal, (Body size source: IPC-SM-782 page 76, https://www.pcb-3d.com/wordpress/wp-content/uploads/ipc-sm-782a_amendment_1_and_2.pdf)")
		(tags "capacitor 0402")
		(property "Reference" "C45"
			(at -12.024999 30.625 90)
			(layer "B.SilkS")
			(effects
				(font
					(size 0.7 0.7)
					(thickness 0.15)
				)
				(justify left bottom mirror)
			)
		)
		(property "Value" "C_1u_25V_0402"
			(at 0 -1.169 90)
			(layer "B.Fab")
			(effects
				(font
					(size 0.7 0.7)
					(thickness 0.15)
				)
				(justify left bottom mirror)
			)
		)
		(property "Datasheet" "https://www.murata.com/products/productdetail?partno=GRM155R61E105KE11%23"
			(at 0 0 270)
			(layer "F.Fab")
			(hide yes)
			(effects
				(font
					(size 1.27 1.27)
					(thickness 0.15)
				)
			)
		)
		(property "MPN" "GRM155R61E105KE11J"
			(at 0 0 270)
			(unlocked yes)
			(layer "B.Fab")
			(hide yes)
			(effects
				(font
					(size 1 1)
					(thickness 0.15)
				)
				(justify mirror)
			)
		)
		(property "Manufacturer" "Murata"
			(at 0 0 270)
			(unlocked yes)
			(layer "B.Fab")
			(hide yes)
			(effects
				(font
					(size 1 1)
					(thickness 0.15)
				)
				(justify mirror)
			)
		)
		(property "License" "Apache-2.0"
			(at 0 0 270)
			(unlocked yes)
			(layer "B.Fab")
			(hide yes)
			(effects
				(font
					(size 1 1)
					(thickness 0.15)
				)
				(justify mirror)
			)
		)
		(property "Author" "Antmicro"
			(at 0 0 270)
			(unlocked yes)
			(layer "B.Fab")
			(hide yes)
			(effects
				(font
					(size 1 1)
					(thickness 0.15)
				)
				(justify mirror)
			)
		)
		(property "Val" "1u"
			(at 0 0 270)
			(unlocked yes)
			(layer "B.Fab")
			(hide yes)
			(effects
				(font
					(size 1 1)
					(thickness 0.15)
				)
				(justify mirror)
			)
		)
		(property "Voltage" "25V"
			(at 0 0 270)
			(unlocked yes)
			(layer "B.Fab")
			(hide yes)
			(effects
				(font
					(size 1 1)
					(thickness 0.15)
				)
				(justify mirror)
			)
		)
		(property "Dielectric" "X5R"
			(at 0 0 270)
			(unlocked yes)
			(layer "B.Fab")
			(hide yes)
			(effects
				(font
					(size 1 1)
					(thickness 0.15)
				)
				(justify mirror)
			)
		)
		(sheetname "/FPGA power/")
		(sheetfile "fpga-power.kicad_sch")
		(attr smd)
		(fp_rect
			(start -0.95 0.45)
			(end 0.95 -0.45)
			(stroke
				(width 0.05)
				(type default)
			)
			(fill no)
			(layer "B.CrtYd")
		)
		(fp_line
			(start -0.5 0.25)
			(end 0.498 0.25)
			(stroke
				(width 0.15)
				(type solid)
			)
			(layer "B.Fab")
		)
		(fp_line
			(start 0.498 0.25)
			(end 0.498 -0.248)
			(stroke
				(width 0.15)
				(type solid)
			)
			(layer "B.Fab")
		)
		(fp_line
			(start -0.5 -0.248)
			(end -0.5 0.25)
			(stroke
				(width 0.15)
				(type solid)
			)
			(layer "B.Fab")
		)
		(fp_line
			(start 0.498 -0.248)
			(end -0.5 -0.248)
			(stroke
				(width 0.15)
				(type solid)
			)
			(layer "B.Fab")
		)
		(fp_text user "Author: Antmicro"
			(at -0.9656 -5.569 90)
			(layer "B.Fab")
			(effects
				(font
					(size 0.7 0.7)
					(thickness 0.15)
				)
				(justify left bottom mirror)
			)
		)
		(fp_text user "License: Apache-2.0"
			(at -0.9656 -4.369 90)
			(layer "B.Fab")
			(effects
				(font
					(size 0.7 0.7)
					(thickness 0.15)
				)
				(justify left bottom mirror)
			)
		)
		(fp_text user "${REFERENCE}"
			(at -0.9656 -3.169 90)
			(layer "B.Fab")
			(effects
				(font
					(size 0.7 0.7)
					(thickness 0.15)
				)
				(justify left bottom mirror)
			)
		)
		(pad "1" smd roundrect
			(at -0.5 0 180)
			(size 0.6 0.6)
			(layers "B.Cu" "B.Mask" "B.Paste")
			(roundrect_rratio 0.25)
			(net 1 "GND")
			(pintype "passive")
		)
		(pad "2" smd roundrect
			(at 0.498 0 270)
			(size 0.6 0.6)
			(layers "B.Cu" "B.Mask" "B.Paste")
			(roundrect_rratio 0.25)
			(net 553 "+0V85")
			(pintype "passive")
		)
	)
	(footprint "antmicro-footprints:C_0402_1005Metric"
		(layer "B.Cu")
		(at 260.574499 173.799 -90)
		(descr "Capacitor SMD 0402")
		(tags "capacitor SMD 0402")
		(property "Reference" "C172"
			(at -1.799 -1.575501 90)
			(layer "B.SilkS")
			(effects
				(font
					(size 0.7 0.7)
					(thickness 0.15)
				)
				(justify left bottom mirror)
			)
		)
		(property "Value" "C_1u_0402"
			(at -1.022927 -2.155213 90)
			(layer "B.Fab")
			(effects
				(font
					(size 0.7 0.7)
					(thickness 0.15)
				)
				(justify left bottom mirror)
			)
		)
		(property "Datasheet" "https://product.tdk.com/en/search/capacitor/ceramic/mlcc/info?part_no=C1005X6S1A105K050BC"
			(at 0 0 270)
			(layer "F.Fab")
			(hide yes)
			(effects
				(font
					(size 1.27 1.27)
					(thickness 0.15)
				)
			)
		)
		(property "Manufacturer" "TDK"
			(at 0 0 270)
			(unlocked yes)
			(layer "B.Fab")
			(hide yes)
			(effects
				(font
					(size 1 1)
					(thickness 0.15)
				)
				(justify mirror)
			)
		)
		(property "MPN" "C1005X6S1A105K050BC"
			(at 0 0 270)
			(unlocked yes)
			(layer "B.Fab")
			(hide yes)
			(effects
				(font
					(size 1 1)
					(thickness 0.15)
				)
				(justify mirror)
			)
		)
		(property "Val" "1u"
			(at 0 0 270)
			(unlocked yes)
			(layer "B.Fab")
			(hide yes)
			(effects
				(font
					(size 1 1)
					(thickness 0.15)
				)
				(justify mirror)
			)
		)
		(property "License" "Apache-2.0"
			(at 0 0 270)
			(unlocked yes)
			(layer "B.Fab")
			(hide yes)
			(effects
				(font
					(size 1 1)
					(thickness 0.15)
				)
				(justify mirror)
			)
		)
		(property "Author" "Antmicro"
			(at 0 0 270)
			(unlocked yes)
			(layer "B.Fab")
			(hide yes)
			(effects
				(font
					(size 1 1)
					(thickness 0.15)
				)
				(justify mirror)
			)
		)
		(property "Voltage" ""
			(at 0 0 270)
			(unlocked yes)
			(layer "B.Fab")
			(hide yes)
			(effects
				(font
					(size 1 1)
					(thickness 0.15)
				)
				(justify mirror)
			)
		)
		(property "Dielectric" ""
			(at 0 0 270)
			(unlocked yes)
			(layer "B.Fab")
			(hide yes)
			(effects
				(font
					(size 1 1)
					(thickness 0.15)
				)
				(justify mirror)
			)
		)
		(sheetname "/Supply/DC-DC AUX, MGT/")
		(sheetfile "dc-dc-aux-mgt.kicad_sch")
		(attr smd)
		(fp_rect
			(start -0.925 0.47)
			(end 0.925 -0.47)
			(stroke
				(width 0.05)
				(type default)
			)
			(fill no)
			(layer "B.CrtYd")
		)
		(fp_line
			(start -0.494 0.25)
			(end 0.504 0.25)
			(stroke
				(width 0.15)
				(type solid)
			)
			(layer "B.Fab")
		)
		(fp_line
			(start 0.504 0.25)
			(end 0.504 -0.248)
			(stroke
				(width 0.15)
				(type solid)
			)
			(layer "B.Fab")
		)
		(fp_line
			(start -0.494 -0.248)
			(end -0.494 0.25)
			(stroke
				(width 0.15)
				(type solid)
			)
			(layer "B.Fab")
		)
		(fp_line
			(start 0.504 -0.248)
			(end -0.494 -0.248)
			(stroke
				(width 0.15)
				(type solid)
			)
			(layer "B.Fab")
		)
		(fp_text user "License: Apache-2.0"
			(at -0.939 -5.799 90)
			(layer "B.Fab")
			(effects
				(font
					(size 0.7 0.7)
					(thickness 0.15)
				)
				(justify left bottom mirror)
			)
		)
		(fp_text user "${REFERENCE}"
			(at -0.939 -4.599 90)
			(layer "B.Fab")
			(effects
				(font
					(size 0.7 0.7)
					(thickness 0.15)
				)
				(justify left bottom mirror)
			)
		)
		(fp_text user "Author: Antmicro"
			(at -0.939 -3.399 90)
			(layer "B.Fab")
			(effects
				(font
					(size 0.7 0.7)
					(thickness 0.15)
				)
				(justify left bottom mirror)
			)
		)
		(pad "1" smd roundrect
			(at -0.48 0 270)
			(size 0.59 0.64)
			(layers "B.Cu" "B.Mask" "B.Paste")
			(roundrect_rratio 0.25)
			(net 1 "GND")
			(pintype "passive")
		)
		(pad "2" smd roundrect
			(at 0.48 0 270)
			(size 0.59 0.64)
			(layers "B.Cu" "B.Mask" "B.Paste")
			(roundrect_rratio 0.25)
			(net 9 "/Supply/DC-DC AUX, MGT/QDCDC1_VCC")
			(pintype "passive")
		)
	)
	(footprint "antmicro-footprints:C_0402_1005Metric"
		(layer "B.Cu")
		(at 171.65 193.299501 90)
		(descr "Capacitor SMD 0402")
		(tags "capacitor SMD 0402")
		(property "Reference" "C227"
			(at 0.994 0.403501 90)
			(layer "B.SilkS")
			(effects
				(font
					(size 0.7 0.7)
					(thickness 0.15)
				)
				(justify right bottom mirror)
			)
		)
		(property "Value" "C_100n_0402"
			(at -1.022927 -2.155213 90)
			(layer "B.Fab")
			(effects
				(font
					(size 0.7 0.7)
					(thickness 0.15)
				)
				(justify right bottom mirror)
			)
		)
		(property "Datasheet" "https://www.murata.com/products/productdetail?partno=GRM155R61H104KE14%23"
			(at 0 0 90)
			(layer "F.Fab")
			(hide yes)
			(effects
				(font
					(size 1.27 1.27)
					(thickness 0.15)
				)
			)
		)
		(property "Manufacturer" "Murata"
			(at 0 0 90)
			(unlocked yes)
			(layer "B.Fab")
			(hide yes)
			(effects
				(font
					(size 1 1)
					(thickness 0.15)
				)
				(justify mirror)
			)
		)
		(property "MPN" "GRM155R61H104KE14D"
			(at 0 0 90)
			(unlocked yes)
			(layer "B.Fab")
			(hide yes)
			(effects
				(font
					(size 1 1)
					(thickness 0.15)
				)
				(justify mirror)
			)
		)
		(property "Val" "100n"
			(at 0 0 90)
			(unlocked yes)
			(layer "B.Fab")
			(hide yes)
			(effects
				(font
					(size 1 1)
					(thickness 0.15)
				)
				(justify mirror)
			)
		)
		(property "License" "Apache-2.0"
			(at 0 0 90)
			(unlocked yes)
			(layer "B.Fab")
			(hide yes)
			(effects
				(font
					(size 1 1)
					(thickness 0.15)
				)
				(justify mirror)
			)
		)
		(property "Author" "Antmicro"
			(at 0 0 90)
			(unlocked yes)
			(layer "B.Fab")
			(hide yes)
			(effects
				(font
					(size 1 1)
					(thickness 0.15)
				)
				(justify mirror)
			)
		)
		(property "Voltage" "50V"
			(at 0 0 90)
			(unlocked yes)
			(layer "B.Fab")
			(hide yes)
			(effects
				(font
					(size 1 1)
					(thickness 0.15)
				)
				(justify mirror)
			)
		)
		(property "Dielectric" "X5R"
			(at 0 0 90)
			(unlocked yes)
			(layer "B.Fab")
			(hide yes)
			(effects
				(font
					(size 1 1)
					(thickness 0.15)
				)
				(justify mirror)
			)
		)
		(sheetname "/FPGA MGT Interface/")
		(sheetfile "fpga-mgt.kicad_sch")
		(attr smd)
		(fp_rect
			(start -0.925 0.47)
			(end 0.925 -0.47)
			(stroke
				(width 0.05)
				(type default)
			)
			(fill no)
			(layer "B.CrtYd")
		)
		(fp_line
			(start 0.504 -0.248)
			(end -0.494 -0.248)
			(stroke
				(width 0.15)
				(type solid)
			)
			(layer "B.Fab")
		)
		(fp_line
			(start -0.494 -0.248)
			(end -0.494 0.25)
			(stroke
				(width 0.15)
				(type solid)
			)
			(layer "B.Fab")
		)
		(fp_line
			(start 0.504 0.25)
			(end 0.504 -0.248)
			(stroke
				(width 0.15)
				(type solid)
			)
			(layer "B.Fab")
		)
		(fp_line
			(start -0.494 0.25)
			(end 0.504 0.25)
			(stroke
				(width 0.15)
				(type solid)
			)
			(layer "B.Fab")
		)
		(fp_text user "Author: Antmicro"
			(at -0.939 -3.399 270)
			(layer "B.Fab")
			(effects
				(font
					(size 0.7 0.7)
					(thickness 0.15)
				)
				(justify left bottom mirror)
			)
		)
		(fp_text user "License: Apache-2.0"
			(at -0.939 -5.799 270)
			(layer "B.Fab")
			(effects
				(font
					(size 0.7 0.7)
					(thickness 0.15)
				)
				(justify left bottom mirror)
			)
		)
		(fp_text user "${REFERENCE}"
			(at -0.939 -4.599 270)
			(layer "B.Fab")
			(effects
				(font
					(size 0.7 0.7)
					(thickness 0.15)
				)
				(justify left bottom mirror)
			)
		)
		(pad "1" smd roundrect
			(at -0.48 0 90)
			(size 0.59 0.64)
			(layers "B.Cu" "B.Mask" "B.Paste")
			(roundrect_rratio 0.25)
			(net 17 "/FPGA MGT Interface/PCIE.TXD2_P")
			(pintype "passive")
		)
		(pad "2" smd roundrect
			(at 0.48 0 90)
			(size 0.59 0.64)
			(layers "B.Cu" "B.Mask" "B.Paste")
			(roundrect_rratio 0.25)
			(net 18 "/FPGA MGT Interface/GTY_225_TX1_P")
			(pintype "passive")
		)
	)
	(footprint "antmicro-footprints:R_0402_1005Metric"
		(layer "B.Cu")
		(at 117.12 140.5 180)
		(descr "Resistor SMD 0402")
		(tags "resistor SMD 0402")
		(property "Reference" "R251"
			(at -1.28 0.6 0)
			(layer "B.SilkS")
			(effects
				(font
					(size 0.7 0.7)
					(thickness 0.15)
				)
				(justify left bottom mirror)
			)
		)
		(property "Value" "R_0R_0402"
			(at -1.011843 -1.772047 0)
			(layer "B.Fab")
			(effects
				(font
					(size 0.7 0.7)
					(thickness 0.15)
				)
				(justify left bottom mirror)
			)
		)
		(property "Datasheet" "https://industrial.panasonic.com/cdbs/www-data/pdf/RDA0000/AOA0000C301.pdf"
			(at 0 0 0)
			(layer "B.Fab")
			(hide yes)
			(effects
				(font
					(size 1.27 1.27)
					(thickness 0.15)
				)
				(justify mirror)
			)
		)
		(property "Description" "SMD Chip Resistor, Jumper, 0 ohm, 100 mW, 0402 [1005 Metric], Thick Film, General Purpose"
			(at 0 0 0)
			(layer "B.Fab")
			(hide yes)
			(effects
				(font
					(size 1.27 1.27)
					(thickness 0.15)
				)
				(justify mirror)
			)
		)
		(property "MPN" "ERJ2GE0R00X"
			(at 0 0 180)
			(unlocked yes)
			(layer "B.Fab")
			(hide yes)
			(effects
				(font
					(size 1 1)
					(thickness 0.15)
				)
				(justify mirror)
			)
		)
		(property "Manufacturer" "Panasonic"
			(at 0 0 180)
			(unlocked yes)
			(layer "B.Fab")
			(hide yes)
			(effects
				(font
					(size 1 1)
					(thickness 0.15)
				)
				(justify mirror)
			)
		)
		(property "License" "Apache-2.0"
			(at 0 0 180)
			(unlocked yes)
			(layer "B.Fab")
			(hide yes)
			(effects
				(font
					(size 1 1)
					(thickness 0.15)
				)
				(justify mirror)
			)
		)
		(property "Author" "Antmicro"
			(at 0 0 180)
			(unlocked yes)
			(layer "B.Fab")
			(hide yes)
			(effects
				(font
					(size 1 1)
					(thickness 0.15)
				)
				(justify mirror)
			)
		)
		(property "Val" "0R"
			(at 0 0 180)
			(unlocked yes)
			(layer "B.Fab")
			(hide yes)
			(effects
				(font
					(size 1 1)
					(thickness 0.15)
				)
				(justify mirror)
			)
		)
		(property "Tolerance" "~"
			(at 0 0 180)
			(unlocked yes)
			(layer "B.Fab")
			(hide yes)
			(effects
				(font
					(size 1 1)
					(thickness 0.15)
				)
				(justify mirror)
			)
		)
		(property "Current" "1A"
			(at 0 0 180)
			(unlocked yes)
			(layer "B.Fab")
			(hide yes)
			(effects
				(font
					(size 1 1)
					(thickness 0.15)
				)
				(justify mirror)
			)
		)
		(sheetname "/Debug FTDI + VNA/")
		(sheetfile "debug-ftdi.kicad_sch")
		(attr smd exclude_from_bom dnp)
		(fp_rect
			(start -0.925 0.47)
			(end 0.925 -0.47)
			(stroke
				(width 0.05)
				(type default)
			)
			(fill no)
			(layer "B.CrtYd")
		)
		(fp_rect
			(start -0.5 0.25)
			(end 0.5 -0.25)
			(stroke
				(width 0.15)
				(type solid)
			)
			(fill no)
			(layer "B.Fab")
		)
		(fp_text user "Author: Antmicro"
			(at -0.95 -4.169 0)
			(layer "B.Fab")
			(effects
				(font
					(size 0.7 0.7)
					(thickness 0.15)
				)
				(justify left bottom mirror)
			)
		)
		(fp_text user "${REFERENCE}"
			(at -0.95 -3.168 0)
			(layer "B.Fab")
			(effects
				(font
					(size 0.7 0.7)
					(thickness 0.15)
				)
				(justify left bottom mirror)
			)
		)
		(fp_text user "License: Apache-2.0"
			(at -0.95 -5.169 0)
			(layer "B.Fab")
			(effects
				(font
					(size 0.7 0.7)
					(thickness 0.15)
				)
				(justify left bottom mirror)
			)
		)
		(pad "1" smd roundrect
			(at -0.48 0 180)
			(size 0.59 0.64)
			(layers "B.Cu" "B.Mask" "B.Paste")
			(roundrect_rratio 0.25)
			(net 818 "Net-(D17-A)")
			(pintype "passive")
		)
		(pad "2" smd roundrect
			(at 0.48 0 180)
			(size 0.59 0.64)
			(layers "B.Cu" "B.Mask" "B.Paste")
			(roundrect_rratio 0.25)
			(net 6 "/Debug FTDI + VNA/FTDI_3V3")
			(pintype "passive")
		)
	)
	(footprint "antmicro-footprints:C_0402_1005Metric_EIA"
		(layer "B.Cu")
		(at 193 158.5 90)
		(descr "Capacitor SMD 0402 (1005 Metric), square (rectangular) end terminal, IPC_7351 nominal, (Body size source: IPC-SM-782 page 76, https://www.pcb-3d.com/wordpress/wp-content/uploads/ipc-sm-782a_amendment_1_and_2.pdf)")
		(tags "capacitor 0402")
		(property "Reference" "C55"
			(at 9.525 -30.65 90)
			(layer "B.SilkS")
			(effects
				(font
					(size 0.7 0.7)
					(thickness 0.15)
				)
				(justify right bottom mirror)
			)
		)
		(property "Value" "C_100n_0402"
			(at 0 -1.169 90)
			(layer "B.Fab")
			(effects
				(font
					(size 0.7 0.7)
					(thickness 0.15)
				)
				(justify right bottom mirror)
			)
		)
		(property "Datasheet" "https://www.murata.com/products/productdetail?partno=GRM155R61H104KE14%23"
			(at 0 0 90)
			(layer "F.Fab")
			(hide yes)
			(effects
				(font
					(size 1.27 1.27)
					(thickness 0.15)
				)
			)
		)
		(property "MPN" "GRM155R61H104KE14D"
			(at 0 0 90)
			(unlocked yes)
			(layer "B.Fab")
			(hide yes)
			(effects
				(font
					(size 1 1)
					(thickness 0.15)
				)
				(justify mirror)
			)
		)
		(property "Manufacturer" "Murata"
			(at 0 0 90)
			(unlocked yes)
			(layer "B.Fab")
			(hide yes)
			(effects
				(font
					(size 1 1)
					(thickness 0.15)
				)
				(justify mirror)
			)
		)
		(property "License" "Apache-2.0"
			(at 0 0 90)
			(unlocked yes)
			(layer "B.Fab")
			(hide yes)
			(effects
				(font
					(size 1 1)
					(thickness 0.15)
				)
				(justify mirror)
			)
		)
		(property "Author" "Antmicro"
			(at 0 0 90)
			(unlocked yes)
			(layer "B.Fab")
			(hide yes)
			(effects
				(font
					(size 1 1)
					(thickness 0.15)
				)
				(justify mirror)
			)
		)
		(property "Val" "100n"
			(at 0 0 90)
			(unlocked yes)
			(layer "B.Fab")
			(hide yes)
			(effects
				(font
					(size 1 1)
					(thickness 0.15)
				)
				(justify mirror)
			)
		)
		(property "Voltage" "50V"
			(at 0 0 90)
			(unlocked yes)
			(layer "B.Fab")
			(hide yes)
			(effects
				(font
					(size 1 1)
					(thickness 0.15)
				)
				(justify mirror)
			)
		)
		(property "Dielectric" "X5R"
			(at 0 0 90)
			(unlocked yes)
			(layer "B.Fab")
			(hide yes)
			(effects
				(font
					(size 1 1)
					(thickness 0.15)
				)
				(justify mirror)
			)
		)
		(sheetname "/FPGA power/")
		(sheetfile "fpga-power.kicad_sch")
		(attr smd)
		(fp_rect
			(start -0.95 0.45)
			(end 0.95 -0.45)
			(stroke
				(width 0.05)
				(type default)
			)
			(fill no)
			(layer "B.CrtYd")
		)
		(fp_line
			(start 0.498 -0.248)
			(end -0.5 -0.248)
			(stroke
				(width 0.15)
				(type solid)
			)
			(layer "B.Fab")
		)
		(fp_line
			(start -0.5 -0.248)
			(end -0.5 0.25)
			(stroke
				(width 0.15)
				(type solid)
			)
			(layer "B.Fab")
		)
		(fp_line
			(start 0.498 0.25)
			(end 0.498 -0.248)
			(stroke
				(width 0.15)
				(type solid)
			)
			(layer "B.Fab")
		)
		(fp_line
			(start -0.5 0.25)
			(end 0.498 0.25)
			(stroke
				(width 0.15)
				(type solid)
			)
			(layer "B.Fab")
		)
		(fp_text user "License: Apache-2.0"
			(at -0.9656 -4.369 270)
			(layer "B.Fab")
			(effects
				(font
					(size 0.7 0.7)
					(thickness 0.15)
				)
				(justify left bottom mirror)
			)
		)
		(fp_text user "Author: Antmicro"
			(at -0.9656 -5.569 270)
			(layer "B.Fab")
			(effects
				(font
					(size 0.7 0.7)
					(thickness 0.15)
				)
				(justify left bottom mirror)
			)
		)
		(fp_text user "${REFERENCE}"
			(at -0.9656 -3.169 270)
			(layer "B.Fab")
			(effects
				(font
					(size 0.7 0.7)
					(thickness 0.15)
				)
				(justify left bottom mirror)
			)
		)
		(pad "1" smd roundrect
			(at -0.5 0)
			(size 0.6 0.6)
			(layers "B.Cu" "B.Mask" "B.Paste")
			(roundrect_rratio 0.25)
			(net 1 "GND")
			(pintype "passive")
		)
		(pad "2" smd roundrect
			(at 0.498 0 90)
			(size 0.6 0.6)
			(layers "B.Cu" "B.Mask" "B.Paste")
			(roundrect_rratio 0.25)
			(net 553 "+0V85")
			(pintype "passive")
		)
	)
	(footprint "antmicro-footprints:R_0402_1005Metric"
		(layer "B.Cu")
		(at 247.845 110.625)
		(descr "Resistor SMD 0402")
		(tags "resistor SMD 0402")
		(property "Reference" "R128"
			(at -3.895 0.45 0)
			(layer "B.SilkS")
			(effects
				(font
					(size 0.7 0.7)
					(thickness 0.15)
				)
				(justify right bottom mirror)
			)
		)
		(property "Value" "R_10k_0402"
			(at -1.011843 -1.772047 0)
			(layer "B.Fab")
			(effects
				(font
					(size 0.7 0.7)
					(thickness 0.15)
				)
				(justify right bottom mirror)
			)
		)
		(property "Datasheet" "https://www.bourns.com/docs/product-datasheets/cr.pdf"
			(at 0 0 0)
			(layer "F.Fab")
			(hide yes)
			(effects
				(font
					(size 1.27 1.27)
					(thickness 0.15)
				)
			)
		)
		(property "MPN" "CR0402-FX-1002GLF"
			(at 0 0 0)
			(unlocked yes)
			(layer "B.Fab")
			(hide yes)
			(effects
				(font
					(size 1 1)
					(thickness 0.15)
				)
				(justify mirror)
			)
		)
		(property "Manufacturer" "Bourns"
			(at 0 0 0)
			(unlocked yes)
			(layer "B.Fab")
			(hide yes)
			(effects
				(font
					(size 1 1)
					(thickness 0.15)
				)
				(justify mirror)
			)
		)
		(property "License" "Apache-2.0"
			(at 0 0 0)
			(unlocked yes)
			(layer "B.Fab")
			(hide yes)
			(effects
				(font
					(size 1 1)
					(thickness 0.15)
				)
				(justify mirror)
			)
		)
		(property "Author" "Antmicro"
			(at 0 0 0)
			(unlocked yes)
			(layer "B.Fab")
			(hide yes)
			(effects
				(font
					(size 1 1)
					(thickness 0.15)
				)
				(justify mirror)
			)
		)
		(property "Val" "10k"
			(at 0 0 0)
			(unlocked yes)
			(layer "B.Fab")
			(hide yes)
			(effects
				(font
					(size 1 1)
					(thickness 0.15)
				)
				(justify mirror)
			)
		)
		(property "Tolerance" "1%"
			(at 0 0 0)
			(unlocked yes)
			(layer "B.Fab")
			(hide yes)
			(effects
				(font
					(size 1 1)
					(thickness 0.15)
				)
				(justify mirror)
			)
		)
		(sheetname "/DDR5 RDIMM/")
		(sheetfile "ddr5-rdimm.kicad_sch")
		(attr smd)
		(fp_rect
			(start -0.925 0.47)
			(end 0.925 -0.47)
			(stroke
				(width 0.05)
				(type default)
			)
			(fill no)
			(layer "B.CrtYd")
		)
		(fp_rect
			(start -0.5 0.25)
			(end 0.5 -0.25)
			(stroke
				(width 0.15)
				(type solid)
			)
			(fill no)
			(layer "B.Fab")
		)
		(fp_text user "${REFERENCE}"
			(at -0.95 -3.168 180)
			(layer "B.Fab")
			(effects
				(font
					(size 0.7 0.7)
					(thickness 0.15)
				)
				(justify left bottom mirror)
			)
		)
		(fp_text user "Author: Antmicro"
			(at -0.95 -4.169 180)
			(layer "B.Fab")
			(effects
				(font
					(size 0.7 0.7)
					(thickness 0.15)
				)
				(justify left bottom mirror)
			)
		)
		(fp_text user "License: Apache-2.0"
			(at -0.95 -5.169 180)
			(layer "B.Fab")
			(effects
				(font
					(size 0.7 0.7)
					(thickness 0.15)
				)
				(justify left bottom mirror)
			)
		)
		(pad "1" smd roundrect
			(at -0.48 0)
			(size 0.59 0.64)
			(layers "B.Cu" "B.Mask" "B.Paste")
			(roundrect_rratio 0.25)
			(net 1 "GND")
			(pintype "passive")
		)
		(pad "2" smd roundrect
			(at 0.48 0)
			(size 0.59 0.64)
			(layers "B.Cu" "B.Mask" "B.Paste")
			(roundrect_rratio 0.25)
			(net 461 "/DDR5 RDIMM/HSA")
			(pintype "passive")
		)
	)
	(footprint "antmicro-footprints:Coax_Conn_U.FL"
		(layer "B.Cu")
		(at 169.898 102.646 90)
		(descr "https://media.digikey.com/pdf/Data%20Sheets/Hirose%20PDFs/UFL%20Series.pdf")
		(property "Reference" "J15"
			(at -3.204 -1.998 180)
			(layer "B.SilkS")
			(effects
				(font
					(size 0.7 0.7)
					(thickness 0.15)
				)
				(justify right bottom mirror)
			)
		)
		(property "Value" "U_FL-R-SMT-1"
			(at -4.13 -2.52 90)
			(layer "B.Fab")
			(effects
				(font
					(size 0.7 0.7)
					(thickness 0.15)
				)
				(justify right bottom mirror)
			)
		)
		(property "Datasheet" "https://media.digikey.com/pdf/Data%20Sheets/Hirose%20PDFs/UFL%20Series.pdf"
			(at 0 0 90)
			(layer "F.Fab")
			(hide yes)
			(effects
				(font
					(size 1.27 1.27)
					(thickness 0.15)
				)
			)
		)
		(property "MPN" "U.FL-R-SMT-1(10)"
			(at 0 0 90)
			(unlocked yes)
			(layer "B.Fab")
			(hide yes)
			(effects
				(font
					(size 1 1)
					(thickness 0.15)
				)
				(justify mirror)
			)
		)
		(property "Manufacturer" "Hirose Electric"
			(at 0 0 90)
			(unlocked yes)
			(layer "B.Fab")
			(hide yes)
			(effects
				(font
					(size 1 1)
					(thickness 0.15)
				)
				(justify mirror)
			)
		)
		(property "Author" "Antmicro"
			(at 0 0 90)
			(unlocked yes)
			(layer "B.Fab")
			(hide yes)
			(effects
				(font
					(size 1 1)
					(thickness 0.15)
				)
				(justify mirror)
			)
		)
		(property "License" "Apache-2.0"
			(at 0 0 90)
			(unlocked yes)
			(layer "B.Fab")
			(hide yes)
			(effects
				(font
					(size 1 1)
					(thickness 0.15)
				)
				(justify mirror)
			)
		)
		(sheetname "/Debug FTDI + VNA/")
		(sheetfile "debug-ftdi.kicad_sch")
		(attr smd)
		(fp_line
			(start 1.588 -1.648)
			(end 1.088 -1.648)
			(stroke
				(width 0.15)
				(type solid)
			)
			(layer "B.SilkS")
		)
		(fp_line
			(start 1.588 -1.648)
			(end 1.588 -1.325)
			(stroke
				(width 0.15)
				(type solid)
			)
			(layer "B.SilkS")
		)
		(fp_line
			(start -1.613 -1.648)
			(end -1.113 -1.648)
			(stroke
				(width 0.15)
				(type solid)
			)
			(layer "B.SilkS")
		)
		(fp_line
			(start -1.613 -1.648)
			(end -1.613 -1.325)
			(stroke
				(width 0.15)
				(type solid)
			)
			(layer "B.SilkS")
		)
		(fp_line
			(start 1.588 1.651)
			(end 1.588 1.325)
			(stroke
				(width 0.15)
				(type solid)
			)
			(layer "B.SilkS")
		)
		(fp_line
			(start 1.588 1.651)
			(end 1.088 1.651)
			(stroke
				(width 0.15)
				(type solid)
			)
			(layer "B.SilkS")
		)
		(fp_line
			(start -1.613 1.651)
			(end -1.613 1.325)
			(stroke
				(width 0.15)
				(type solid)
			)
			(layer "B.SilkS")
		)
		(fp_line
			(start -1.613 1.651)
			(end -1.113 1.651)
			(stroke
				(width 0.15)
				(type solid)
			)
			(layer "B.SilkS")
		)
		(fp_rect
			(start -2 2.051)
			(end 1.999 -2.05)
			(stroke
				(width 0.05)
				(type solid)
			)
			(fill no)
			(layer "B.CrtYd")
		)
		(fp_line
			(start 1.487 -1.55)
			(end 1.487 1.551)
			(stroke
				(width 0.15)
				(type solid)
			)
			(layer "B.Fab")
		)
		(fp_line
			(start -1.512 -1.55)
			(end 1.487 -1.55)
			(stroke
				(width 0.15)
				(type solid)
			)
			(layer "B.Fab")
		)
		(fp_line
			(start -1.512 -1.55)
			(end -1.512 1.551)
			(stroke
				(width 0.15)
				(type solid)
			)
			(layer "B.Fab")
		)
		(fp_line
			(start -1.512 1.551)
			(end 1.487 1.551)
			(stroke
				(width 0.15)
				(type solid)
			)
			(layer "B.Fab")
		)
		(fp_text user "License: Apache-2.0"
			(at -4.13 -5.72 270)
			(layer "B.Fab")
			(effects
				(font
					(size 0.7 0.7)
					(thickness 0.15)
				)
				(justify left bottom mirror)
			)
		)
		(fp_text user "${REFERENCE}"
			(at -4.13 -6.92 270)
			(layer "B.Fab")
			(effects
				(font
					(size 0.7 0.7)
					(thickness 0.15)
				)
				(justify left bottom mirror)
			)
		)
		(fp_text user "Author: Antmicro"
			(at -4.13 -4.52 270)
			(layer "B.Fab")
			(effects
				(font
					(size 0.7 0.7)
					(thickness 0.15)
				)
				(justify left bottom mirror)
			)
		)
		(pad "1" smd rect
			(at -0.012 -1.499 90)
			(size 1 1.05)
			(layers "B.Cu" "B.Mask" "B.Paste")
			(net 371 "Net-(J15-Pad1)")
			(pintype "passive")
		)
		(pad "SH1" smd rect
			(at 1.463 0 90)
			(size 1.05 2.2)
			(layers "B.Cu" "B.Mask" "B.Paste")
			(net 1 "GND")
			(pintype "passive")
		)
		(pad "SH2" smd rect
			(at -1.488 0 90)
			(size 1.05 2.2)
			(layers "B.Cu" "B.Mask" "B.Paste")
			(net 1 "GND")
			(pintype "passive")
		)
		(zone
			(net 0)
			(net_name "")
			(layer "B.Cu")
			(hatch edge 0.508)
			(connect_pads
				(clearance 0)
			)
			(min_thickness 0.254)
			(filled_areas_thickness no)
			(keepout
				(tracks not_allowed)
				(vias not_allowed)
				(pads not_allowed)
				(copperpour not_allowed)
				(footprints not_allowed)
			)
			(placement
				(enabled no)
				(sheetname "")
			)
			(fill
				(thermal_gap 0.508)
				(thermal_bridge_width 0.508)
			)
			(polygon
				(pts
					(xy 168.938 101.716) (xy 168.938 103.596) (xy 170.998 103.596) (xy 170.998 101.716)
				)
			)
		)
	)
	(footprint "antmicro-footprints:C_0402_1005Metric"
		(layer "B.Cu")
		(at 149.084499 160.429 90)
		(descr "Capacitor SMD 0402")
		(tags "capacitor SMD 0402")
		(property "Reference" "C236"
			(at 1.433 0.515501 90)
			(layer "B.SilkS")
			(effects
				(font
					(size 0.7 0.7)
					(thickness 0.15)
				)
				(justify right bottom mirror)
			)
		)
		(property "Value" "C_100n_0402"
			(at -1.022927 -2.155213 90)
			(layer "B.Fab")
			(effects
				(font
					(size 0.7 0.7)
					(thickness 0.15)
				)
				(justify right bottom mirror)
			)
		)
		(property "Datasheet" "https://www.murata.com/products/productdetail?partno=GRM155R61H104KE14%23"
			(at 0 0 90)
			(layer "F.Fab")
			(hide yes)
			(effects
				(font
					(size 1.27 1.27)
					(thickness 0.15)
				)
			)
		)
		(property "MPN" "GRM155R61H104KE14D"
			(at 0 0 90)
			(unlocked yes)
			(layer "B.Fab")
			(hide yes)
			(effects
				(font
					(size 1 1)
					(thickness 0.15)
				)
				(justify mirror)
			)
		)
		(property "Manufacturer" "Murata"
			(at 0 0 90)
			(unlocked yes)
			(layer "B.Fab")
			(hide yes)
			(effects
				(font
					(size 1 1)
					(thickness 0.15)
				)
				(justify mirror)
			)
		)
		(property "License" "Apache-2.0"
			(at 0 0 90)
			(unlocked yes)
			(layer "B.Fab")
			(hide yes)
			(effects
				(font
					(size 1 1)
					(thickness 0.15)
				)
				(justify mirror)
			)
		)
		(property "Author" "Antmicro"
			(at 0 0 90)
			(unlocked yes)
			(layer "B.Fab")
			(hide yes)
			(effects
				(font
					(size 1 1)
					(thickness 0.15)
				)
				(justify mirror)
			)
		)
		(property "Val" "100n"
			(at 0 0 90)
			(unlocked yes)
			(layer "B.Fab")
			(hide yes)
			(effects
				(font
					(size 1 1)
					(thickness 0.15)
				)
				(justify mirror)
			)
		)
		(property "Voltage" "50V"
			(at 0 0 90)
			(unlocked yes)
			(layer "B.Fab")
			(hide yes)
			(effects
				(font
					(size 1 1)
					(thickness 0.15)
				)
				(justify mirror)
			)
		)
		(property "Dielectric" "X5R"
			(at 0 0 90)
			(unlocked yes)
			(layer "B.Fab")
			(hide yes)
			(effects
				(font
					(size 1 1)
					(thickness 0.15)
				)
				(justify mirror)
			)
		)
		(sheetname "/Debug FTDI + VNA/")
		(sheetfile "debug-ftdi.kicad_sch")
		(attr smd)
		(fp_rect
			(start -0.925 0.47)
			(end 0.925 -0.47)
			(stroke
				(width 0.05)
				(type default)
			)
			(fill no)
			(layer "B.CrtYd")
		)
		(fp_line
			(start 0.504 -0.248)
			(end -0.494 -0.248)
			(stroke
				(width 0.15)
				(type solid)
			)
			(layer "B.Fab")
		)
		(fp_line
			(start -0.494 -0.248)
			(end -0.494 0.25)
			(stroke
				(width 0.15)
				(type solid)
			)
			(layer "B.Fab")
		)
		(fp_line
			(start 0.504 0.25)
			(end 0.504 -0.248)
			(stroke
				(width 0.15)
				(type solid)
			)
			(layer "B.Fab")
		)
		(fp_line
			(start -0.494 0.25)
			(end 0.504 0.25)
			(stroke
				(width 0.15)
				(type solid)
			)
			(layer "B.Fab")
		)
		(fp_text user "Author: Antmicro"
			(at -0.939 -3.399 270)
			(layer "B.Fab")
			(effects
				(font
					(size 0.7 0.7)
					(thickness 0.15)
				)
				(justify left bottom mirror)
			)
		)
		(fp_text user "License: Apache-2.0"
			(at -0.939 -5.799 270)
			(layer "B.Fab")
			(effects
				(font
					(size 0.7 0.7)
					(thickness 0.15)
				)
				(justify left bottom mirror)
			)
		)
		(fp_text user "${REFERENCE}"
			(at -0.939 -4.599 270)
			(layer "B.Fab")
			(effects
				(font
					(size 0.7 0.7)
					(thickness 0.15)
				)
				(justify left bottom mirror)
			)
		)
		(pad "1" smd roundrect
			(at -0.48 0 90)
			(size 0.59 0.64)
			(layers "B.Cu" "B.Mask" "B.Paste")
			(roundrect_rratio 0.25)
			(net 1 "GND")
			(pintype "passive")
		)
		(pad "2" smd roundrect
			(at 0.48 0 90)
			(size 0.59 0.64)
			(layers "B.Cu" "B.Mask" "B.Paste")
			(roundrect_rratio 0.25)
			(net 151 "+3V3")
			(pintype "passive")
		)
	)
	(footprint "antmicro-footprints:R_0402_1005Metric"
		(layer "B.Cu")
		(at 235.59 134.755 90)
		(descr "Resistor SMD 0402")
		(tags "resistor SMD 0402")
		(property "Reference" "R124"
			(at -3.745 0.46 90)
			(layer "B.SilkS")
			(effects
				(font
					(size 0.7 0.7)
					(thickness 0.15)
				)
				(justify right bottom mirror)
			)
		)
		(property "Value" "R_4k7_0402"
			(at -1.011843 -1.772047 90)
			(layer "B.Fab")
			(effects
				(font
					(size 0.7 0.7)
					(thickness 0.15)
				)
				(justify right bottom mirror)
			)
		)
		(property "Datasheet" "https://www.bourns.com/docs/product-datasheets/cr.pdf"
			(at 0 0 90)
			(layer "F.Fab")
			(hide yes)
			(effects
				(font
					(size 1.27 1.27)
					(thickness 0.15)
				)
			)
		)
		(property "Manufacturer" "Bourns"
			(at 0 0 90)
			(unlocked yes)
			(layer "B.Fab")
			(hide yes)
			(effects
				(font
					(size 1 1)
					(thickness 0.15)
				)
				(justify mirror)
			)
		)
		(property "MPN" "CR0402-FX-4701GLF"
			(at 0 0 90)
			(unlocked yes)
			(layer "B.Fab")
			(hide yes)
			(effects
				(font
					(size 1 1)
					(thickness 0.15)
				)
				(justify mirror)
			)
		)
		(property "Val" "4k7"
			(at 0 0 90)
			(unlocked yes)
			(layer "B.Fab")
			(hide yes)
			(effects
				(font
					(size 1 1)
					(thickness 0.15)
				)
				(justify mirror)
			)
		)
		(property "License" "Apache-2.0"
			(at 0 0 90)
			(unlocked yes)
			(layer "B.Fab")
			(hide yes)
			(effects
				(font
					(size 1 1)
					(thickness 0.15)
				)
				(justify mirror)
			)
		)
		(property "Author" "Antmicro"
			(at 0 0 90)
			(unlocked yes)
			(layer "B.Fab")
			(hide yes)
			(effects
				(font
					(size 1 1)
					(thickness 0.15)
				)
				(justify mirror)
			)
		)
		(property "Tolerance" "1%"
			(at 0 0 90)
			(unlocked yes)
			(layer "B.Fab")
			(hide yes)
			(effects
				(font
					(size 1 1)
					(thickness 0.15)
				)
				(justify mirror)
			)
		)
		(sheetname "/I^{2}C + I3C/")
		(sheetfile "i2c.kicad_sch")
		(attr smd)
		(fp_rect
			(start -0.925 0.47)
			(end 0.925 -0.47)
			(stroke
				(width 0.05)
				(type default)
			)
			(fill no)
			(layer "B.CrtYd")
		)
		(fp_rect
			(start -0.5 0.25)
			(end 0.5 -0.25)
			(stroke
				(width 0.15)
				(type solid)
			)
			(fill no)
			(layer "B.Fab")
		)
		(fp_text user "License: Apache-2.0"
			(at -0.95 -5.169 270)
			(layer "B.Fab")
			(effects
				(font
					(size 0.7 0.7)
					(thickness 0.15)
				)
				(justify left bottom mirror)
			)
		)
		(fp_text user "Author: Antmicro"
			(at -0.95 -4.169 270)
			(layer "B.Fab")
			(effects
				(font
					(size 0.7 0.7)
					(thickness 0.15)
				)
				(justify left bottom mirror)
			)
		)
		(fp_text user "${REFERENCE}"
			(at -0.95 -3.168 270)
			(layer "B.Fab")
			(effects
				(font
					(size 0.7 0.7)
					(thickness 0.15)
				)
				(justify left bottom mirror)
			)
		)
		(pad "1" smd roundrect
			(at -0.48 0 90)
			(size 0.59 0.64)
			(layers "B.Cu" "B.Mask" "B.Paste")
			(roundrect_rratio 0.25)
			(net 201 "VDDSPD")
			(pintype "passive")
		)
		(pad "2" smd roundrect
			(at 0.48 0 90)
			(size 0.59 0.64)
			(layers "B.Cu" "B.Mask" "B.Paste")
			(roundrect_rratio 0.25)
			(net 459 "/DDR5 RDIMM/DDR.SDA")
			(pintype "passive")
		)
	)
	(footprint "antmicro-footprints:C_0402_1005Metric"
		(layer "B.Cu")
		(at 255.689499 140.75 -90)
		(descr "Capacitor SMD 0402")
		(tags "capacitor SMD 0402")
		(property "Reference" "C212"
			(at 1 -0.410501 90)
			(layer "B.SilkS")
			(effects
				(font
					(size 0.7 0.7)
					(thickness 0.15)
				)
				(justify left bottom mirror)
			)
		)
		(property "Value" "C_100n_0402"
			(at -1.022927 -2.155213 90)
			(layer "B.Fab")
			(effects
				(font
					(size 0.7 0.7)
					(thickness 0.15)
				)
				(justify left bottom mirror)
			)
		)
		(property "Datasheet" "https://www.murata.com/products/productdetail?partno=GRM155R61H104KE14%23"
			(at 0 0 270)
			(layer "F.Fab")
			(hide yes)
			(effects
				(font
					(size 1.27 1.27)
					(thickness 0.15)
				)
			)
		)
		(property "Manufacturer" "Murata"
			(at 0 0 270)
			(unlocked yes)
			(layer "B.Fab")
			(hide yes)
			(effects
				(font
					(size 1 1)
					(thickness 0.15)
				)
				(justify mirror)
			)
		)
		(property "MPN" "GRM155R61H104KE14D"
			(at 0 0 270)
			(unlocked yes)
			(layer "B.Fab")
			(hide yes)
			(effects
				(font
					(size 1 1)
					(thickness 0.15)
				)
				(justify mirror)
			)
		)
		(property "Val" "100n"
			(at 0 0 270)
			(unlocked yes)
			(layer "B.Fab")
			(hide yes)
			(effects
				(font
					(size 1 1)
					(thickness 0.15)
				)
				(justify mirror)
			)
		)
		(property "License" "Apache-2.0"
			(at 0 0 270)
			(unlocked yes)
			(layer "B.Fab")
			(hide yes)
			(effects
				(font
					(size 1 1)
					(thickness 0.15)
				)
				(justify mirror)
			)
		)
		(property "Author" "Antmicro"
			(at 0 0 270)
			(unlocked yes)
			(layer "B.Fab")
			(hide yes)
			(effects
				(font
					(size 1 1)
					(thickness 0.15)
				)
				(justify mirror)
			)
		)
		(property "Voltage" "50V"
			(at 0 0 270)
			(unlocked yes)
			(layer "B.Fab")
			(hide yes)
			(effects
				(font
					(size 1 1)
					(thickness 0.15)
				)
				(justify mirror)
			)
		)
		(property "Dielectric" "X5R"
			(at 0 0 270)
			(unlocked yes)
			(layer "B.Fab")
			(hide yes)
			(effects
				(font
					(size 1 1)
					(thickness 0.15)
				)
				(justify mirror)
			)
		)
		(sheetname "/Supply/")
		(sheetfile "supply.kicad_sch")
		(attr smd)
		(fp_rect
			(start -0.925 0.47)
			(end 0.925 -0.47)
			(stroke
				(width 0.05)
				(type default)
			)
			(fill no)
			(layer "B.CrtYd")
		)
		(fp_line
			(start -0.494 0.25)
			(end 0.504 0.25)
			(stroke
				(width 0.15)
				(type solid)
			)
			(layer "B.Fab")
		)
		(fp_line
			(start 0.504 0.25)
			(end 0.504 -0.248)
			(stroke
				(width 0.15)
				(type solid)
			)
			(layer "B.Fab")
		)
		(fp_line
			(start -0.494 -0.248)
			(end -0.494 0.25)
			(stroke
				(width 0.15)
				(type solid)
			)
			(layer "B.Fab")
		)
		(fp_line
			(start 0.504 -0.248)
			(end -0.494 -0.248)
			(stroke
				(width 0.15)
				(type solid)
			)
			(layer "B.Fab")
		)
		(fp_text user "Author: Antmicro"
			(at -0.939 -3.399 90)
			(layer "B.Fab")
			(effects
				(font
					(size 0.7 0.7)
					(thickness 0.15)
				)
				(justify left bottom mirror)
			)
		)
		(fp_text user "License: Apache-2.0"
			(at -0.939 -5.799 90)
			(layer "B.Fab")
			(effects
				(font
					(size 0.7 0.7)
					(thickness 0.15)
				)
				(justify left bottom mirror)
			)
		)
		(fp_text user "${REFERENCE}"
			(at -0.939 -4.599 90)
			(layer "B.Fab")
			(effects
				(font
					(size 0.7 0.7)
					(thickness 0.15)
				)
				(justify left bottom mirror)
			)
		)
		(pad "1" smd roundrect
			(at -0.48 0 270)
			(size 0.59 0.64)
			(layers "B.Cu" "B.Mask" "B.Paste")
			(roundrect_rratio 0.25)
			(net 1 "GND")
			(pintype "passive")
		)
		(pad "2" smd roundrect
			(at 0.48 0 270)
			(size 0.59 0.64)
			(layers "B.Cu" "B.Mask" "B.Paste")
			(roundrect_rratio 0.25)
			(net 38 "+3V3_AON")
			(pintype "passive")
		)
	)
	(footprint "antmicro-footprints:C_0402_1005Metric_EIA"
		(layer "B.Cu")
		(at 176 159.5 -90)
		(descr "Capacitor SMD 0402 (1005 Metric), square (rectangular) end terminal, IPC_7351 nominal, (Body size source: IPC-SM-782 page 76, https://www.pcb-3d.com/wordpress/wp-content/uploads/ipc-sm-782a_amendment_1_and_2.pdf)")
		(tags "capacitor 0402")
		(property "Reference" "C312"
			(at -0.65 -1.5 90)
			(layer "B.SilkS")
			(effects
				(font
					(size 0.7 0.7)
					(thickness 0.15)
				)
				(justify left bottom mirror)
			)
		)
		(property "Value" "C_100n_0402"
			(at 0 -1.169 90)
			(layer "B.Fab")
			(effects
				(font
					(size 0.7 0.7)
					(thickness 0.15)
				)
				(justify left bottom mirror)
			)
		)
		(property "Datasheet" "https://www.murata.com/products/productdetail?partno=GRM155R61H104KE14%23"
			(at 0 0 270)
			(layer "F.Fab")
			(hide yes)
			(effects
				(font
					(size 1.27 1.27)
					(thickness 0.15)
				)
			)
		)
		(property "MPN" "GRM155R61H104KE14D"
			(at 0 0 270)
			(unlocked yes)
			(layer "B.Fab")
			(hide yes)
			(effects
				(font
					(size 1 1)
					(thickness 0.15)
				)
				(justify mirror)
			)
		)
		(property "Manufacturer" "Murata"
			(at 0 0 270)
			(unlocked yes)
			(layer "B.Fab")
			(hide yes)
			(effects
				(font
					(size 1 1)
					(thickness 0.15)
				)
				(justify mirror)
			)
		)
		(property "License" "Apache-2.0"
			(at 0 0 270)
			(unlocked yes)
			(layer "B.Fab")
			(hide yes)
			(effects
				(font
					(size 1 1)
					(thickness 0.15)
				)
				(justify mirror)
			)
		)
		(property "Author" "Antmicro"
			(at 0 0 270)
			(unlocked yes)
			(layer "B.Fab")
			(hide yes)
			(effects
				(font
					(size 1 1)
					(thickness 0.15)
				)
				(justify mirror)
			)
		)
		(property "Val" "100n"
			(at 0 0 270)
			(unlocked yes)
			(layer "B.Fab")
			(hide yes)
			(effects
				(font
					(size 1 1)
					(thickness 0.15)
				)
				(justify mirror)
			)
		)
		(property "Voltage" "50V"
			(at 0 0 270)
			(unlocked yes)
			(layer "B.Fab")
			(hide yes)
			(effects
				(font
					(size 1 1)
					(thickness 0.15)
				)
				(justify mirror)
			)
		)
		(property "Dielectric" "X5R"
			(at 0 0 270)
			(unlocked yes)
			(layer "B.Fab")
			(hide yes)
			(effects
				(font
					(size 1 1)
					(thickness 0.15)
				)
				(justify mirror)
			)
		)
		(sheetname "/FPGA power/")
		(sheetfile "fpga-power.kicad_sch")
		(attr smd)
		(fp_rect
			(start -0.95 0.45)
			(end 0.95 -0.45)
			(stroke
				(width 0.05)
				(type default)
			)
			(fill no)
			(layer "B.CrtYd")
		)
		(fp_line
			(start -0.5 0.25)
			(end 0.498 0.25)
			(stroke
				(width 0.15)
				(type solid)
			)
			(layer "B.Fab")
		)
		(fp_line
			(start 0.498 0.25)
			(end 0.498 -0.248)
			(stroke
				(width 0.15)
				(type solid)
			)
			(layer "B.Fab")
		)
		(fp_line
			(start -0.5 -0.248)
			(end -0.5 0.25)
			(stroke
				(width 0.15)
				(type solid)
			)
			(layer "B.Fab")
		)
		(fp_line
			(start 0.498 -0.248)
			(end -0.5 -0.248)
			(stroke
				(width 0.15)
				(type solid)
			)
			(layer "B.Fab")
		)
		(fp_text user "${REFERENCE}"
			(at -0.9656 -3.169 90)
			(layer "B.Fab")
			(effects
				(font
					(size 0.7 0.7)
					(thickness 0.15)
				)
				(justify left bottom mirror)
			)
		)
		(fp_text user "Author: Antmicro"
			(at -0.9656 -5.569 90)
			(layer "B.Fab")
			(effects
				(font
					(size 0.7 0.7)
					(thickness 0.15)
				)
				(justify left bottom mirror)
			)
		)
		(fp_text user "License: Apache-2.0"
			(at -0.9656 -4.369 90)
			(layer "B.Fab")
			(effects
				(font
					(size 0.7 0.7)
					(thickness 0.15)
				)
				(justify left bottom mirror)
			)
		)
		(pad "1" smd roundrect
			(at -0.5 0 180)
			(size 0.6 0.6)
			(layers "B.Cu" "B.Mask" "B.Paste")
			(roundrect_rratio 0.25)
			(net 1 "GND")
			(pintype "passive")
		)
		(pad "2" smd roundrect
			(at 0.498 0 270)
			(size 0.6 0.6)
			(layers "B.Cu" "B.Mask" "B.Paste")
			(roundrect_rratio 0.25)
			(net 172 "+1V2_MGTAVTT")
			(pintype "passive")
		)
	)
	(footprint "antmicro-footprints:C_0402_1005Metric_EIA"
		(layer "B.Cu")
		(at 176.5 145)
		(descr "Capacitor SMD 0402 (1005 Metric), square (rectangular) end terminal, IPC_7351 nominal, (Body size source: IPC-SM-782 page 76, https://www.pcb-3d.com/wordpress/wp-content/uploads/ipc-sm-782a_amendment_1_and_2.pdf)")
		(tags "capacitor 0402")
		(property "Reference" "C87"
			(at -1.1 -0.525 0)
			(layer "B.SilkS")
			(effects
				(font
					(size 0.7 0.7)
					(thickness 0.15)
				)
				(justify right bottom mirror)
			)
		)
		(property "Value" "C_10u_10V_0402"
			(at 0 -1.169 0)
			(layer "B.Fab")
			(effects
				(font
					(size 0.7 0.7)
					(thickness 0.15)
				)
				(justify right bottom mirror)
			)
		)
		(property "Datasheet" "https://www.murata.com/products/productdetail?partno=GRM155R61A106ME11%23"
			(at 0 0 0)
			(layer "F.Fab")
			(hide yes)
			(effects
				(font
					(size 1.27 1.27)
					(thickness 0.15)
				)
			)
		)
		(property "MPN" "GRM155R61A106ME11D"
			(at 0 0 0)
			(unlocked yes)
			(layer "B.Fab")
			(hide yes)
			(effects
				(font
					(size 1 1)
					(thickness 0.15)
				)
				(justify mirror)
			)
		)
		(property "Manufacturer" "Murata"
			(at 0 0 0)
			(unlocked yes)
			(layer "B.Fab")
			(hide yes)
			(effects
				(font
					(size 1 1)
					(thickness 0.15)
				)
				(justify mirror)
			)
		)
		(property "License" "Apache-2.0"
			(at 0 0 0)
			(unlocked yes)
			(layer "B.Fab")
			(hide yes)
			(effects
				(font
					(size 1 1)
					(thickness 0.15)
				)
				(justify mirror)
			)
		)
		(property "Author" "Antmicro"
			(at 0 0 0)
			(unlocked yes)
			(layer "B.Fab")
			(hide yes)
			(effects
				(font
					(size 1 1)
					(thickness 0.15)
				)
				(justify mirror)
			)
		)
		(property "Val" "10u"
			(at 0 0 0)
			(unlocked yes)
			(layer "B.Fab")
			(hide yes)
			(effects
				(font
					(size 1 1)
					(thickness 0.15)
				)
				(justify mirror)
			)
		)
		(property "Voltage" "10V"
			(at 0 0 0)
			(unlocked yes)
			(layer "B.Fab")
			(hide yes)
			(effects
				(font
					(size 1 1)
					(thickness 0.15)
				)
				(justify mirror)
			)
		)
		(property "Dielectric" "X5R"
			(at 0 0 0)
			(unlocked yes)
			(layer "B.Fab")
			(hide yes)
			(effects
				(font
					(size 1 1)
					(thickness 0.15)
				)
				(justify mirror)
			)
		)
		(sheetname "/FPGA power/")
		(sheetfile "fpga-power.kicad_sch")
		(attr smd)
		(fp_rect
			(start -0.95 0.45)
			(end 0.95 -0.45)
			(stroke
				(width 0.05)
				(type default)
			)
			(fill no)
			(layer "B.CrtYd")
		)
		(fp_line
			(start -0.5 -0.248)
			(end -0.5 0.25)
			(stroke
				(width 0.15)
				(type solid)
			)
			(layer "B.Fab")
		)
		(fp_line
			(start -0.5 0.25)
			(end 0.498 0.25)
			(stroke
				(width 0.15)
				(type solid)
			)
			(layer "B.Fab")
		)
		(fp_line
			(start 0.498 -0.248)
			(end -0.5 -0.248)
			(stroke
				(width 0.15)
				(type solid)
			)
			(layer "B.Fab")
		)
		(fp_line
			(start 0.498 0.25)
			(end 0.498 -0.248)
			(stroke
				(width 0.15)
				(type solid)
			)
			(layer "B.Fab")
		)
		(fp_text user "License: Apache-2.0"
			(at -0.9656 -4.369 180)
			(layer "B.Fab")
			(effects
				(font
					(size 0.7 0.7)
					(thickness 0.15)
				)
				(justify left bottom mirror)
			)
		)
		(fp_text user "Author: Antmicro"
			(at -0.9656 -5.569 180)
			(layer "B.Fab")
			(effects
				(font
					(size 0.7 0.7)
					(thickness 0.15)
				)
				(justify left bottom mirror)
			)
		)
		(fp_text user "${REFERENCE}"
			(at -0.9656 -3.169 180)
			(layer "B.Fab")
			(effects
				(font
					(size 0.7 0.7)
					(thickness 0.15)
				)
				(justify left bottom mirror)
			)
		)
		(pad "1" smd roundrect
			(at -0.5 0 270)
			(size 0.6 0.6)
			(layers "B.Cu" "B.Mask" "B.Paste")
			(roundrect_rratio 0.25)
			(net 1 "GND")
			(pintype "passive")
		)
		(pad "2" smd roundrect
			(at 0.498 0)
			(size 0.6 0.6)
			(layers "B.Cu" "B.Mask" "B.Paste")
			(roundrect_rratio 0.25)
			(net 797 "+1V8")
			(pintype "passive")
		)
	)
	(footprint "antmicro-footprints:C_0402_1005Metric"
		(layer "B.Cu")
		(at 182.672499 193.2285 90)
		(descr "Capacitor SMD 0402")
		(tags "capacitor SMD 0402")
		(property "Reference" "C257"
			(at 0.994 0.403501 90)
			(layer "B.SilkS")
			(effects
				(font
					(size 0.7 0.7)
					(thickness 0.15)
				)
				(justify right bottom mirror)
			)
		)
		(property "Value" "C_100n_0402"
			(at -1.022927 -2.155213 90)
			(layer "B.Fab")
			(effects
				(font
					(size 0.7 0.7)
					(thickness 0.15)
				)
				(justify right bottom mirror)
			)
		)
		(property "Datasheet" "https://www.murata.com/products/productdetail?partno=GRM155R61H104KE14%23"
			(at 0 0 90)
			(layer "F.Fab")
			(hide yes)
			(effects
				(font
					(size 1.27 1.27)
					(thickness 0.15)
				)
			)
		)
		(property "Manufacturer" "Murata"
			(at 0 0 90)
			(unlocked yes)
			(layer "B.Fab")
			(hide yes)
			(effects
				(font
					(size 1 1)
					(thickness 0.15)
				)
				(justify mirror)
			)
		)
		(property "MPN" "GRM155R61H104KE14D"
			(at 0 0 90)
			(unlocked yes)
			(layer "B.Fab")
			(hide yes)
			(effects
				(font
					(size 1 1)
					(thickness 0.15)
				)
				(justify mirror)
			)
		)
		(property "Val" "100n"
			(at 0 0 90)
			(unlocked yes)
			(layer "B.Fab")
			(hide yes)
			(effects
				(font
					(size 1 1)
					(thickness 0.15)
				)
				(justify mirror)
			)
		)
		(property "License" "Apache-2.0"
			(at 0 0 90)
			(unlocked yes)
			(layer "B.Fab")
			(hide yes)
			(effects
				(font
					(size 1 1)
					(thickness 0.15)
				)
				(justify mirror)
			)
		)
		(property "Author" "Antmicro"
			(at 0 0 90)
			(unlocked yes)
			(layer "B.Fab")
			(hide yes)
			(effects
				(font
					(size 1 1)
					(thickness 0.15)
				)
				(justify mirror)
			)
		)
		(property "Voltage" "50V"
			(at 0 0 90)
			(unlocked yes)
			(layer "B.Fab")
			(hide yes)
			(effects
				(font
					(size 1 1)
					(thickness 0.15)
				)
				(justify mirror)
			)
		)
		(property "Dielectric" "X5R"
			(at 0 0 90)
			(unlocked yes)
			(layer "B.Fab")
			(hide yes)
			(effects
				(font
					(size 1 1)
					(thickness 0.15)
				)
				(justify mirror)
			)
		)
		(sheetname "/FPGA MGT Interface/")
		(sheetfile "fpga-mgt.kicad_sch")
		(attr smd)
		(fp_rect
			(start -0.925 0.47)
			(end 0.925 -0.47)
			(stroke
				(width 0.05)
				(type default)
			)
			(fill no)
			(layer "B.CrtYd")
		)
		(fp_line
			(start 0.504 -0.248)
			(end -0.494 -0.248)
			(stroke
				(width 0.15)
				(type solid)
			)
			(layer "B.Fab")
		)
		(fp_line
			(start -0.494 -0.248)
			(end -0.494 0.25)
			(stroke
				(width 0.15)
				(type solid)
			)
			(layer "B.Fab")
		)
		(fp_line
			(start 0.504 0.25)
			(end 0.504 -0.248)
			(stroke
				(width 0.15)
				(type solid)
			)
			(layer "B.Fab")
		)
		(fp_line
			(start -0.494 0.25)
			(end 0.504 0.25)
			(stroke
				(width 0.15)
				(type solid)
			)
			(layer "B.Fab")
		)
		(fp_text user "Author: Antmicro"
			(at -0.939 -3.399 270)
			(layer "B.Fab")
			(effects
				(font
					(size 0.7 0.7)
					(thickness 0.15)
				)
				(justify left bottom mirror)
			)
		)
		(fp_text user "License: Apache-2.0"
			(at -0.939 -5.799 270)
			(layer "B.Fab")
			(effects
				(font
					(size 0.7 0.7)
					(thickness 0.15)
				)
				(justify left bottom mirror)
			)
		)
		(fp_text user "${REFERENCE}"
			(at -0.939 -4.599 270)
			(layer "B.Fab")
			(effects
				(font
					(size 0.7 0.7)
					(thickness 0.15)
				)
				(justify left bottom mirror)
			)
		)
		(pad "1" smd roundrect
			(at -0.48 0 90)
			(size 0.59 0.64)
			(layers "B.Cu" "B.Mask" "B.Paste")
			(roundrect_rratio 0.25)
			(net 259 "/FPGA MGT Interface/PCIE.TXD4_N")
			(pintype "passive")
		)
		(pad "2" smd roundrect
			(at 0.48 0 90)
			(size 0.59 0.64)
			(layers "B.Cu" "B.Mask" "B.Paste")
			(roundrect_rratio 0.25)
			(net 568 "/FPGA MGT Interface/GTY_224_TX3_N")
			(pintype "passive")
		)
	)
	(footprint "antmicro-footprints:R_0402_1005Metric"
		(layer "B.Cu")
		(at 250.05 183.649 90)
		(descr "Resistor SMD 0402")
		(tags "resistor SMD 0402")
		(property "Reference" "R232"
			(at 1 0.4 90)
			(layer "B.SilkS")
			(effects
				(font
					(size 0.7 0.7)
					(thickness 0.15)
				)
				(justify right bottom mirror)
			)
		)
		(property "Value" "R_47k_0402"
			(at -1.011843 -1.772047 90)
			(layer "B.Fab")
			(effects
				(font
					(size 0.7 0.7)
					(thickness 0.15)
				)
				(justify right bottom mirror)
			)
		)
		(property "Datasheet" "https://www.bourns.com/docs/product-datasheets/cr.pdf"
			(at 0 0 90)
			(layer "F.Fab")
			(hide yes)
			(effects
				(font
					(size 1.27 1.27)
					(thickness 0.15)
				)
			)
		)
		(property "MPN" "CR0402-FX-4702GLF"
			(at 0 0 90)
			(unlocked yes)
			(layer "B.Fab")
			(hide yes)
			(effects
				(font
					(size 1 1)
					(thickness 0.15)
				)
				(justify mirror)
			)
		)
		(property "Manufacturer" "Bourns"
			(at 0 0 90)
			(unlocked yes)
			(layer "B.Fab")
			(hide yes)
			(effects
				(font
					(size 1 1)
					(thickness 0.15)
				)
				(justify mirror)
			)
		)
		(property "License" "Apache-2.0"
			(at 0 0 90)
			(unlocked yes)
			(layer "B.Fab")
			(hide yes)
			(effects
				(font
					(size 1 1)
					(thickness 0.15)
				)
				(justify mirror)
			)
		)
		(property "Author" "Antmicro"
			(at 0 0 90)
			(unlocked yes)
			(layer "B.Fab")
			(hide yes)
			(effects
				(font
					(size 1 1)
					(thickness 0.15)
				)
				(justify mirror)
			)
		)
		(property "Val" "47k"
			(at 0 0 90)
			(unlocked yes)
			(layer "B.Fab")
			(hide yes)
			(effects
				(font
					(size 1 1)
					(thickness 0.15)
				)
				(justify mirror)
			)
		)
		(property "Tolerance" "1%"
			(at 0 0 90)
			(unlocked yes)
			(layer "B.Fab")
			(hide yes)
			(effects
				(font
					(size 1 1)
					(thickness 0.15)
				)
				(justify mirror)
			)
		)
		(sheetname "/I^{2}C + I3C/")
		(sheetfile "i2c.kicad_sch")
		(attr smd)
		(fp_rect
			(start -0.925 0.47)
			(end 0.925 -0.47)
			(stroke
				(width 0.05)
				(type default)
			)
			(fill no)
			(layer "B.CrtYd")
		)
		(fp_rect
			(start -0.5 0.25)
			(end 0.5 -0.25)
			(stroke
				(width 0.15)
				(type solid)
			)
			(fill no)
			(layer "B.Fab")
		)
		(fp_text user "License: Apache-2.0"
			(at -0.95 -5.169 270)
			(layer "B.Fab")
			(effects
				(font
					(size 0.7 0.7)
					(thickness 0.15)
				)
				(justify left bottom mirror)
			)
		)
		(fp_text user "Author: Antmicro"
			(at -0.95 -4.169 270)
			(layer "B.Fab")
			(effects
				(font
					(size 0.7 0.7)
					(thickness 0.15)
				)
				(justify left bottom mirror)
			)
		)
		(fp_text user "${REFERENCE}"
			(at -0.95 -3.168 270)
			(layer "B.Fab")
			(effects
				(font
					(size 0.7 0.7)
					(thickness 0.15)
				)
				(justify left bottom mirror)
			)
		)
		(pad "1" smd roundrect
			(at -0.48 0 90)
			(size 0.59 0.64)
			(layers "B.Cu" "B.Mask" "B.Paste")
			(roundrect_rratio 0.25)
			(net 779 "~{I3C_EXT_PU}")
			(pintype "passive")
		)
		(pad "2" smd roundrect
			(at 0.48 0 90)
			(size 0.59 0.64)
			(layers "B.Cu" "B.Mask" "B.Paste")
			(roundrect_rratio 0.25)
			(net 775 "Net-(Q24-S)")
			(pintype "passive")
		)
	)
	(footprint "antmicro-footprints:SC70-3"
		(layer "B.Cu")
		(at 112.38 166.47 180)
		(property "Reference" "Q18"
			(at -1.57 -1.23 90)
			(layer "B.SilkS")
			(effects
				(font
					(size 0.7 0.7)
					(thickness 0.15)
				)
				(justify left bottom mirror)
			)
		)
		(property "Value" "BSS138PW"
			(at 0 -2.3 0)
			(layer "B.Fab")
			(effects
				(font
					(size 0.7 0.7)
					(thickness 0.15)
				)
				(justify left bottom mirror)
			)
		)
		(property "Datasheet" "https://assets.nexperia.com/documents/data-sheet/BSS138PW.pdf"
			(at 0 0 180)
			(layer "F.Fab")
			(hide yes)
			(effects
				(font
					(size 1.27 1.27)
					(thickness 0.15)
				)
			)
		)
		(property "MPN" "BSS138PW"
			(at 0 0 180)
			(unlocked yes)
			(layer "B.Fab")
			(hide yes)
			(effects
				(font
					(size 1 1)
					(thickness 0.15)
				)
				(justify mirror)
			)
		)
		(property "Manufacturer" "Nexperia"
			(at 0 0 180)
			(unlocked yes)
			(layer "B.Fab")
			(hide yes)
			(effects
				(font
					(size 1 1)
					(thickness 0.15)
				)
				(justify mirror)
			)
		)
		(property "Author" "Antmicro"
			(at 0 0 180)
			(unlocked yes)
			(layer "B.Fab")
			(hide yes)
			(effects
				(font
					(size 1 1)
					(thickness 0.15)
				)
				(justify mirror)
			)
		)
		(property "License" "Apache-2.0"
			(at 0 0 180)
			(unlocked yes)
			(layer "B.Fab")
			(hide yes)
			(effects
				(font
					(size 1 1)
					(thickness 0.15)
				)
				(justify mirror)
			)
		)
		(sheetname "/HDMI + SD Card/")
		(sheetfile "hdmi-sd-card.kicad_sch")
		(attr smd)
		(fp_line
			(start 0.627 0.6)
			(end 0.627 0.999)
			(stroke
				(width 0.15)
				(type solid)
			)
			(layer "B.SilkS")
		)
		(fp_line
			(start 0.627 -0.6)
			(end 0.627 -1.001)
			(stroke
				(width 0.15)
				(type solid)
			)
			(layer "B.SilkS")
		)
		(fp_line
			(start -0.3 1)
			(end 0.627 0.999)
			(stroke
				(width 0.15)
				(type solid)
			)
			(layer "B.SilkS")
		)
		(fp_line
			(start -0.3 -1)
			(end 0.627 -1.001)
			(stroke
				(width 0.15)
				(type solid)
			)
			(layer "B.SilkS")
		)
		(fp_line
			(start 1.4 0.4)
			(end 1.4 -0.4)
			(stroke
				(width 0.05)
				(type solid)
			)
			(layer "B.CrtYd")
		)
		(fp_line
			(start 1.4 -0.4)
			(end 0.9 -0.4)
			(stroke
				(width 0.05)
				(type solid)
			)
			(layer "B.CrtYd")
		)
		(fp_line
			(start 0.9 1.3)
			(end 0.9 0.4)
			(stroke
				(width 0.05)
				(type solid)
			)
			(layer "B.CrtYd")
		)
		(fp_line
			(start 0.9 0.4)
			(end 1.4 0.4)
			(stroke
				(width 0.05)
				(type solid)
			)
			(layer "B.CrtYd")
		)
		(fp_line
			(start 0.9 -0.4)
			(end 0.9 -1.3)
			(stroke
				(width 0.05)
				(type solid)
			)
			(layer "B.CrtYd")
		)
		(fp_line
			(start 0.9 -1.3)
			(end -0.9 -1.3)
			(stroke
				(width 0.05)
				(type solid)
			)
			(layer "B.CrtYd")
		)
		(fp_line
			(start -0.9 1.3)
			(end 0.9 1.3)
			(stroke
				(width 0.05)
				(type solid)
			)
			(layer "B.CrtYd")
		)
		(fp_line
			(start -0.9 1.3)
			(end -0.9 1)
			(stroke
				(width 0.05)
				(type solid)
			)
			(layer "B.CrtYd")
		)
		(fp_line
			(start -0.9 1)
			(end -1.4 1)
			(stroke
				(width 0.05)
				(type solid)
			)
			(layer "B.CrtYd")
		)
		(fp_line
			(start -0.9 -1)
			(end -1.4 -1)
			(stroke
				(width 0.05)
				(type solid)
			)
			(layer "B.CrtYd")
		)
		(fp_line
			(start -0.9 -1.3)
			(end -0.9 -1)
			(stroke
				(width 0.05)
				(type solid)
			)
			(layer "B.CrtYd")
		)
		(fp_line
			(start -1.4 -1)
			(end -1.4 1)
			(stroke
				(width 0.05)
				(type solid)
			)
			(layer "B.CrtYd")
		)
		(fp_rect
			(start -0.623 0.999)
			(end 0.627 -1.001)
			(stroke
				(width 0.15)
				(type solid)
			)
			(fill no)
			(layer "B.Fab")
		)
		(fp_text user "Author: Antmicro"
			(at -1.45 -5.782 0)
			(layer "B.Fab")
			(effects
				(font
					(size 0.7 0.7)
					(thickness 0.15)
				)
				(justify left bottom mirror)
			)
		)
		(fp_text user "License: Apache-2.0"
			(at -1.45 -6.782 0)
			(layer "B.Fab")
			(effects
				(font
					(size 0.7 0.7)
					(thickness 0.15)
				)
				(justify left bottom mirror)
			)
		)
		(fp_text user "${REFERENCE}"
			(at -1.45 -4.783 0)
			(layer "B.Fab")
			(effects
				(font
					(size 0.7 0.7)
					(thickness 0.15)
				)
				(justify left bottom mirror)
			)
		)
		(pad "1" smd rect
			(at -1.051 0.65 90)
			(size 0.6 0.6)
			(layers "B.Cu" "B.Mask" "B.Paste")
			(net 506 "Net-(Q18-G)")
			(pinfunction "G")
			(pintype "passive")
		)
		(pad "2" smd rect
			(at -1.051 -0.65 90)
			(size 0.6 0.6)
			(layers "B.Cu" "B.Mask" "B.Paste")
			(net 1 "GND")
			(pinfunction "S")
			(pintype "passive")
		)
		(pad "3" smd rect
			(at 1.05 0 90)
			(size 0.6 0.6)
			(layers "B.Cu" "B.Mask" "B.Paste")
			(net 604 "/HDMI + SD Card/HDMI_IN_HPD_CONN")
			(pinfunction "D")
			(pintype "passive")
		)
	)
	(footprint "antmicro-footprints:C_0402_1005Metric"
		(layer "B.Cu")
		(at 193.622499 193.2285 90)
		(descr "Capacitor SMD 0402")
		(tags "capacitor SMD 0402")
		(property "Reference" "C251"
			(at 0.994 0.403501 90)
			(layer "B.SilkS")
			(effects
				(font
					(size 0.7 0.7)
					(thickness 0.15)
				)
				(justify right bottom mirror)
			)
		)
		(property "Value" "C_100n_0402"
			(at -1.022927 -2.155213 90)
			(layer "B.Fab")
			(effects
				(font
					(size 0.7 0.7)
					(thickness 0.15)
				)
				(justify right bottom mirror)
			)
		)
		(property "Datasheet" "https://www.murata.com/products/productdetail?partno=GRM155R61H104KE14%23"
			(at 0 0 90)
			(layer "F.Fab")
			(hide yes)
			(effects
				(font
					(size 1.27 1.27)
					(thickness 0.15)
				)
			)
		)
		(property "Manufacturer" "Murata"
			(at 0 0 90)
			(unlocked yes)
			(layer "B.Fab")
			(hide yes)
			(effects
				(font
					(size 1 1)
					(thickness 0.15)
				)
				(justify mirror)
			)
		)
		(property "MPN" "GRM155R61H104KE14D"
			(at 0 0 90)
			(unlocked yes)
			(layer "B.Fab")
			(hide yes)
			(effects
				(font
					(size 1 1)
					(thickness 0.15)
				)
				(justify mirror)
			)
		)
		(property "Val" "100n"
			(at 0 0 90)
			(unlocked yes)
			(layer "B.Fab")
			(hide yes)
			(effects
				(font
					(size 1 1)
					(thickness 0.15)
				)
				(justify mirror)
			)
		)
		(property "License" "Apache-2.0"
			(at 0 0 90)
			(unlocked yes)
			(layer "B.Fab")
			(hide yes)
			(effects
				(font
					(size 1 1)
					(thickness 0.15)
				)
				(justify mirror)
			)
		)
		(property "Author" "Antmicro"
			(at 0 0 90)
			(unlocked yes)
			(layer "B.Fab")
			(hide yes)
			(effects
				(font
					(size 1 1)
					(thickness 0.15)
				)
				(justify mirror)
			)
		)
		(property "Voltage" "50V"
			(at 0 0 90)
			(unlocked yes)
			(layer "B.Fab")
			(hide yes)
			(effects
				(font
					(size 1 1)
					(thickness 0.15)
				)
				(justify mirror)
			)
		)
		(property "Dielectric" "X5R"
			(at 0 0 90)
			(unlocked yes)
			(layer "B.Fab")
			(hide yes)
			(effects
				(font
					(size 1 1)
					(thickness 0.15)
				)
				(justify mirror)
			)
		)
		(sheetname "/FPGA MGT Interface/")
		(sheetfile "fpga-mgt.kicad_sch")
		(attr smd)
		(fp_rect
			(start -0.925 0.47)
			(end 0.925 -0.47)
			(stroke
				(width 0.05)
				(type default)
			)
			(fill no)
			(layer "B.CrtYd")
		)
		(fp_line
			(start 0.504 -0.248)
			(end -0.494 -0.248)
			(stroke
				(width 0.15)
				(type solid)
			)
			(layer "B.Fab")
		)
		(fp_line
			(start -0.494 -0.248)
			(end -0.494 0.25)
			(stroke
				(width 0.15)
				(type solid)
			)
			(layer "B.Fab")
		)
		(fp_line
			(start 0.504 0.25)
			(end 0.504 -0.248)
			(stroke
				(width 0.15)
				(type solid)
			)
			(layer "B.Fab")
		)
		(fp_line
			(start -0.494 0.25)
			(end 0.504 0.25)
			(stroke
				(width 0.15)
				(type solid)
			)
			(layer "B.Fab")
		)
		(fp_text user "${REFERENCE}"
			(at -0.939 -4.599 270)
			(layer "B.Fab")
			(effects
				(font
					(size 0.7 0.7)
					(thickness 0.15)
				)
				(justify left bottom mirror)
			)
		)
		(fp_text user "License: Apache-2.0"
			(at -0.939 -5.799 270)
			(layer "B.Fab")
			(effects
				(font
					(size 0.7 0.7)
					(thickness 0.15)
				)
				(justify left bottom mirror)
			)
		)
		(fp_text user "Author: Antmicro"
			(at -0.939 -3.399 270)
			(layer "B.Fab")
			(effects
				(font
					(size 0.7 0.7)
					(thickness 0.15)
				)
				(justify left bottom mirror)
			)
		)
		(pad "1" smd roundrect
			(at -0.48 0 90)
			(size 0.59 0.64)
			(layers "B.Cu" "B.Mask" "B.Paste")
			(roundrect_rratio 0.25)
			(net 253 "/FPGA MGT Interface/PCIE.TXD7_P")
			(pintype "passive")
		)
		(pad "2" smd roundrect
			(at 0.48 0 90)
			(size 0.59 0.64)
			(layers "B.Cu" "B.Mask" "B.Paste")
			(roundrect_rratio 0.25)
			(net 557 "/FPGA MGT Interface/GTY_224_TX0_P")
			(pintype "passive")
		)
	)
	(footprint "antmicro-footprints:C_0402_1005Metric"
		(layer "B.Cu")
		(at 185.622499 193.2285 90)
		(descr "Capacitor SMD 0402")
		(tags "capacitor SMD 0402")
		(property "Reference" "C255"
			(at 0.994 0.403501 90)
			(layer "B.SilkS")
			(effects
				(font
					(size 0.7 0.7)
					(thickness 0.15)
				)
				(justify right bottom mirror)
			)
		)
		(property "Value" "C_100n_0402"
			(at -1.022927 -2.155213 90)
			(layer "B.Fab")
			(effects
				(font
					(size 0.7 0.7)
					(thickness 0.15)
				)
				(justify right bottom mirror)
			)
		)
		(property "Datasheet" "https://www.murata.com/products/productdetail?partno=GRM155R61H104KE14%23"
			(at 0 0 90)
			(layer "F.Fab")
			(hide yes)
			(effects
				(font
					(size 1.27 1.27)
					(thickness 0.15)
				)
			)
		)
		(property "Manufacturer" "Murata"
			(at 0 0 90)
			(unlocked yes)
			(layer "B.Fab")
			(hide yes)
			(effects
				(font
					(size 1 1)
					(thickness 0.15)
				)
				(justify mirror)
			)
		)
		(property "MPN" "GRM155R61H104KE14D"
			(at 0 0 90)
			(unlocked yes)
			(layer "B.Fab")
			(hide yes)
			(effects
				(font
					(size 1 1)
					(thickness 0.15)
				)
				(justify mirror)
			)
		)
		(property "Val" "100n"
			(at 0 0 90)
			(unlocked yes)
			(layer "B.Fab")
			(hide yes)
			(effects
				(font
					(size 1 1)
					(thickness 0.15)
				)
				(justify mirror)
			)
		)
		(property "License" "Apache-2.0"
			(at 0 0 90)
			(unlocked yes)
			(layer "B.Fab")
			(hide yes)
			(effects
				(font
					(size 1 1)
					(thickness 0.15)
				)
				(justify mirror)
			)
		)
		(property "Author" "Antmicro"
			(at 0 0 90)
			(unlocked yes)
			(layer "B.Fab")
			(hide yes)
			(effects
				(font
					(size 1 1)
					(thickness 0.15)
				)
				(justify mirror)
			)
		)
		(property "Voltage" "50V"
			(at 0 0 90)
			(unlocked yes)
			(layer "B.Fab")
			(hide yes)
			(effects
				(font
					(size 1 1)
					(thickness 0.15)
				)
				(justify mirror)
			)
		)
		(property "Dielectric" "X5R"
			(at 0 0 90)
			(unlocked yes)
			(layer "B.Fab")
			(hide yes)
			(effects
				(font
					(size 1 1)
					(thickness 0.15)
				)
				(justify mirror)
			)
		)
		(sheetname "/FPGA MGT Interface/")
		(sheetfile "fpga-mgt.kicad_sch")
		(attr smd)
		(fp_rect
			(start -0.925 0.47)
			(end 0.925 -0.47)
			(stroke
				(width 0.05)
				(type default)
			)
			(fill no)
			(layer "B.CrtYd")
		)
		(fp_line
			(start 0.504 -0.248)
			(end -0.494 -0.248)
			(stroke
				(width 0.15)
				(type solid)
			)
			(layer "B.Fab")
		)
		(fp_line
			(start -0.494 -0.248)
			(end -0.494 0.25)
			(stroke
				(width 0.15)
				(type solid)
			)
			(layer "B.Fab")
		)
		(fp_line
			(start 0.504 0.25)
			(end 0.504 -0.248)
			(stroke
				(width 0.15)
				(type solid)
			)
			(layer "B.Fab")
		)
		(fp_line
			(start -0.494 0.25)
			(end 0.504 0.25)
			(stroke
				(width 0.15)
				(type solid)
			)
			(layer "B.Fab")
		)
		(fp_text user "License: Apache-2.0"
			(at -0.939 -5.799 270)
			(layer "B.Fab")
			(effects
				(font
					(size 0.7 0.7)
					(thickness 0.15)
				)
				(justify left bottom mirror)
			)
		)
		(fp_text user "${REFERENCE}"
			(at -0.939 -4.599 270)
			(layer "B.Fab")
			(effects
				(font
					(size 0.7 0.7)
					(thickness 0.15)
				)
				(justify left bottom mirror)
			)
		)
		(fp_text user "Author: Antmicro"
			(at -0.939 -3.399 270)
			(layer "B.Fab")
			(effects
				(font
					(size 0.7 0.7)
					(thickness 0.15)
				)
				(justify left bottom mirror)
			)
		)
		(pad "1" smd roundrect
			(at -0.48 0 90)
			(size 0.59 0.64)
			(layers "B.Cu" "B.Mask" "B.Paste")
			(roundrect_rratio 0.25)
			(net 257 "/FPGA MGT Interface/PCIE.TXD5_P")
			(pintype "passive")
		)
		(pad "2" smd roundrect
			(at 0.48 0 90)
			(size 0.59 0.64)
			(layers "B.Cu" "B.Mask" "B.Paste")
			(roundrect_rratio 0.25)
			(net 563 "/FPGA MGT Interface/GTY_224_TX2_P")
			(pintype "passive")
		)
	)
	(footprint "antmicro-footprints:C_0402_1005Metric_EIA"
		(layer "B.Cu")
		(at 180 159.5 -90)
		(descr "Capacitor SMD 0402 (1005 Metric), square (rectangular) end terminal, IPC_7351 nominal, (Body size source: IPC-SM-782 page 76, https://www.pcb-3d.com/wordpress/wp-content/uploads/ipc-sm-782a_amendment_1_and_2.pdf)")
		(tags "capacitor 0402")
		(property "Reference" "C310"
			(at -0.65 -1.4 90)
			(layer "B.SilkS")
			(effects
				(font
					(size 0.7 0.7)
					(thickness 0.15)
				)
				(justify left bottom mirror)
			)
		)
		(property "Value" "C_100n_0402"
			(at 0 -1.169 90)
			(layer "B.Fab")
			(effects
				(font
					(size 0.7 0.7)
					(thickness 0.15)
				)
				(justify left bottom mirror)
			)
		)
		(property "Datasheet" "https://www.murata.com/products/productdetail?partno=GRM155R61H104KE14%23"
			(at 0 0 270)
			(layer "F.Fab")
			(hide yes)
			(effects
				(font
					(size 1.27 1.27)
					(thickness 0.15)
				)
			)
		)
		(property "MPN" "GRM155R61H104KE14D"
			(at 0 0 270)
			(unlocked yes)
			(layer "B.Fab")
			(hide yes)
			(effects
				(font
					(size 1 1)
					(thickness 0.15)
				)
				(justify mirror)
			)
		)
		(property "Manufacturer" "Murata"
			(at 0 0 270)
			(unlocked yes)
			(layer "B.Fab")
			(hide yes)
			(effects
				(font
					(size 1 1)
					(thickness 0.15)
				)
				(justify mirror)
			)
		)
		(property "License" "Apache-2.0"
			(at 0 0 270)
			(unlocked yes)
			(layer "B.Fab")
			(hide yes)
			(effects
				(font
					(size 1 1)
					(thickness 0.15)
				)
				(justify mirror)
			)
		)
		(property "Author" "Antmicro"
			(at 0 0 270)
			(unlocked yes)
			(layer "B.Fab")
			(hide yes)
			(effects
				(font
					(size 1 1)
					(thickness 0.15)
				)
				(justify mirror)
			)
		)
		(property "Val" "100n"
			(at 0 0 270)
			(unlocked yes)
			(layer "B.Fab")
			(hide yes)
			(effects
				(font
					(size 1 1)
					(thickness 0.15)
				)
				(justify mirror)
			)
		)
		(property "Voltage" "50V"
			(at 0 0 270)
			(unlocked yes)
			(layer "B.Fab")
			(hide yes)
			(effects
				(font
					(size 1 1)
					(thickness 0.15)
				)
				(justify mirror)
			)
		)
		(property "Dielectric" "X5R"
			(at 0 0 270)
			(unlocked yes)
			(layer "B.Fab")
			(hide yes)
			(effects
				(font
					(size 1 1)
					(thickness 0.15)
				)
				(justify mirror)
			)
		)
		(sheetname "/FPGA power/")
		(sheetfile "fpga-power.kicad_sch")
		(attr smd)
		(fp_rect
			(start -0.95 0.45)
			(end 0.95 -0.45)
			(stroke
				(width 0.05)
				(type default)
			)
			(fill no)
			(layer "B.CrtYd")
		)
		(fp_line
			(start -0.5 0.25)
			(end 0.498 0.25)
			(stroke
				(width 0.15)
				(type solid)
			)
			(layer "B.Fab")
		)
		(fp_line
			(start 0.498 0.25)
			(end 0.498 -0.248)
			(stroke
				(width 0.15)
				(type solid)
			)
			(layer "B.Fab")
		)
		(fp_line
			(start -0.5 -0.248)
			(end -0.5 0.25)
			(stroke
				(width 0.15)
				(type solid)
			)
			(layer "B.Fab")
		)
		(fp_line
			(start 0.498 -0.248)
			(end -0.5 -0.248)
			(stroke
				(width 0.15)
				(type solid)
			)
			(layer "B.Fab")
		)
		(fp_text user "${REFERENCE}"
			(at -0.9656 -3.169 90)
			(layer "B.Fab")
			(effects
				(font
					(size 0.7 0.7)
					(thickness 0.15)
				)
				(justify left bottom mirror)
			)
		)
		(fp_text user "License: Apache-2.0"
			(at -0.9656 -4.369 90)
			(layer "B.Fab")
			(effects
				(font
					(size 0.7 0.7)
					(thickness 0.15)
				)
				(justify left bottom mirror)
			)
		)
		(fp_text user "Author: Antmicro"
			(at -0.9656 -5.569 90)
			(layer "B.Fab")
			(effects
				(font
					(size 0.7 0.7)
					(thickness 0.15)
				)
				(justify left bottom mirror)
			)
		)
		(pad "1" smd roundrect
			(at -0.5 0 180)
			(size 0.6 0.6)
			(layers "B.Cu" "B.Mask" "B.Paste")
			(roundrect_rratio 0.25)
			(net 1 "GND")
			(pintype "passive")
		)
		(pad "2" smd roundrect
			(at 0.498 0 270)
			(size 0.6 0.6)
			(layers "B.Cu" "B.Mask" "B.Paste")
			(roundrect_rratio 0.25)
			(net 172 "+1V2_MGTAVTT")
			(pintype "passive")
		)
	)
	(footprint "antmicro-footprints:C_0402_1005Metric_EIA"
		(layer "B.Cu")
		(at 194 146.499 90)
		(descr "Capacitor SMD 0402 (1005 Metric), square (rectangular) end terminal, IPC_7351 nominal, (Body size source: IPC-SM-782 page 76, https://www.pcb-3d.com/wordpress/wp-content/uploads/ipc-sm-782a_amendment_1_and_2.pdf)")
		(tags "capacitor 0402")
		(property "Reference" "C334"
			(at 13.199 -30.6 270)
			(layer "B.SilkS")
			(effects
				(font
					(size 0.7 0.7)
					(thickness 0.15)
				)
				(justify left bottom mirror)
			)
		)
		(property "Value" "C_100n_0402"
			(at 0 -1.169 270)
			(layer "B.Fab")
			(effects
				(font
					(size 0.7 0.7)
					(thickness 0.15)
				)
				(justify left bottom mirror)
			)
		)
		(property "Manufacturer" "Murata"
			(at 0 0 90)
			(unlocked yes)
			(layer "B.Fab")
			(hide yes)
			(effects
				(font
					(size 1 1)
					(thickness 0.15)
				)
				(justify mirror)
			)
		)
		(property "MPN" "GRM155R61H104KE14D"
			(at 0 0 90)
			(unlocked yes)
			(layer "B.Fab")
			(hide yes)
			(effects
				(font
					(size 1 1)
					(thickness 0.15)
				)
				(justify mirror)
			)
		)
		(property "Val" "100n"
			(at 0 0 90)
			(unlocked yes)
			(layer "B.Fab")
			(hide yes)
			(effects
				(font
					(size 1 1)
					(thickness 0.15)
				)
				(justify mirror)
			)
		)
		(property "License" "Apache-2.0"
			(at 0 0 90)
			(unlocked yes)
			(layer "B.Fab")
			(hide yes)
			(effects
				(font
					(size 1 1)
					(thickness 0.15)
				)
				(justify mirror)
			)
		)
		(property "Author" "Antmicro"
			(at 0 0 90)
			(unlocked yes)
			(layer "B.Fab")
			(hide yes)
			(effects
				(font
					(size 1 1)
					(thickness 0.15)
				)
				(justify mirror)
			)
		)
		(property "Voltage" "50V"
			(at 0 0 90)
			(unlocked yes)
			(layer "B.Fab")
			(hide yes)
			(effects
				(font
					(size 1 1)
					(thickness 0.15)
				)
				(justify mirror)
			)
		)
		(property "Dielectric" "X5R"
			(at 0 0 90)
			(unlocked yes)
			(layer "B.Fab")
			(hide yes)
			(effects
				(font
					(size 1 1)
					(thickness 0.15)
				)
				(justify mirror)
			)
		)
		(sheetname "/FPGA banks HP/")
		(sheetfile "fpga-hp-banks.kicad_sch")
		(attr smd)
		(fp_rect
			(start -0.95 0.45)
			(end 0.95 -0.45)
			(stroke
				(width 0.05)
				(type default)
			)
			(fill no)
			(layer "B.CrtYd")
		)
		(fp_line
			(start 0.498 -0.248)
			(end -0.5 -0.248)
			(stroke
				(width 0.15)
				(type solid)
			)
			(layer "B.Fab")
		)
		(fp_line
			(start -0.5 -0.248)
			(end -0.5 0.25)
			(stroke
				(width 0.15)
				(type solid)
			)
			(layer "B.Fab")
		)
		(fp_line
			(start 0.498 0.25)
			(end 0.498 -0.248)
			(stroke
				(width 0.15)
				(type solid)
			)
			(layer "B.Fab")
		)
		(fp_line
			(start -0.5 0.25)
			(end 0.498 0.25)
			(stroke
				(width 0.15)
				(type solid)
			)
			(layer "B.Fab")
		)
		(fp_text user "${REFERENCE}"
			(at -0.9656 -3.169 270)
			(layer "B.Fab")
			(effects
				(font
					(size 0.7 0.7)
					(thickness 0.15)
				)
				(justify left bottom mirror)
			)
		)
		(fp_text user "Author: Antmicro"
			(at -0.9656 -5.569 270)
			(layer "B.Fab")
			(effects
				(font
					(size 0.7 0.7)
					(thickness 0.15)
				)
				(justify left bottom mirror)
			)
		)
		(fp_text user "License: Apache-2.0"
			(at -0.9656 -4.369 270)
			(layer "B.Fab")
			(effects
				(font
					(size 0.7 0.7)
					(thickness 0.15)
				)
				(justify left bottom mirror)
			)
		)
		(pad "1" smd roundrect
			(at -0.5 0)
			(size 0.6 0.6)
			(layers "B.Cu" "B.Mask" "B.Paste")
			(roundrect_rratio 0.25)
			(net 536 "/FPGA banks HP/VREF_65")
			(pintype "passive")
		)
		(pad "2" smd roundrect
			(at 0.498 0 90)
			(size 0.6 0.6)
			(layers "B.Cu" "B.Mask" "B.Paste")
			(roundrect_rratio 0.25)
			(net 1 "GND")
			(pintype "passive")
		)
	)
	(footprint "antmicro-footprints:R_0402_1005Metric"
		(layer "B.Cu")
		(at 108 102.1 -90)
		(descr "Resistor SMD 0402")
		(tags "resistor SMD 0402")
		(property "Reference" "R42"
			(at -1.122484 0.772697 90)
			(layer "B.SilkS")
			(effects
				(font
					(size 0.7 0.7)
					(thickness 0.15)
				)
				(justify left bottom mirror)
			)
		)
		(property "Value" "R_330R_0402"
			(at -1.011843 -1.772047 90)
			(layer "B.Fab")
			(effects
				(font
					(size 0.7 0.7)
					(thickness 0.15)
				)
				(justify left bottom mirror)
			)
		)
		(property "Datasheet" "https://www.bourns.com/docs/product-datasheets/cr.pdf"
			(at 0 0 270)
			(layer "F.Fab")
			(hide yes)
			(effects
				(font
					(size 1.27 1.27)
					(thickness 0.15)
				)
			)
		)
		(property "Manufacturer" "Bourns"
			(at 0 0 270)
			(unlocked yes)
			(layer "B.Fab")
			(hide yes)
			(effects
				(font
					(size 1 1)
					(thickness 0.15)
				)
				(justify mirror)
			)
		)
		(property "MPN" "CR0402-FX-3300GLF"
			(at 0 0 270)
			(unlocked yes)
			(layer "B.Fab")
			(hide yes)
			(effects
				(font
					(size 1 1)
					(thickness 0.15)
				)
				(justify mirror)
			)
		)
		(property "Val" "330R"
			(at 0 0 270)
			(unlocked yes)
			(layer "B.Fab")
			(hide yes)
			(effects
				(font
					(size 1 1)
					(thickness 0.15)
				)
				(justify mirror)
			)
		)
		(property "License" "Apache-2.0"
			(at 0 0 270)
			(unlocked yes)
			(layer "B.Fab")
			(hide yes)
			(effects
				(font
					(size 1 1)
					(thickness 0.15)
				)
				(justify mirror)
			)
		)
		(property "Author" "Antmicro"
			(at 0 0 270)
			(unlocked yes)
			(layer "B.Fab")
			(hide yes)
			(effects
				(font
					(size 1 1)
					(thickness 0.15)
				)
				(justify mirror)
			)
		)
		(property "Tolerance" "1%"
			(at 0 0 270)
			(unlocked yes)
			(layer "B.Fab")
			(hide yes)
			(effects
				(font
					(size 1 1)
					(thickness 0.15)
				)
				(justify mirror)
			)
		)
		(sheetname "/FPGA banks HD/")
		(sheetfile "fpga-hd-banks.kicad_sch")
		(attr smd)
		(fp_rect
			(start -0.925 0.47)
			(end 0.925 -0.47)
			(stroke
				(width 0.05)
				(type default)
			)
			(fill no)
			(layer "B.CrtYd")
		)
		(fp_rect
			(start -0.5 0.25)
			(end 0.5 -0.25)
			(stroke
				(width 0.15)
				(type solid)
			)
			(fill no)
			(layer "B.Fab")
		)
		(fp_text user "License: Apache-2.0"
			(at -0.95 -5.169 90)
			(layer "B.Fab")
			(effects
				(font
					(size 0.7 0.7)
					(thickness 0.15)
				)
				(justify left bottom mirror)
			)
		)
		(fp_text user "${REFERENCE}"
			(at -0.95 -3.168 90)
			(layer "B.Fab")
			(effects
				(font
					(size 0.7 0.7)
					(thickness 0.15)
				)
				(justify left bottom mirror)
			)
		)
		(fp_text user "Author: Antmicro"
			(at -0.95 -4.169 90)
			(layer "B.Fab")
			(effects
				(font
					(size 0.7 0.7)
					(thickness 0.15)
				)
				(justify left bottom mirror)
			)
		)
		(pad "1" smd roundrect
			(at -0.48 0 270)
			(size 0.59 0.64)
			(layers "B.Cu" "B.Mask" "B.Paste")
			(roundrect_rratio 0.25)
			(net 231 "Net-(D6-A)")
			(pintype "passive")
		)
		(pad "2" smd roundrect
			(at 0.48 0 270)
			(size 0.59 0.64)
			(layers "B.Cu" "B.Mask" "B.Paste")
			(roundrect_rratio 0.25)
			(net 274 "Net-(Q6-D)")
			(pintype "passive")
		)
	)
	(footprint "antmicro-footprints:C_0402_1005Metric_EIA"
		(layer "B.Cu")
		(at 193 156.499999 90)
		(descr "Capacitor SMD 0402 (1005 Metric), square (rectangular) end terminal, IPC_7351 nominal, (Body size source: IPC-SM-782 page 76, https://www.pcb-3d.com/wordpress/wp-content/uploads/ipc-sm-782a_amendment_1_and_2.pdf)")
		(tags "capacitor 0402")
		(property "Reference" "C92"
			(at 9.849999 -30.7 90)
			(layer "B.SilkS")
			(effects
				(font
					(size 0.7 0.7)
					(thickness 0.15)
				)
				(justify right bottom mirror)
			)
		)
		(property "Value" "C_1u_25V_0402"
			(at 0 -1.169 90)
			(layer "B.Fab")
			(effects
				(font
					(size 0.7 0.7)
					(thickness 0.15)
				)
				(justify right bottom mirror)
			)
		)
		(property "Datasheet" "https://www.murata.com/products/productdetail?partno=GRM155R61E105KE11%23"
			(at 0 0 90)
			(layer "F.Fab")
			(hide yes)
			(effects
				(font
					(size 1.27 1.27)
					(thickness 0.15)
				)
			)
		)
		(property "MPN" "GRM155R61E105KE11J"
			(at 0 0 90)
			(unlocked yes)
			(layer "B.Fab")
			(hide yes)
			(effects
				(font
					(size 1 1)
					(thickness 0.15)
				)
				(justify mirror)
			)
		)
		(property "Manufacturer" "Murata"
			(at 0 0 90)
			(unlocked yes)
			(layer "B.Fab")
			(hide yes)
			(effects
				(font
					(size 1 1)
					(thickness 0.15)
				)
				(justify mirror)
			)
		)
		(property "License" "Apache-2.0"
			(at 0 0 90)
			(unlocked yes)
			(layer "B.Fab")
			(hide yes)
			(effects
				(font
					(size 1 1)
					(thickness 0.15)
				)
				(justify mirror)
			)
		)
		(property "Author" "Antmicro"
			(at 0 0 90)
			(unlocked yes)
			(layer "B.Fab")
			(hide yes)
			(effects
				(font
					(size 1 1)
					(thickness 0.15)
				)
				(justify mirror)
			)
		)
		(property "Val" "1u"
			(at 0 0 90)
			(unlocked yes)
			(layer "B.Fab")
			(hide yes)
			(effects
				(font
					(size 1 1)
					(thickness 0.15)
				)
				(justify mirror)
			)
		)
		(property "Voltage" "25V"
			(at 0 0 90)
			(unlocked yes)
			(layer "B.Fab")
			(hide yes)
			(effects
				(font
					(size 1 1)
					(thickness 0.15)
				)
				(justify mirror)
			)
		)
		(property "Dielectric" "X5R"
			(at 0 0 90)
			(unlocked yes)
			(layer "B.Fab")
			(hide yes)
			(effects
				(font
					(size 1 1)
					(thickness 0.15)
				)
				(justify mirror)
			)
		)
		(sheetname "/FPGA power/")
		(sheetfile "fpga-power.kicad_sch")
		(attr smd)
		(fp_rect
			(start -0.95 0.45)
			(end 0.95 -0.45)
			(stroke
				(width 0.05)
				(type default)
			)
			(fill no)
			(layer "B.CrtYd")
		)
		(fp_line
			(start 0.498 -0.248)
			(end -0.5 -0.248)
			(stroke
				(width 0.15)
				(type solid)
			)
			(layer "B.Fab")
		)
		(fp_line
			(start -0.5 -0.248)
			(end -0.5 0.25)
			(stroke
				(width 0.15)
				(type solid)
			)
			(layer "B.Fab")
		)
		(fp_line
			(start 0.498 0.25)
			(end 0.498 -0.248)
			(stroke
				(width 0.15)
				(type solid)
			)
			(layer "B.Fab")
		)
		(fp_line
			(start -0.5 0.25)
			(end 0.498 0.25)
			(stroke
				(width 0.15)
				(type solid)
			)
			(layer "B.Fab")
		)
		(fp_text user "Author: Antmicro"
			(at -0.9656 -5.569 270)
			(layer "B.Fab")
			(effects
				(font
					(size 0.7 0.7)
					(thickness 0.15)
				)
				(justify left bottom mirror)
			)
		)
		(fp_text user "${REFERENCE}"
			(at -0.9656 -3.169 270)
			(layer "B.Fab")
			(effects
				(font
					(size 0.7 0.7)
					(thickness 0.15)
				)
				(justify left bottom mirror)
			)
		)
		(fp_text user "License: Apache-2.0"
			(at -0.9656 -4.369 270)
			(layer "B.Fab")
			(effects
				(font
					(size 0.7 0.7)
					(thickness 0.15)
				)
				(justify left bottom mirror)
			)
		)
		(pad "1" smd roundrect
			(at -0.5 0)
			(size 0.6 0.6)
			(layers "B.Cu" "B.Mask" "B.Paste")
			(roundrect_rratio 0.25)
			(net 1 "GND")
			(pintype "passive")
		)
		(pad "2" smd roundrect
			(at 0.498 0 90)
			(size 0.6 0.6)
			(layers "B.Cu" "B.Mask" "B.Paste")
			(roundrect_rratio 0.25)
			(net 553 "+0V85")
			(pintype "passive")
		)
	)
	(footprint "antmicro-footprints:C_0805_2012Metric"
		(layer "B.Cu")
		(at 203.5 158.4 90)
		(descr "Capacitor SMD 0805")
		(tags "capacitor SMD 0805")
		(property "Reference" "C241"
			(at -1.22 1.91 90)
			(layer "B.SilkS")
			(effects
				(font
					(size 0.7 0.7)
					(thickness 0.15)
				)
				(justify right bottom mirror)
			)
		)
		(property "Value" "C_100u_0805"
			(at -2.055717 -1.963152 90)
			(layer "B.Fab")
			(effects
				(font
					(size 0.7 0.7)
					(thickness 0.15)
				)
				(justify right bottom mirror)
			)
		)
		(property "Datasheet" "https://www.murata.com/products/productdetail?partno=GRM21BR60J107ME15%23"
			(at 0 0 90)
			(layer "F.Fab")
			(hide yes)
			(effects
				(font
					(size 1.27 1.27)
					(thickness 0.15)
				)
			)
		)
		(property "MPN" "GRM21BR60J107ME15L"
			(at 0 0 90)
			(unlocked yes)
			(layer "B.Fab")
			(hide yes)
			(effects
				(font
					(size 1 1)
					(thickness 0.15)
				)
				(justify mirror)
			)
		)
		(property "Manufacturer" "Murata"
			(at 0 0 90)
			(unlocked yes)
			(layer "B.Fab")
			(hide yes)
			(effects
				(font
					(size 1 1)
					(thickness 0.15)
				)
				(justify mirror)
			)
		)
		(property "License" "Apache-2.0"
			(at 0 0 90)
			(unlocked yes)
			(layer "B.Fab")
			(hide yes)
			(effects
				(font
					(size 1 1)
					(thickness 0.15)
				)
				(justify mirror)
			)
		)
		(property "Author" "Antmicro"
			(at 0 0 90)
			(unlocked yes)
			(layer "B.Fab")
			(hide yes)
			(effects
				(font
					(size 1 1)
					(thickness 0.15)
				)
				(justify mirror)
			)
		)
		(property "Val" "100u"
			(at 0 0 90)
			(unlocked yes)
			(layer "B.Fab")
			(hide yes)
			(effects
				(font
					(size 1 1)
					(thickness 0.15)
				)
				(justify mirror)
			)
		)
		(property "Voltage" ""
			(at 0 0 90)
			(unlocked yes)
			(layer "B.Fab")
			(hide yes)
			(effects
				(font
					(size 1 1)
					(thickness 0.15)
				)
				(justify mirror)
			)
		)
		(property "Dielectric" ""
			(at 0 0 90)
			(unlocked yes)
			(layer "B.Fab")
			(hide yes)
			(effects
				(font
					(size 1 1)
					(thickness 0.15)
				)
				(justify mirror)
			)
		)
		(property "Public" "False"
			(at 0 0 90)
			(unlocked yes)
			(layer "B.Fab")
			(hide yes)
			(effects
				(font
					(size 1 1)
					(thickness 0.15)
				)
				(justify mirror)
			)
		)
		(sheetname "/FPGA power/")
		(sheetfile "fpga-power.kicad_sch")
		(attr smd)
		(fp_line
			(start -0.3 -0.7)
			(end 0.3 -0.7)
			(stroke
				(width 0.15)
				(type solid)
			)
			(layer "B.SilkS")
		)
		(fp_line
			(start -0.3 0.7)
			(end 0.3 0.7)
			(stroke
				(width 0.15)
				(type solid)
			)
			(layer "B.SilkS")
		)
		(fp_rect
			(start 1.95 0.9)
			(end -1.95 -0.9)
			(stroke
				(width 0.05)
				(type default)
			)
			(fill no)
			(layer "B.CrtYd")
		)
		(fp_rect
			(start -0.95 0.675)
			(end 0.95 -0.675)
			(stroke
				(width 0.15)
				(type solid)
			)
			(fill no)
			(layer "B.Fab")
		)
		(fp_text user "License: Apache-2.0"
			(at -1.9 -4.947 270)
			(layer "B.Fab")
			(effects
				(font
					(size 0.7 0.7)
					(thickness 0.15)
				)
				(justify left bottom mirror)
			)
		)
		(fp_text user "Author: Antmicro"
			(at -1.9 -5.947 270)
			(layer "B.Fab")
			(effects
				(font
					(size 0.7 0.7)
					(thickness 0.15)
				)
				(justify left bottom mirror)
			)
		)
		(fp_text user "${REFERENCE}"
			(at -1.9 -3.947 270)
			(layer "B.Fab")
			(effects
				(font
					(size 0.7 0.7)
					(thickness 0.15)
				)
				(justify left bottom mirror)
			)
		)
		(pad "1" smd roundrect
			(at -1.1 0 90)
			(size 1.2 1.3)
			(layers "B.Cu" "B.Mask" "B.Paste")
			(roundrect_rratio 0.25)
			(net 1 "GND")
			(pintype "passive")
		)
		(pad "2" smd roundrect
			(at 1.1 0 90)
			(size 1.2 1.3)
			(layers "B.Cu" "B.Mask" "B.Paste")
			(roundrect_rratio 0.25)
			(net 553 "+0V85")
			(pintype "passive")
		)
	)
	(footprint "antmicro-footprints:R_0402_1005Metric"
		(layer "B.Cu")
		(at 188.4 103.2 180)
		(descr "Resistor SMD 0402")
		(tags "resistor SMD 0402")
		(property "Reference" "R25"
			(at -3.13 -0.41 0)
			(layer "B.SilkS")
			(effects
				(font
					(size 0.7 0.7)
					(thickness 0.15)
				)
				(justify left bottom mirror)
			)
		)
		(property "Value" "R_47k_0402"
			(at -1.011843 -1.772047 0)
			(layer "B.Fab")
			(effects
				(font
					(size 0.7 0.7)
					(thickness 0.15)
				)
				(justify left bottom mirror)
			)
		)
		(property "Datasheet" "https://www.bourns.com/docs/product-datasheets/cr.pdf"
			(at 0 0 180)
			(layer "F.Fab")
			(hide yes)
			(effects
				(font
					(size 1.27 1.27)
					(thickness 0.15)
				)
			)
		)
		(property "MPN" "CR0402-FX-4702GLF"
			(at 0 0 180)
			(unlocked yes)
			(layer "B.Fab")
			(hide yes)
			(effects
				(font
					(size 1 1)
					(thickness 0.15)
				)
				(justify mirror)
			)
		)
		(property "Manufacturer" "Bourns"
			(at 0 0 180)
			(unlocked yes)
			(layer "B.Fab")
			(hide yes)
			(effects
				(font
					(size 1 1)
					(thickness 0.15)
				)
				(justify mirror)
			)
		)
		(property "License" "Apache-2.0"
			(at 0 0 180)
			(unlocked yes)
			(layer "B.Fab")
			(hide yes)
			(effects
				(font
					(size 1 1)
					(thickness 0.15)
				)
				(justify mirror)
			)
		)
		(property "Author" "Antmicro"
			(at 0 0 180)
			(unlocked yes)
			(layer "B.Fab")
			(hide yes)
			(effects
				(font
					(size 1 1)
					(thickness 0.15)
				)
				(justify mirror)
			)
		)
		(property "Val" "47k"
			(at 0 0 180)
			(unlocked yes)
			(layer "B.Fab")
			(hide yes)
			(effects
				(font
					(size 1 1)
					(thickness 0.15)
				)
				(justify mirror)
			)
		)
		(property "Tolerance" "1%"
			(at 0 0 180)
			(unlocked yes)
			(layer "B.Fab")
			(hide yes)
			(effects
				(font
					(size 1 1)
					(thickness 0.15)
				)
				(justify mirror)
			)
		)
		(sheetname "/DDR5 RDIMM/")
		(sheetfile "ddr5-rdimm.kicad_sch")
		(attr smd)
		(fp_rect
			(start -0.925 0.47)
			(end 0.925 -0.47)
			(stroke
				(width 0.05)
				(type default)
			)
			(fill no)
			(layer "B.CrtYd")
		)
		(fp_rect
			(start -0.5 0.25)
			(end 0.5 -0.25)
			(stroke
				(width 0.15)
				(type solid)
			)
			(fill no)
			(layer "B.Fab")
		)
		(fp_text user "Author: Antmicro"
			(at -0.95 -4.169 0)
			(layer "B.Fab")
			(effects
				(font
					(size 0.7 0.7)
					(thickness 0.15)
				)
				(justify left bottom mirror)
			)
		)
		(fp_text user "License: Apache-2.0"
			(at -0.95 -5.169 0)
			(layer "B.Fab")
			(effects
				(font
					(size 0.7 0.7)
					(thickness 0.15)
				)
				(justify left bottom mirror)
			)
		)
		(fp_text user "${REFERENCE}"
			(at -0.95 -3.168 0)
			(layer "B.Fab")
			(effects
				(font
					(size 0.7 0.7)
					(thickness 0.15)
				)
				(justify left bottom mirror)
			)
		)
		(pad "1" smd roundrect
			(at -0.48 0 180)
			(size 0.59 0.64)
			(layers "B.Cu" "B.Mask" "B.Paste")
			(roundrect_rratio 0.25)
			(net 703 "/DDR5 RDIMM/VSS_DET1")
			(pintype "passive")
		)
		(pad "2" smd roundrect
			(at 0.48 0 180)
			(size 0.59 0.64)
			(layers "B.Cu" "B.Mask" "B.Paste")
			(roundrect_rratio 0.25)
			(net 151 "+3V3")
			(pintype "passive")
		)
	)
	(footprint "antmicro-footprints:C_0402_1005Metric_EIA"
		(layer "B.Cu")
		(at 192.5 160)
		(descr "Capacitor SMD 0402 (1005 Metric), square (rectangular) end terminal, IPC_7351 nominal, (Body size source: IPC-SM-782 page 76, https://www.pcb-3d.com/wordpress/wp-content/uploads/ipc-sm-782a_amendment_1_and_2.pdf)")
		(tags "capacitor 0402")
		(property "Reference" "C97"
			(at -32.125 -9.775 0)
			(layer "B.SilkS")
			(effects
				(font
					(size 0.7 0.7)
					(thickness 0.15)
				)
				(justify right bottom mirror)
			)
		)
		(property "Value" "C_4u7_0402"
			(at 0 -1.169 0)
			(layer "B.Fab")
			(effects
				(font
					(size 0.7 0.7)
					(thickness 0.15)
				)
				(justify right bottom mirror)
			)
		)
		(property "Datasheet" "https://www.murata.com/products/productdetail?partno=GRM155R61A475MEAA%23"
			(at 0 0 0)
			(layer "F.Fab")
			(hide yes)
			(effects
				(font
					(size 1.27 1.27)
					(thickness 0.15)
				)
			)
		)
		(property "Manufacturer" "Murata"
			(at 0 0 0)
			(unlocked yes)
			(layer "B.Fab")
			(hide yes)
			(effects
				(font
					(size 1 1)
					(thickness 0.15)
				)
				(justify mirror)
			)
		)
		(property "MPN" "GRM155R61A475MEAAD"
			(at 0 0 0)
			(unlocked yes)
			(layer "B.Fab")
			(hide yes)
			(effects
				(font
					(size 1 1)
					(thickness 0.15)
				)
				(justify mirror)
			)
		)
		(property "Val" "4u7"
			(at 0 0 0)
			(unlocked yes)
			(layer "B.Fab")
			(hide yes)
			(effects
				(font
					(size 1 1)
					(thickness 0.15)
				)
				(justify mirror)
			)
		)
		(property "License" "Apache-2.0"
			(at 0 0 0)
			(unlocked yes)
			(layer "B.Fab")
			(hide yes)
			(effects
				(font
					(size 1 1)
					(thickness 0.15)
				)
				(justify mirror)
			)
		)
		(property "Author" "Antmicro"
			(at 0 0 0)
			(unlocked yes)
			(layer "B.Fab")
			(hide yes)
			(effects
				(font
					(size 1 1)
					(thickness 0.15)
				)
				(justify mirror)
			)
		)
		(property "Voltage" ""
			(at 0 0 0)
			(unlocked yes)
			(layer "B.Fab")
			(hide yes)
			(effects
				(font
					(size 1 1)
					(thickness 0.15)
				)
				(justify mirror)
			)
		)
		(property "Dielectric" ""
			(at 0 0 0)
			(unlocked yes)
			(layer "B.Fab")
			(hide yes)
			(effects
				(font
					(size 1 1)
					(thickness 0.15)
				)
				(justify mirror)
			)
		)
		(sheetname "/FPGA power/")
		(sheetfile "fpga-power.kicad_sch")
		(attr smd)
		(fp_rect
			(start -0.95 0.45)
			(end 0.95 -0.45)
			(stroke
				(width 0.05)
				(type default)
			)
			(fill no)
			(layer "B.CrtYd")
		)
		(fp_line
			(start -0.5 -0.248)
			(end -0.5 0.25)
			(stroke
				(width 0.15)
				(type solid)
			)
			(layer "B.Fab")
		)
		(fp_line
			(start -0.5 0.25)
			(end 0.498 0.25)
			(stroke
				(width 0.15)
				(type solid)
			)
			(layer "B.Fab")
		)
		(fp_line
			(start 0.498 -0.248)
			(end -0.5 -0.248)
			(stroke
				(width 0.15)
				(type solid)
			)
			(layer "B.Fab")
		)
		(fp_line
			(start 0.498 0.25)
			(end 0.498 -0.248)
			(stroke
				(width 0.15)
				(type solid)
			)
			(layer "B.Fab")
		)
		(fp_text user "Author: Antmicro"
			(at -0.9656 -5.569 180)
			(layer "B.Fab")
			(effects
				(font
					(size 0.7 0.7)
					(thickness 0.15)
				)
				(justify left bottom mirror)
			)
		)
		(fp_text user "${REFERENCE}"
			(at -0.9656 -3.169 180)
			(layer "B.Fab")
			(effects
				(font
					(size 0.7 0.7)
					(thickness 0.15)
				)
				(justify left bottom mirror)
			)
		)
		(fp_text user "License: Apache-2.0"
			(at -0.9656 -4.369 180)
			(layer "B.Fab")
			(effects
				(font
					(size 0.7 0.7)
					(thickness 0.15)
				)
				(justify left bottom mirror)
			)
		)
		(pad "1" smd roundrect
			(at -0.5 0 270)
			(size 0.6 0.6)
			(layers "B.Cu" "B.Mask" "B.Paste")
			(roundrect_rratio 0.25)
			(net 573 "+1V8_MGTVCCAUX")
			(pintype "passive")
		)
		(pad "2" smd roundrect
			(at 0.498 0)
			(size 0.6 0.6)
			(layers "B.Cu" "B.Mask" "B.Paste")
			(roundrect_rratio 0.25)
			(net 1 "GND")
			(pintype "passive")
		)
	)
	(footprint "antmicro-footprints:C_0402_1005Metric"
		(layer "B.Cu")
		(at 182.510001 167.45 90)
		(descr "Capacitor SMD 0402")
		(tags "capacitor SMD 0402")
		(property "Reference" "C292"
			(at -4 0.115999 90)
			(layer "B.SilkS")
			(effects
				(font
					(size 0.7 0.7)
					(thickness 0.15)
				)
				(justify right bottom mirror)
			)
		)
		(property "Value" "C_100n_0402"
			(at -1.022927 -2.155213 90)
			(layer "B.Fab")
			(effects
				(font
					(size 0.7 0.7)
					(thickness 0.15)
				)
				(justify right bottom mirror)
			)
		)
		(property "Datasheet" "https://www.murata.com/products/productdetail?partno=GRM155R61H104KE14%23"
			(at 0 0 90)
			(layer "F.Fab")
			(hide yes)
			(effects
				(font
					(size 1.27 1.27)
					(thickness 0.15)
				)
			)
		)
		(property "Manufacturer" "Murata"
			(at 0 0 90)
			(unlocked yes)
			(layer "B.Fab")
			(hide yes)
			(effects
				(font
					(size 1 1)
					(thickness 0.15)
				)
				(justify mirror)
			)
		)
		(property "MPN" "GRM155R61H104KE14D"
			(at 0 0 90)
			(unlocked yes)
			(layer "B.Fab")
			(hide yes)
			(effects
				(font
					(size 1 1)
					(thickness 0.15)
				)
				(justify mirror)
			)
		)
		(property "Val" "100n"
			(at 0 0 90)
			(unlocked yes)
			(layer "B.Fab")
			(hide yes)
			(effects
				(font
					(size 1 1)
					(thickness 0.15)
				)
				(justify mirror)
			)
		)
		(property "License" "Apache-2.0"
			(at 0 0 90)
			(unlocked yes)
			(layer "B.Fab")
			(hide yes)
			(effects
				(font
					(size 1 1)
					(thickness 0.15)
				)
				(justify mirror)
			)
		)
		(property "Author" "Antmicro"
			(at 0 0 90)
			(unlocked yes)
			(layer "B.Fab")
			(hide yes)
			(effects
				(font
					(size 1 1)
					(thickness 0.15)
				)
				(justify mirror)
			)
		)
		(property "Voltage" "50V"
			(at 0 0 90)
			(unlocked yes)
			(layer "B.Fab")
			(hide yes)
			(effects
				(font
					(size 1 1)
					(thickness 0.15)
				)
				(justify mirror)
			)
		)
		(property "Dielectric" "X5R"
			(at 0 0 90)
			(unlocked yes)
			(layer "B.Fab")
			(hide yes)
			(effects
				(font
					(size 1 1)
					(thickness 0.15)
				)
				(justify mirror)
			)
		)
		(sheetname "/FPGA MGT Interface/")
		(sheetfile "fpga-mgt.kicad_sch")
		(attr smd)
		(fp_rect
			(start -0.925 0.47)
			(end 0.925 -0.47)
			(stroke
				(width 0.05)
				(type default)
			)
			(fill no)
			(layer "B.CrtYd")
		)
		(fp_line
			(start 0.504 -0.248)
			(end -0.494 -0.248)
			(stroke
				(width 0.15)
				(type solid)
			)
			(layer "B.Fab")
		)
		(fp_line
			(start -0.494 -0.248)
			(end -0.494 0.25)
			(stroke
				(width 0.15)
				(type solid)
			)
			(layer "B.Fab")
		)
		(fp_line
			(start 0.504 0.25)
			(end 0.504 -0.248)
			(stroke
				(width 0.15)
				(type solid)
			)
			(layer "B.Fab")
		)
		(fp_line
			(start -0.494 0.25)
			(end 0.504 0.25)
			(stroke
				(width 0.15)
				(type solid)
			)
			(layer "B.Fab")
		)
		(fp_text user "Author: Antmicro"
			(at -0.939 -3.399 270)
			(layer "B.Fab")
			(effects
				(font
					(size 0.7 0.7)
					(thickness 0.15)
				)
				(justify left bottom mirror)
			)
		)
		(fp_text user "License: Apache-2.0"
			(at -0.939 -5.799 270)
			(layer "B.Fab")
			(effects
				(font
					(size 0.7 0.7)
					(thickness 0.15)
				)
				(justify left bottom mirror)
			)
		)
		(fp_text user "${REFERENCE}"
			(at -0.939 -4.599 270)
			(layer "B.Fab")
			(effects
				(font
					(size 0.7 0.7)
					(thickness 0.15)
				)
				(justify left bottom mirror)
			)
		)
		(pad "1" smd roundrect
			(at -0.48 0 90)
			(size 0.59 0.64)
			(layers "B.Cu" "B.Mask" "B.Paste")
			(roundrect_rratio 0.25)
			(net 294 "/FPGA MGT Interface/HDMI_OUT.D2_P")
			(pintype "passive")
		)
		(pad "2" smd roundrect
			(at 0.48 0 90)
			(size 0.59 0.64)
			(layers "B.Cu" "B.Mask" "B.Paste")
			(roundrect_rratio 0.25)
			(net 628 "/FPGA MGT Interface/HDMI_FPGA.TX2_P")
			(pintype "passive")
		)
	)
	(footprint "antmicro-footprints:R_0402_1005Metric"
		(layer "B.Cu")
		(at 253.75 117.11 180)
		(descr "Resistor SMD 0402")
		(tags "resistor SMD 0402")
		(property "Reference" "R244"
			(at -1.37 0.57 0)
			(layer "B.SilkS")
			(effects
				(font
					(size 0.7 0.7)
					(thickness 0.15)
				)
				(justify left bottom mirror)
			)
		)
		(property "Value" "R_47k_0402"
			(at -1.011843 -1.772047 0)
			(layer "B.Fab")
			(effects
				(font
					(size 0.7 0.7)
					(thickness 0.15)
				)
				(justify left bottom mirror)
			)
		)
		(property "Datasheet" "https://www.bourns.com/docs/product-datasheets/cr.pdf"
			(at 0 0 180)
			(layer "F.Fab")
			(hide yes)
			(effects
				(font
					(size 1.27 1.27)
					(thickness 0.15)
				)
			)
		)
		(property "MPN" "CR0402-FX-4702GLF"
			(at 0 0 180)
			(unlocked yes)
			(layer "B.Fab")
			(hide yes)
			(effects
				(font
					(size 1 1)
					(thickness 0.15)
				)
				(justify mirror)
			)
		)
		(property "Manufacturer" "Bourns"
			(at 0 0 180)
			(unlocked yes)
			(layer "B.Fab")
			(hide yes)
			(effects
				(font
					(size 1 1)
					(thickness 0.15)
				)
				(justify mirror)
			)
		)
		(property "License" "Apache-2.0"
			(at 0 0 180)
			(unlocked yes)
			(layer "B.Fab")
			(hide yes)
			(effects
				(font
					(size 1 1)
					(thickness 0.15)
				)
				(justify mirror)
			)
		)
		(property "Author" "Antmicro"
			(at 0 0 180)
			(unlocked yes)
			(layer "B.Fab")
			(hide yes)
			(effects
				(font
					(size 1 1)
					(thickness 0.15)
				)
				(justify mirror)
			)
		)
		(property "Val" "47k"
			(at 0 0 180)
			(unlocked yes)
			(layer "B.Fab")
			(hide yes)
			(effects
				(font
					(size 1 1)
					(thickness 0.15)
				)
				(justify mirror)
			)
		)
		(property "Tolerance" "1%"
			(at 0 0 180)
			(unlocked yes)
			(layer "B.Fab")
			(hide yes)
			(effects
				(font
					(size 1 1)
					(thickness 0.15)
				)
				(justify mirror)
			)
		)
		(sheetname "/DDR5 RDIMM/")
		(sheetfile "ddr5-rdimm.kicad_sch")
		(attr smd)
		(fp_rect
			(start -0.925 0.47)
			(end 0.925 -0.47)
			(stroke
				(width 0.05)
				(type default)
			)
			(fill no)
			(layer "B.CrtYd")
		)
		(fp_rect
			(start -0.5 0.25)
			(end 0.5 -0.25)
			(stroke
				(width 0.15)
				(type solid)
			)
			(fill no)
			(layer "B.Fab")
		)
		(fp_text user "Author: Antmicro"
			(at -0.95 -4.169 0)
			(layer "B.Fab")
			(effects
				(font
					(size 0.7 0.7)
					(thickness 0.15)
				)
				(justify left bottom mirror)
			)
		)
		(fp_text user "${REFERENCE}"
			(at -0.95 -3.168 0)
			(layer "B.Fab")
			(effects
				(font
					(size 0.7 0.7)
					(thickness 0.15)
				)
				(justify left bottom mirror)
			)
		)
		(fp_text user "License: Apache-2.0"
			(at -0.95 -5.169 0)
			(layer "B.Fab")
			(effects
				(font
					(size 0.7 0.7)
					(thickness 0.15)
				)
				(justify left bottom mirror)
			)
		)
		(pad "1" smd roundrect
			(at -0.48 0 180)
			(size 0.59 0.64)
			(layers "B.Cu" "B.Mask" "B.Paste")
			(roundrect_rratio 0.25)
			(net 807 "Net-(Q26-D)")
			(pintype "passive")
		)
		(pad "2" smd roundrect
			(at 0.48 0 180)
			(size 0.59 0.64)
			(layers "B.Cu" "B.Mask" "B.Paste")
			(roundrect_rratio 0.25)
			(net 151 "+3V3")
			(pintype "passive")
		)
	)
	(footprint "antmicro-footprints:C_0402_1005Metric"
		(layer "B.Cu")
		(at 247.475 187.338)
		(descr "Capacitor SMD 0402")
		(tags "capacitor SMD 0402")
		(property "Reference" "C318"
			(at 0.825 0.461 0)
			(layer "B.SilkS")
			(effects
				(font
					(size 0.7 0.7)
					(thickness 0.15)
				)
				(justify right bottom mirror)
			)
		)
		(property "Value" "C_100n_0402"
			(at -1.022927 -2.155213 0)
			(layer "B.Fab")
			(effects
				(font
					(size 0.7 0.7)
					(thickness 0.15)
				)
				(justify right bottom mirror)
			)
		)
		(property "Datasheet" "https://www.murata.com/products/productdetail?partno=GRM155R61H104KE14%23"
			(at 0 0 0)
			(layer "F.Fab")
			(hide yes)
			(effects
				(font
					(size 1.27 1.27)
					(thickness 0.15)
				)
			)
		)
		(property "MPN" "GRM155R61H104KE14D"
			(at 0 0 0)
			(unlocked yes)
			(layer "B.Fab")
			(hide yes)
			(effects
				(font
					(size 1 1)
					(thickness 0.15)
				)
				(justify mirror)
			)
		)
		(property "Manufacturer" "Murata"
			(at 0 0 0)
			(unlocked yes)
			(layer "B.Fab")
			(hide yes)
			(effects
				(font
					(size 1 1)
					(thickness 0.15)
				)
				(justify mirror)
			)
		)
		(property "License" "Apache-2.0"
			(at 0 0 0)
			(unlocked yes)
			(layer "B.Fab")
			(hide yes)
			(effects
				(font
					(size 1 1)
					(thickness 0.15)
				)
				(justify mirror)
			)
		)
		(property "Author" "Antmicro"
			(at 0 0 0)
			(unlocked yes)
			(layer "B.Fab")
			(hide yes)
			(effects
				(font
					(size 1 1)
					(thickness 0.15)
				)
				(justify mirror)
			)
		)
		(property "Val" "100n"
			(at 0 0 0)
			(unlocked yes)
			(layer "B.Fab")
			(hide yes)
			(effects
				(font
					(size 1 1)
					(thickness 0.15)
				)
				(justify mirror)
			)
		)
		(property "Voltage" "50V"
			(at 0 0 0)
			(unlocked yes)
			(layer "B.Fab")
			(hide yes)
			(effects
				(font
					(size 1 1)
					(thickness 0.15)
				)
				(justify mirror)
			)
		)
		(property "Dielectric" "X5R"
			(at 0 0 0)
			(unlocked yes)
			(layer "B.Fab")
			(hide yes)
			(effects
				(font
					(size 1 1)
					(thickness 0.15)
				)
				(justify mirror)
			)
		)
		(sheetname "/I^{2}C + I3C/")
		(sheetfile "i2c.kicad_sch")
		(attr smd)
		(fp_rect
			(start -0.925 0.47)
			(end 0.925 -0.47)
			(stroke
				(width 0.05)
				(type default)
			)
			(fill no)
			(layer "B.CrtYd")
		)
		(fp_line
			(start -0.494 -0.248)
			(end -0.494 0.25)
			(stroke
				(width 0.15)
				(type solid)
			)
			(layer "B.Fab")
		)
		(fp_line
			(start -0.494 0.25)
			(end 0.504 0.25)
			(stroke
				(width 0.15)
				(type solid)
			)
			(layer "B.Fab")
		)
		(fp_line
			(start 0.504 -0.248)
			(end -0.494 -0.248)
			(stroke
				(width 0.15)
				(type solid)
			)
			(layer "B.Fab")
		)
		(fp_line
			(start 0.504 0.25)
			(end 0.504 -0.248)
			(stroke
				(width 0.15)
				(type solid)
			)
			(layer "B.Fab")
		)
		(fp_text user "Author: Antmicro"
			(at -0.939 -3.399 180)
			(layer "B.Fab")
			(effects
				(font
					(size 0.7 0.7)
					(thickness 0.15)
				)
				(justify left bottom mirror)
			)
		)
		(fp_text user "${REFERENCE}"
			(at -0.939 -4.599 180)
			(layer "B.Fab")
			(effects
				(font
					(size 0.7 0.7)
					(thickness 0.15)
				)
				(justify left bottom mirror)
			)
		)
		(fp_text user "License: Apache-2.0"
			(at -0.939 -5.799 180)
			(layer "B.Fab")
			(effects
				(font
					(size 0.7 0.7)
					(thickness 0.15)
				)
				(justify left bottom mirror)
			)
		)
		(pad "1" smd roundrect
			(at -0.48 0)
			(size 0.59 0.64)
			(layers "B.Cu" "B.Mask" "B.Paste")
			(roundrect_rratio 0.25)
			(net 1 "GND")
			(pintype "passive")
		)
		(pad "2" smd roundrect
			(at 0.48 0)
			(size 0.59 0.64)
			(layers "B.Cu" "B.Mask" "B.Paste")
			(roundrect_rratio 0.25)
			(net 662 "Net-(Q22-D)")
			(pintype "passive")
		)
	)
	(footprint "antmicro-footprints:R_0402_1005Metric_EIA"
		(layer "B.Cu")
		(at 199 157.5 -90)
		(descr "Resistor SMD 0402 (1005 Metric), square (rectangular) end terminal, IPC_7351 nominal, (Body size source: IPC-SM-782 page 76, https://www.pcb-3d.com/wordpress/wp-content/uploads/ipc-sm-782a_amendment_1_and_2.pdf)")
		(tags "resistor 0402")
		(property "Reference" "R36"
			(at -11.925 29.575 90)
			(layer "B.SilkS")
			(effects
				(font
					(size 0.7 0.7)
					(thickness 0.15)
				)
				(justify left bottom mirror)
			)
		)
		(property "Value" "R_100R_0402"
			(at 0 -1.169 90)
			(layer "B.Fab")
			(effects
				(font
					(size 0.7 0.7)
					(thickness 0.15)
				)
				(justify left bottom mirror)
			)
		)
		(property "Datasheet" "https://www.bourns.com/docs/product-datasheets/cr.pdf"
			(at 0 0 270)
			(layer "F.Fab")
			(hide yes)
			(effects
				(font
					(size 1.27 1.27)
					(thickness 0.15)
				)
			)
		)
		(property "Manufacturer" "Bourns"
			(at 0 0 270)
			(unlocked yes)
			(layer "B.Fab")
			(hide yes)
			(effects
				(font
					(size 1 1)
					(thickness 0.15)
				)
				(justify mirror)
			)
		)
		(property "MPN" "CR0402-FX-1000GLF"
			(at 0 0 270)
			(unlocked yes)
			(layer "B.Fab")
			(hide yes)
			(effects
				(font
					(size 1 1)
					(thickness 0.15)
				)
				(justify mirror)
			)
		)
		(property "Val" "100R"
			(at 0 0 270)
			(unlocked yes)
			(layer "B.Fab")
			(hide yes)
			(effects
				(font
					(size 1 1)
					(thickness 0.15)
				)
				(justify mirror)
			)
		)
		(property "License" "Apache-2.0"
			(at 0 0 270)
			(unlocked yes)
			(layer "B.Fab")
			(hide yes)
			(effects
				(font
					(size 1 1)
					(thickness 0.15)
				)
				(justify mirror)
			)
		)
		(property "Author" "Antmicro"
			(at 0 0 270)
			(unlocked yes)
			(layer "B.Fab")
			(hide yes)
			(effects
				(font
					(size 1 1)
					(thickness 0.15)
				)
				(justify mirror)
			)
		)
		(property "Tolerance" "1%"
			(at 0 0 270)
			(unlocked yes)
			(layer "B.Fab")
			(hide yes)
			(effects
				(font
					(size 1 1)
					(thickness 0.15)
				)
				(justify mirror)
			)
		)
		(sheetname "/FPGA power/")
		(sheetfile "fpga-power.kicad_sch")
		(attr smd)
		(fp_rect
			(start -0.95 0.45)
			(end 0.95 -0.45)
			(stroke
				(width 0.05)
				(type default)
			)
			(fill no)
			(layer "B.CrtYd")
		)
		(fp_line
			(start -0.5 0.25)
			(end 0.499 0.25)
			(stroke
				(width 0.15)
				(type solid)
			)
			(layer "B.Fab")
		)
		(fp_line
			(start 0.499 0.25)
			(end 0.499 -0.249)
			(stroke
				(width 0.15)
				(type solid)
			)
			(layer "B.Fab")
		)
		(fp_line
			(start -0.5 -0.249)
			(end -0.5 0.25)
			(stroke
				(width 0.15)
				(type solid)
			)
			(layer "B.Fab")
		)
		(fp_line
			(start 0.499 -0.249)
			(end -0.5 -0.249)
			(stroke
				(width 0.15)
				(type solid)
			)
			(layer "B.Fab")
		)
		(fp_text user "${REFERENCE}"
			(at -0.95 -3.169 90)
			(layer "B.Fab")
			(effects
				(font
					(size 0.7 0.7)
					(thickness 0.15)
				)
				(justify left bottom mirror)
			)
		)
		(fp_text user "Author: Antmicro"
			(at -0.95 -5.569 90)
			(layer "B.Fab")
			(effects
				(font
					(size 0.7 0.7)
					(thickness 0.15)
				)
				(justify left bottom mirror)
			)
		)
		(fp_text user "License: Apache-2.0"
			(at -0.95 -4.369 90)
			(layer "B.Fab")
			(effects
				(font
					(size 0.7 0.7)
					(thickness 0.15)
				)
				(justify left bottom mirror)
			)
		)
		(pad "1" smd roundrect
			(at -0.5 0 180)
			(size 0.6 0.6)
			(layers "B.Cu" "B.Mask" "B.Paste")
			(roundrect_rratio 0.25)
			(net 288 "Net-(U34L-MGTRREF_R)")
			(pintype "passive")
		)
		(pad "2" smd roundrect
			(at 0.499 0 270)
			(size 0.6 0.6)
			(layers "B.Cu" "B.Mask" "B.Paste")
			(roundrect_rratio 0.25)
			(net 172 "+1V2_MGTAVTT")
			(pintype "passive")
		)
	)
	(footprint "antmicro-footprints:C_0402_1005Metric_EIA"
		(layer "B.Cu")
		(at 191 150.5 90)
		(descr "Capacitor SMD 0402 (1005 Metric), square (rectangular) end terminal, IPC_7351 nominal, (Body size source: IPC-SM-782 page 76, https://www.pcb-3d.com/wordpress/wp-content/uploads/ipc-sm-782a_amendment_1_and_2.pdf)")
		(tags "capacitor 0402")
		(property "Reference" "C64"
			(at 9.8 -30.625 90)
			(layer "B.SilkS")
			(effects
				(font
					(size 0.7 0.7)
					(thickness 0.15)
				)
				(justify right bottom mirror)
			)
		)
		(property "Value" "C_100n_0402"
			(at 0 -1.169 90)
			(layer "B.Fab")
			(effects
				(font
					(size 0.7 0.7)
					(thickness 0.15)
				)
				(justify right bottom mirror)
			)
		)
		(property "Datasheet" "https://www.murata.com/products/productdetail?partno=GRM155R61H104KE14%23"
			(at 0 0 90)
			(layer "F.Fab")
			(hide yes)
			(effects
				(font
					(size 1.27 1.27)
					(thickness 0.15)
				)
			)
		)
		(property "MPN" "GRM155R61H104KE14D"
			(at 0 0 90)
			(unlocked yes)
			(layer "B.Fab")
			(hide yes)
			(effects
				(font
					(size 1 1)
					(thickness 0.15)
				)
				(justify mirror)
			)
		)
		(property "Manufacturer" "Murata"
			(at 0 0 90)
			(unlocked yes)
			(layer "B.Fab")
			(hide yes)
			(effects
				(font
					(size 1 1)
					(thickness 0.15)
				)
				(justify mirror)
			)
		)
		(property "License" "Apache-2.0"
			(at 0 0 90)
			(unlocked yes)
			(layer "B.Fab")
			(hide yes)
			(effects
				(font
					(size 1 1)
					(thickness 0.15)
				)
				(justify mirror)
			)
		)
		(property "Author" "Antmicro"
			(at 0 0 90)
			(unlocked yes)
			(layer "B.Fab")
			(hide yes)
			(effects
				(font
					(size 1 1)
					(thickness 0.15)
				)
				(justify mirror)
			)
		)
		(property "Val" "100n"
			(at 0 0 90)
			(unlocked yes)
			(layer "B.Fab")
			(hide yes)
			(effects
				(font
					(size 1 1)
					(thickness 0.15)
				)
				(justify mirror)
			)
		)
		(property "Voltage" "50V"
			(at 0 0 90)
			(unlocked yes)
			(layer "B.Fab")
			(hide yes)
			(effects
				(font
					(size 1 1)
					(thickness 0.15)
				)
				(justify mirror)
			)
		)
		(property "Dielectric" "X5R"
			(at 0 0 90)
			(unlocked yes)
			(layer "B.Fab")
			(hide yes)
			(effects
				(font
					(size 1 1)
					(thickness 0.15)
				)
				(justify mirror)
			)
		)
		(sheetname "/FPGA power/")
		(sheetfile "fpga-power.kicad_sch")
		(attr smd)
		(fp_rect
			(start -0.95 0.45)
			(end 0.95 -0.45)
			(stroke
				(width 0.05)
				(type default)
			)
			(fill no)
			(layer "B.CrtYd")
		)
		(fp_line
			(start 0.498 -0.248)
			(end -0.5 -0.248)
			(stroke
				(width 0.15)
				(type solid)
			)
			(layer "B.Fab")
		)
		(fp_line
			(start -0.5 -0.248)
			(end -0.5 0.25)
			(stroke
				(width 0.15)
				(type solid)
			)
			(layer "B.Fab")
		)
		(fp_line
			(start 0.498 0.25)
			(end 0.498 -0.248)
			(stroke
				(width 0.15)
				(type solid)
			)
			(layer "B.Fab")
		)
		(fp_line
			(start -0.5 0.25)
			(end 0.498 0.25)
			(stroke
				(width 0.15)
				(type solid)
			)
			(layer "B.Fab")
		)
		(fp_text user "License: Apache-2.0"
			(at -0.9656 -4.369 270)
			(layer "B.Fab")
			(effects
				(font
					(size 0.7 0.7)
					(thickness 0.15)
				)
				(justify left bottom mirror)
			)
		)
		(fp_text user "Author: Antmicro"
			(at -0.9656 -5.569 270)
			(layer "B.Fab")
			(effects
				(font
					(size 0.7 0.7)
					(thickness 0.15)
				)
				(justify left bottom mirror)
			)
		)
		(fp_text user "${REFERENCE}"
			(at -0.9656 -3.169 270)
			(layer "B.Fab")
			(effects
				(font
					(size 0.7 0.7)
					(thickness 0.15)
				)
				(justify left bottom mirror)
			)
		)
		(pad "1" smd roundrect
			(at -0.5 0)
			(size 0.6 0.6)
			(layers "B.Cu" "B.Mask" "B.Paste")
			(roundrect_rratio 0.25)
			(net 1 "GND")
			(pintype "passive")
		)
		(pad "2" smd roundrect
			(at 0.498 0 90)
			(size 0.6 0.6)
			(layers "B.Cu" "B.Mask" "B.Paste")
			(roundrect_rratio 0.25)
			(net 553 "+0V85")
			(pintype "passive")
		)
	)
	(footprint "antmicro-footprints:C_0402_1005Metric"
		(layer "B.Cu")
		(at 206.18 141.6045 180)
		(descr "Capacitor SMD 0402")
		(tags "capacitor SMD 0402")
		(property "Reference" "C329"
			(at -2.32 0.0045 0)
			(layer "B.SilkS")
			(effects
				(font
					(size 0.7 0.7)
					(thickness 0.15)
				)
				(justify mirror)
			)
		)
		(property "Value" "C_10u_6.3V_0402"
			(at -1.022927 -2.155213 0)
			(layer "B.Fab")
			(effects
				(font
					(size 0.7 0.7)
					(thickness 0.15)
				)
				(justify left bottom mirror)
			)
		)
		(property "Datasheet" "https://www.murata.com/products/productdetail?partno=GRM155R60J106ME15%23"
			(at 0 0 0)
			(layer "B.Fab")
			(hide yes)
			(effects
				(font
					(size 1.27 1.27)
					(thickness 0.15)
				)
				(justify mirror)
			)
		)
		(property "MPN" "GRM155R60J106ME15D"
			(at 0 0 0)
			(unlocked yes)
			(layer "B.Fab")
			(hide yes)
			(effects
				(font
					(size 1 1)
					(thickness 0.15)
				)
				(justify mirror)
			)
		)
		(property "Manufacturer" "Murata"
			(at 0 0 0)
			(unlocked yes)
			(layer "B.Fab")
			(hide yes)
			(effects
				(font
					(size 1 1)
					(thickness 0.15)
				)
				(justify mirror)
			)
		)
		(property "License" "Apache-2.0"
			(at 0 0 0)
			(unlocked yes)
			(layer "B.Fab")
			(hide yes)
			(effects
				(font
					(size 1 1)
					(thickness 0.15)
				)
				(justify mirror)
			)
		)
		(property "Author" "Antmicro"
			(at 0 0 0)
			(unlocked yes)
			(layer "B.Fab")
			(hide yes)
			(effects
				(font
					(size 1 1)
					(thickness 0.15)
				)
				(justify mirror)
			)
		)
		(property "Val" "10u"
			(at 0 0 0)
			(unlocked yes)
			(layer "B.Fab")
			(hide yes)
			(effects
				(font
					(size 1 1)
					(thickness 0.15)
				)
				(justify mirror)
			)
		)
		(property "Voltage" "6.3V"
			(at 0 0 0)
			(unlocked yes)
			(layer "B.Fab")
			(hide yes)
			(effects
				(font
					(size 1 1)
					(thickness 0.15)
				)
				(justify mirror)
			)
		)
		(property "Dielectric" "X5R"
			(at 0 0 0)
			(unlocked yes)
			(layer "B.Fab")
			(hide yes)
			(effects
				(font
					(size 1 1)
					(thickness 0.15)
				)
				(justify mirror)
			)
		)
		(sheetname "/Supply/")
		(sheetfile "supply.kicad_sch")
		(attr smd)
		(fp_rect
			(start -0.925 0.47)
			(end 0.925 -0.47)
			(stroke
				(width 0.05)
				(type default)
			)
			(fill no)
			(layer "B.CrtYd")
		)
		(fp_line
			(start 0.504 0.25)
			(end 0.504 -0.248)
			(stroke
				(width 0.15)
				(type solid)
			)
			(layer "B.Fab")
		)
		(fp_line
			(start 0.504 -0.248)
			(end -0.494 -0.248)
			(stroke
				(width 0.15)
				(type solid)
			)
			(layer "B.Fab")
		)
		(fp_line
			(start -0.494 0.25)
			(end 0.504 0.25)
			(stroke
				(width 0.15)
				(type solid)
			)
			(layer "B.Fab")
		)
		(fp_line
			(start -0.494 -0.248)
			(end -0.494 0.25)
			(stroke
				(width 0.15)
				(type solid)
			)
			(layer "B.Fab")
		)
		(fp_text user "License: Apache-2.0"
			(at -0.939 -5.799 0)
			(layer "B.Fab")
			(effects
				(font
					(size 0.7 0.7)
					(thickness 0.15)
				)
				(justify left bottom mirror)
			)
		)
		(fp_text user "${REFERENCE}"
			(at -0.939 -4.599 0)
			(layer "B.Fab")
			(effects
				(font
					(size 0.7 0.7)
					(thickness 0.15)
				)
				(justify left bottom mirror)
			)
		)
		(fp_text user "Author: Antmicro"
			(at -0.939 -3.399 0)
			(layer "B.Fab")
			(effects
				(font
					(size 0.7 0.7)
					(thickness 0.15)
				)
				(justify left bottom mirror)
			)
		)
		(pad "1" smd roundrect
			(at -0.48 0 180)
			(size 0.59 0.64)
			(layers "B.Cu" "B.Mask" "B.Paste")
			(roundrect_rratio 0.25)
			(net 1 "GND")
			(pintype "passive")
		)
		(pad "2" smd roundrect
			(at 0.48 0 180)
			(size 0.59 0.64)
			(layers "B.Cu" "B.Mask" "B.Paste")
			(roundrect_rratio 0.25)
			(net 151 "+3V3")
			(pintype "passive")
		)
	)
	(footprint "antmicro-footprints:R_0402_1005Metric"
		(layer "B.Cu")
		(at 209.89 153.1505 180)
		(descr "Resistor SMD 0402")
		(tags "resistor SMD 0402")
		(property "Reference" "R9"
			(at 0.96 0.0405 0)
			(layer "B.SilkS")
			(effects
				(font
					(size 0.7 0.7)
					(thickness 0.15)
				)
				(justify left bottom mirror)
			)
		)
		(property "Value" "R_22R_0402"
			(at -1.011843 -1.772047 0)
			(layer "B.Fab")
			(effects
				(font
					(size 0.7 0.7)
					(thickness 0.15)
				)
				(justify left bottom mirror)
			)
		)
		(property "Datasheet" "https://www.bourns.com/docs/product-datasheets/cr.pdf"
			(at 0 0 180)
			(layer "F.Fab")
			(hide yes)
			(effects
				(font
					(size 1.27 1.27)
					(thickness 0.15)
				)
			)
		)
		(property "Manufacturer" "Bourns"
			(at 0 0 180)
			(unlocked yes)
			(layer "B.Fab")
			(hide yes)
			(effects
				(font
					(size 1 1)
					(thickness 0.15)
				)
				(justify mirror)
			)
		)
		(property "MPN" "CR0402-FX-22R0GLF"
			(at 0 0 180)
			(unlocked yes)
			(layer "B.Fab")
			(hide yes)
			(effects
				(font
					(size 1 1)
					(thickness 0.15)
				)
				(justify mirror)
			)
		)
		(property "Val" "22R"
			(at 0 0 180)
			(unlocked yes)
			(layer "B.Fab")
			(hide yes)
			(effects
				(font
					(size 1 1)
					(thickness 0.15)
				)
				(justify mirror)
			)
		)
		(property "License" "Apache-2.0"
			(at 0 0 180)
			(unlocked yes)
			(layer "B.Fab")
			(hide yes)
			(effects
				(font
					(size 1 1)
					(thickness 0.15)
				)
				(justify mirror)
			)
		)
		(property "Author" "Antmicro"
			(at 0 0 180)
			(unlocked yes)
			(layer "B.Fab")
			(hide yes)
			(effects
				(font
					(size 1 1)
					(thickness 0.15)
				)
				(justify mirror)
			)
		)
		(property "Tolerance" "1%"
			(at 0 0 180)
			(unlocked yes)
			(layer "B.Fab")
			(hide yes)
			(effects
				(font
					(size 1 1)
					(thickness 0.15)
				)
				(justify mirror)
			)
		)
		(sheetname "/HyperRAM + QSPI Flash/")
		(sheetfile "hyperram-flash.kicad_sch")
		(attr smd)
		(fp_rect
			(start -0.925 0.47)
			(end 0.925 -0.47)
			(stroke
				(width 0.05)
				(type default)
			)
			(fill no)
			(layer "B.CrtYd")
		)
		(fp_rect
			(start -0.5 0.25)
			(end 0.5 -0.25)
			(stroke
				(width 0.15)
				(type solid)
			)
			(fill no)
			(layer "B.Fab")
		)
		(fp_text user "${REFERENCE}"
			(at -0.95 -3.168 0)
			(layer "B.Fab")
			(effects
				(font
					(size 0.7 0.7)
					(thickness 0.15)
				)
				(justify left bottom mirror)
			)
		)
		(fp_text user "License: Apache-2.0"
			(at -0.95 -5.169 0)
			(layer "B.Fab")
			(effects
				(font
					(size 0.7 0.7)
					(thickness 0.15)
				)
				(justify left bottom mirror)
			)
		)
		(fp_text user "Author: Antmicro"
			(at -0.95 -4.169 0)
			(layer "B.Fab")
			(effects
				(font
					(size 0.7 0.7)
					(thickness 0.15)
				)
				(justify left bottom mirror)
			)
		)
		(pad "1" smd roundrect
			(at -0.48 0 180)
			(size 0.59 0.64)
			(layers "B.Cu" "B.Mask" "B.Paste")
			(roundrect_rratio 0.25)
			(net 279 "/HyperRAM + QSPI Flash/IO3")
			(pintype "passive")
		)
		(pad "2" smd roundrect
			(at 0.48 0 180)
			(size 0.59 0.64)
			(layers "B.Cu" "B.Mask" "B.Paste")
			(roundrect_rratio 0.25)
			(net 354 "/FPGA Config/FLASH.IO3")
			(pintype "passive")
		)
	)
	(footprint "antmicro-footprints:R_0402_1005Metric"
		(layer "B.Cu")
		(at 206.325 154.19 -90)
		(descr "Resistor SMD 0402")
		(tags "resistor SMD 0402")
		(property "Reference" "R39"
			(at 1.36 -0.405 90)
			(layer "B.SilkS")
			(effects
				(font
					(size 0.7 0.7)
					(thickness 0.15)
				)
				(justify left bottom mirror)
			)
		)
		(property "Value" "R_4k7_0402"
			(at -1.011843 -1.772047 90)
			(layer "B.Fab")
			(effects
				(font
					(size 0.7 0.7)
					(thickness 0.15)
				)
				(justify left bottom mirror)
			)
		)
		(property "Datasheet" "https://www.bourns.com/docs/product-datasheets/cr.pdf"
			(at 0 0 270)
			(layer "F.Fab")
			(hide yes)
			(effects
				(font
					(size 1.27 1.27)
					(thickness 0.15)
				)
			)
		)
		(property "MPN" "CR0402-FX-4701GLF"
			(at 0 0 270)
			(unlocked yes)
			(layer "B.Fab")
			(hide yes)
			(effects
				(font
					(size 1 1)
					(thickness 0.15)
				)
				(justify mirror)
			)
		)
		(property "Manufacturer" "Bourns"
			(at 0 0 270)
			(unlocked yes)
			(layer "B.Fab")
			(hide yes)
			(effects
				(font
					(size 1 1)
					(thickness 0.15)
				)
				(justify mirror)
			)
		)
		(property "License" "Apache-2.0"
			(at 0 0 270)
			(unlocked yes)
			(layer "B.Fab")
			(hide yes)
			(effects
				(font
					(size 1 1)
					(thickness 0.15)
				)
				(justify mirror)
			)
		)
		(property "Author" "Antmicro"
			(at 0 0 270)
			(unlocked yes)
			(layer "B.Fab")
			(hide yes)
			(effects
				(font
					(size 1 1)
					(thickness 0.15)
				)
				(justify mirror)
			)
		)
		(property "Val" "4k7"
			(at 0 0 270)
			(unlocked yes)
			(layer "B.Fab")
			(hide yes)
			(effects
				(font
					(size 1 1)
					(thickness 0.15)
				)
				(justify mirror)
			)
		)
		(property "Tolerance" "1%"
			(at 0 0 270)
			(unlocked yes)
			(layer "B.Fab")
			(hide yes)
			(effects
				(font
					(size 1 1)
					(thickness 0.15)
				)
				(justify mirror)
			)
		)
		(sheetname "/FPGA Config/")
		(sheetfile "fpga-config.kicad_sch")
		(attr smd)
		(fp_rect
			(start -0.925 0.47)
			(end 0.925 -0.47)
			(stroke
				(width 0.05)
				(type default)
			)
			(fill no)
			(layer "B.CrtYd")
		)
		(fp_rect
			(start -0.5 0.25)
			(end 0.5 -0.25)
			(stroke
				(width 0.15)
				(type solid)
			)
			(fill no)
			(layer "B.Fab")
		)
		(fp_text user "Author: Antmicro"
			(at -0.95 -4.169 90)
			(layer "B.Fab")
			(effects
				(font
					(size 0.7 0.7)
					(thickness 0.15)
				)
				(justify left bottom mirror)
			)
		)
		(fp_text user "License: Apache-2.0"
			(at -0.95 -5.169 90)
			(layer "B.Fab")
			(effects
				(font
					(size 0.7 0.7)
					(thickness 0.15)
				)
				(justify left bottom mirror)
			)
		)
		(fp_text user "${REFERENCE}"
			(at -0.95 -3.168 90)
			(layer "B.Fab")
			(effects
				(font
					(size 0.7 0.7)
					(thickness 0.15)
				)
				(justify left bottom mirror)
			)
		)
		(pad "1" smd roundrect
			(at -0.48 0 270)
			(size 0.59 0.64)
			(layers "B.Cu" "B.Mask" "B.Paste")
			(roundrect_rratio 0.25)
			(net 151 "+3V3")
			(pintype "passive")
		)
		(pad "2" smd roundrect
			(at 0.48 0 270)
			(size 0.59 0.64)
			(layers "B.Cu" "B.Mask" "B.Paste")
			(roundrect_rratio 0.25)
			(net 705 "/FPGA Config/~{THERM}")
			(pintype "passive")
		)
	)
	(footprint "antmicro-footprints:C_0402_1005Metric_EIA"
		(layer "B.Cu")
		(at 187 158.5 90)
		(descr "Capacitor SMD 0402 (1005 Metric), square (rectangular) end terminal, IPC_7351 nominal, (Body size source: IPC-SM-782 page 76, https://www.pcb-3d.com/wordpress/wp-content/uploads/ipc-sm-782a_amendment_1_and_2.pdf)")
		(tags "capacitor 0402")
		(property "Reference" "C50"
			(at 9.5 -30.675 90)
			(layer "B.SilkS")
			(effects
				(font
					(size 0.7 0.7)
					(thickness 0.15)
				)
				(justify right bottom mirror)
			)
		)
		(property "Value" "C_1u_25V_0402"
			(at 0 -1.169 90)
			(layer "B.Fab")
			(effects
				(font
					(size 0.7 0.7)
					(thickness 0.15)
				)
				(justify right bottom mirror)
			)
		)
		(property "Datasheet" "https://www.murata.com/products/productdetail?partno=GRM155R61E105KE11%23"
			(at 0 0 90)
			(layer "F.Fab")
			(hide yes)
			(effects
				(font
					(size 1.27 1.27)
					(thickness 0.15)
				)
			)
		)
		(property "MPN" "GRM155R61E105KE11J"
			(at 0 0 90)
			(unlocked yes)
			(layer "B.Fab")
			(hide yes)
			(effects
				(font
					(size 1 1)
					(thickness 0.15)
				)
				(justify mirror)
			)
		)
		(property "Manufacturer" "Murata"
			(at 0 0 90)
			(unlocked yes)
			(layer "B.Fab")
			(hide yes)
			(effects
				(font
					(size 1 1)
					(thickness 0.15)
				)
				(justify mirror)
			)
		)
		(property "License" "Apache-2.0"
			(at 0 0 90)
			(unlocked yes)
			(layer "B.Fab")
			(hide yes)
			(effects
				(font
					(size 1 1)
					(thickness 0.15)
				)
				(justify mirror)
			)
		)
		(property "Author" "Antmicro"
			(at 0 0 90)
			(unlocked yes)
			(layer "B.Fab")
			(hide yes)
			(effects
				(font
					(size 1 1)
					(thickness 0.15)
				)
				(justify mirror)
			)
		)
		(property "Val" "1u"
			(at 0 0 90)
			(unlocked yes)
			(layer "B.Fab")
			(hide yes)
			(effects
				(font
					(size 1 1)
					(thickness 0.15)
				)
				(justify mirror)
			)
		)
		(property "Voltage" "25V"
			(at 0 0 90)
			(unlocked yes)
			(layer "B.Fab")
			(hide yes)
			(effects
				(font
					(size 1 1)
					(thickness 0.15)
				)
				(justify mirror)
			)
		)
		(property "Dielectric" "X5R"
			(at 0 0 90)
			(unlocked yes)
			(layer "B.Fab")
			(hide yes)
			(effects
				(font
					(size 1 1)
					(thickness 0.15)
				)
				(justify mirror)
			)
		)
		(sheetname "/FPGA power/")
		(sheetfile "fpga-power.kicad_sch")
		(attr smd)
		(fp_rect
			(start -0.95 0.45)
			(end 0.95 -0.45)
			(stroke
				(width 0.05)
				(type default)
			)
			(fill no)
			(layer "B.CrtYd")
		)
		(fp_line
			(start 0.498 -0.248)
			(end -0.5 -0.248)
			(stroke
				(width 0.15)
				(type solid)
			)
			(layer "B.Fab")
		)
		(fp_line
			(start -0.5 -0.248)
			(end -0.5 0.25)
			(stroke
				(width 0.15)
				(type solid)
			)
			(layer "B.Fab")
		)
		(fp_line
			(start 0.498 0.25)
			(end 0.498 -0.248)
			(stroke
				(width 0.15)
				(type solid)
			)
			(layer "B.Fab")
		)
		(fp_line
			(start -0.5 0.25)
			(end 0.498 0.25)
			(stroke
				(width 0.15)
				(type solid)
			)
			(layer "B.Fab")
		)
		(fp_text user "License: Apache-2.0"
			(at -0.9656 -4.369 270)
			(layer "B.Fab")
			(effects
				(font
					(size 0.7 0.7)
					(thickness 0.15)
				)
				(justify left bottom mirror)
			)
		)
		(fp_text user "${REFERENCE}"
			(at -0.9656 -3.169 270)
			(layer "B.Fab")
			(effects
				(font
					(size 0.7 0.7)
					(thickness 0.15)
				)
				(justify left bottom mirror)
			)
		)
		(fp_text user "Author: Antmicro"
			(at -0.9656 -5.569 270)
			(layer "B.Fab")
			(effects
				(font
					(size 0.7 0.7)
					(thickness 0.15)
				)
				(justify left bottom mirror)
			)
		)
		(pad "1" smd roundrect
			(at -0.5 0)
			(size 0.6 0.6)
			(layers "B.Cu" "B.Mask" "B.Paste")
			(roundrect_rratio 0.25)
			(net 1 "GND")
			(pintype "passive")
		)
		(pad "2" smd roundrect
			(at 0.498 0 90)
			(size 0.6 0.6)
			(layers "B.Cu" "B.Mask" "B.Paste")
			(roundrect_rratio 0.25)
			(net 553 "+0V85")
			(pintype "passive")
		)
	)
	(footprint "antmicro-footprints:C_0402_1005Metric"
		(layer "B.Cu")
		(at 206.18 140.6045 180)
		(descr "Capacitor SMD 0402")
		(tags "capacitor SMD 0402")
		(property "Reference" "C328"
			(at -2.32 0.0045 0)
			(layer "B.SilkS")
			(effects
				(font
					(size 0.7 0.7)
					(thickness 0.15)
				)
				(justify mirror)
			)
		)
		(property "Value" "C_100n_0402"
			(at -1.022927 -2.155213 0)
			(layer "B.Fab")
			(effects
				(font
					(size 0.7 0.7)
					(thickness 0.15)
				)
				(justify left bottom mirror)
			)
		)
		(property "Datasheet" "https://www.murata.com/products/productdetail?partno=GRM155R61H104KE14%23"
			(at 0 0 0)
			(layer "B.Fab")
			(hide yes)
			(effects
				(font
					(size 1.27 1.27)
					(thickness 0.15)
				)
				(justify mirror)
			)
		)
		(property "Manufacturer" "Murata"
			(at 0 0 0)
			(unlocked yes)
			(layer "B.Fab")
			(hide yes)
			(effects
				(font
					(size 1 1)
					(thickness 0.15)
				)
				(justify mirror)
			)
		)
		(property "MPN" "GRM155R61H104KE14D"
			(at 0 0 0)
			(unlocked yes)
			(layer "B.Fab")
			(hide yes)
			(effects
				(font
					(size 1 1)
					(thickness 0.15)
				)
				(justify mirror)
			)
		)
		(property "Val" "100n"
			(at 0 0 0)
			(unlocked yes)
			(layer "B.Fab")
			(hide yes)
			(effects
				(font
					(size 1 1)
					(thickness 0.15)
				)
				(justify mirror)
			)
		)
		(property "License" "Apache-2.0"
			(at 0 0 0)
			(unlocked yes)
			(layer "B.Fab")
			(hide yes)
			(effects
				(font
					(size 1 1)
					(thickness 0.15)
				)
				(justify mirror)
			)
		)
		(property "Author" "Antmicro"
			(at 0 0 0)
			(unlocked yes)
			(layer "B.Fab")
			(hide yes)
			(effects
				(font
					(size 1 1)
					(thickness 0.15)
				)
				(justify mirror)
			)
		)
		(property "Voltage" "50V"
			(at 0 0 0)
			(unlocked yes)
			(layer "B.Fab")
			(hide yes)
			(effects
				(font
					(size 1 1)
					(thickness 0.15)
				)
				(justify mirror)
			)
		)
		(property "Dielectric" "X5R"
			(at 0 0 0)
			(unlocked yes)
			(layer "B.Fab")
			(hide yes)
			(effects
				(font
					(size 1 1)
					(thickness 0.15)
				)
				(justify mirror)
			)
		)
		(sheetname "/Supply/")
		(sheetfile "supply.kicad_sch")
		(attr smd)
		(fp_rect
			(start -0.925 0.47)
			(end 0.925 -0.47)
			(stroke
				(width 0.05)
				(type default)
			)
			(fill no)
			(layer "B.CrtYd")
		)
		(fp_line
			(start 0.504 0.25)
			(end 0.504 -0.248)
			(stroke
				(width 0.15)
				(type solid)
			)
			(layer "B.Fab")
		)
		(fp_line
			(start 0.504 -0.248)
			(end -0.494 -0.248)
			(stroke
				(width 0.15)
				(type solid)
			)
			(layer "B.Fab")
		)
		(fp_line
			(start -0.494 0.25)
			(end 0.504 0.25)
			(stroke
				(width 0.15)
				(type solid)
			)
			(layer "B.Fab")
		)
		(fp_line
			(start -0.494 -0.248)
			(end -0.494 0.25)
			(stroke
				(width 0.15)
				(type solid)
			)
			(layer "B.Fab")
		)
		(fp_text user "${REFERENCE}"
			(at -0.939 -4.599 0)
			(layer "B.Fab")
			(effects
				(font
					(size 0.7 0.7)
					(thickness 0.15)
				)
				(justify left bottom mirror)
			)
		)
		(fp_text user "Author: Antmicro"
			(at -0.939 -3.399 0)
			(layer "B.Fab")
			(effects
				(font
					(size 0.7 0.7)
					(thickness 0.15)
				)
				(justify left bottom mirror)
			)
		)
		(fp_text user "License: Apache-2.0"
			(at -0.939 -5.799 0)
			(layer "B.Fab")
			(effects
				(font
					(size 0.7 0.7)
					(thickness 0.15)
				)
				(justify left bottom mirror)
			)
		)
		(pad "1" smd roundrect
			(at -0.48 0 180)
			(size 0.59 0.64)
			(layers "B.Cu" "B.Mask" "B.Paste")
			(roundrect_rratio 0.25)
			(net 1 "GND")
			(pintype "passive")
		)
		(pad "2" smd roundrect
			(at 0.48 0 180)
			(size 0.59 0.64)
			(layers "B.Cu" "B.Mask" "B.Paste")
			(roundrect_rratio 0.25)
			(net 151 "+3V3")
			(pintype "passive")
		)
	)
	(footprint "antmicro-footprints:R_0402_1005Metric"
		(layer "B.Cu")
		(at 112.33 164.14 -90)
		(descr "Resistor SMD 0402")
		(tags "resistor SMD 0402")
		(property "Reference" "R85"
			(at -1.122484 0.772697 90)
			(layer "B.SilkS")
			(effects
				(font
					(size 0.7 0.7)
					(thickness 0.15)
				)
				(justify left bottom mirror)
			)
		)
		(property "Value" "R_10k_0402"
			(at -1.011843 -1.772047 90)
			(layer "B.Fab")
			(effects
				(font
					(size 0.7 0.7)
					(thickness 0.15)
				)
				(justify left bottom mirror)
			)
		)
		(property "Datasheet" "https://www.bourns.com/docs/product-datasheets/cr.pdf"
			(at 0 0 270)
			(layer "F.Fab")
			(hide yes)
			(effects
				(font
					(size 1.27 1.27)
					(thickness 0.15)
				)
			)
		)
		(property "MPN" "CR0402-FX-1002GLF"
			(at 0 0 270)
			(unlocked yes)
			(layer "B.Fab")
			(hide yes)
			(effects
				(font
					(size 1 1)
					(thickness 0.15)
				)
				(justify mirror)
			)
		)
		(property "Manufacturer" "Bourns"
			(at 0 0 270)
			(unlocked yes)
			(layer "B.Fab")
			(hide yes)
			(effects
				(font
					(size 1 1)
					(thickness 0.15)
				)
				(justify mirror)
			)
		)
		(property "License" "Apache-2.0"
			(at 0 0 270)
			(unlocked yes)
			(layer "B.Fab")
			(hide yes)
			(effects
				(font
					(size 1 1)
					(thickness 0.15)
				)
				(justify mirror)
			)
		)
		(property "Author" "Antmicro"
			(at 0 0 270)
			(unlocked yes)
			(layer "B.Fab")
			(hide yes)
			(effects
				(font
					(size 1 1)
					(thickness 0.15)
				)
				(justify mirror)
			)
		)
		(property "Val" "10k"
			(at 0 0 270)
			(unlocked yes)
			(layer "B.Fab")
			(hide yes)
			(effects
				(font
					(size 1 1)
					(thickness 0.15)
				)
				(justify mirror)
			)
		)
		(property "Tolerance" "1%"
			(at 0 0 270)
			(unlocked yes)
			(layer "B.Fab")
			(hide yes)
			(effects
				(font
					(size 1 1)
					(thickness 0.15)
				)
				(justify mirror)
			)
		)
		(sheetname "/HDMI + SD Card/")
		(sheetfile "hdmi-sd-card.kicad_sch")
		(attr smd)
		(fp_rect
			(start -0.925 0.47)
			(end 0.925 -0.47)
			(stroke
				(width 0.05)
				(type default)
			)
			(fill no)
			(layer "B.CrtYd")
		)
		(fp_rect
			(start -0.5 0.25)
			(end 0.5 -0.25)
			(stroke
				(width 0.15)
				(type solid)
			)
			(fill no)
			(layer "B.Fab")
		)
		(fp_text user "License: Apache-2.0"
			(at -0.95 -5.169 90)
			(layer "B.Fab")
			(effects
				(font
					(size 0.7 0.7)
					(thickness 0.15)
				)
				(justify left bottom mirror)
			)
		)
		(fp_text user "${REFERENCE}"
			(at -0.95 -3.168 90)
			(layer "B.Fab")
			(effects
				(font
					(size 0.7 0.7)
					(thickness 0.15)
				)
				(justify left bottom mirror)
			)
		)
		(fp_text user "Author: Antmicro"
			(at -0.95 -4.169 90)
			(layer "B.Fab")
			(effects
				(font
					(size 0.7 0.7)
					(thickness 0.15)
				)
				(justify left bottom mirror)
			)
		)
		(pad "1" smd roundrect
			(at -0.48 0 270)
			(size 0.59 0.64)
			(layers "B.Cu" "B.Mask" "B.Paste")
			(roundrect_rratio 0.25)
			(net 1 "GND")
			(pintype "passive")
		)
		(pad "2" smd roundrect
			(at 0.48 0 270)
			(size 0.59 0.64)
			(layers "B.Cu" "B.Mask" "B.Paste")
			(roundrect_rratio 0.25)
			(net 297 "/HDMI + SD Card/HDMI_IN_5V")
			(pintype "passive")
		)
	)
	(footprint "antmicro-footprints:C_0402_1005Metric"
		(layer "B.Cu")
		(at 174.48 150.689999 -90)
		(descr "Capacitor SMD 0402")
		(tags "capacitor SMD 0402")
		(property "Reference" "C315"
			(at 1.010001 -0.37 90)
			(layer "B.SilkS")
			(effects
				(font
					(size 0.7 0.7)
					(thickness 0.15)
				)
				(justify left bottom mirror)
			)
		)
		(property "Value" "C_100n_0402"
			(at -1.022927 -2.155213 90)
			(layer "B.Fab")
			(effects
				(font
					(size 0.7 0.7)
					(thickness 0.15)
				)
				(justify left bottom mirror)
			)
		)
		(property "Datasheet" "https://www.murata.com/products/productdetail?partno=GRM155R61H104KE14%23"
			(at 0 0 270)
			(layer "F.Fab")
			(hide yes)
			(effects
				(font
					(size 1.27 1.27)
					(thickness 0.15)
				)
			)
		)
		(property "MPN" "GRM155R61H104KE14D"
			(at 0 0 270)
			(unlocked yes)
			(layer "B.Fab")
			(hide yes)
			(effects
				(font
					(size 1 1)
					(thickness 0.15)
				)
				(justify mirror)
			)
		)
		(property "Manufacturer" "Murata"
			(at 0 0 270)
			(unlocked yes)
			(layer "B.Fab")
			(hide yes)
			(effects
				(font
					(size 1 1)
					(thickness 0.15)
				)
				(justify mirror)
			)
		)
		(property "License" "Apache-2.0"
			(at 0 0 270)
			(unlocked yes)
			(layer "B.Fab")
			(hide yes)
			(effects
				(font
					(size 1 1)
					(thickness 0.15)
				)
				(justify mirror)
			)
		)
		(property "Author" "Antmicro"
			(at 0 0 270)
			(unlocked yes)
			(layer "B.Fab")
			(hide yes)
			(effects
				(font
					(size 1 1)
					(thickness 0.15)
				)
				(justify mirror)
			)
		)
		(property "Val" "100n"
			(at 0 0 270)
			(unlocked yes)
			(layer "B.Fab")
			(hide yes)
			(effects
				(font
					(size 1 1)
					(thickness 0.15)
				)
				(justify mirror)
			)
		)
		(property "Voltage" "50V"
			(at 0 0 270)
			(unlocked yes)
			(layer "B.Fab")
			(hide yes)
			(effects
				(font
					(size 1 1)
					(thickness 0.15)
				)
				(justify mirror)
			)
		)
		(property "Dielectric" "X5R"
			(at 0 0 270)
			(unlocked yes)
			(layer "B.Fab")
			(hide yes)
			(effects
				(font
					(size 1 1)
					(thickness 0.15)
				)
				(justify mirror)
			)
		)
		(sheetname "/FPGA MGT Interface/")
		(sheetfile "fpga-mgt.kicad_sch")
		(attr smd)
		(fp_rect
			(start -0.925 0.47)
			(end 0.925 -0.47)
			(stroke
				(width 0.05)
				(type default)
			)
			(fill no)
			(layer "B.CrtYd")
		)
		(fp_line
			(start -0.494 0.25)
			(end 0.504 0.25)
			(stroke
				(width 0.15)
				(type solid)
			)
			(layer "B.Fab")
		)
		(fp_line
			(start 0.504 0.25)
			(end 0.504 -0.248)
			(stroke
				(width 0.15)
				(type solid)
			)
			(layer "B.Fab")
		)
		(fp_line
			(start -0.494 -0.248)
			(end -0.494 0.25)
			(stroke
				(width 0.15)
				(type solid)
			)
			(layer "B.Fab")
		)
		(fp_line
			(start 0.504 -0.248)
			(end -0.494 -0.248)
			(stroke
				(width 0.15)
				(type solid)
			)
			(layer "B.Fab")
		)
		(fp_text user "Author: Antmicro"
			(at -0.939 -3.399 90)
			(layer "B.Fab")
			(effects
				(font
					(size 0.7 0.7)
					(thickness 0.15)
				)
				(justify left bottom mirror)
			)
		)
		(fp_text user "License: Apache-2.0"
			(at -0.939 -5.799 90)
			(layer "B.Fab")
			(effects
				(font
					(size 0.7 0.7)
					(thickness 0.15)
				)
				(justify left bottom mirror)
			)
		)
		(fp_text user "${REFERENCE}"
			(at -0.939 -4.599 90)
			(layer "B.Fab")
			(effects
				(font
					(size 0.7 0.7)
					(thickness 0.15)
				)
				(justify left bottom mirror)
			)
		)
		(pad "1" smd roundrect
			(at -0.48 0 270)
			(size 0.59 0.64)
			(layers "B.Cu" "B.Mask" "B.Paste")
			(roundrect_rratio 0.25)
			(net 403 "HDMI_REC_CLK_P")
			(pintype "passive")
		)
		(pad "2" smd roundrect
			(at 0.48 0 270)
			(size 0.59 0.64)
			(layers "B.Cu" "B.Mask" "B.Paste")
			(roundrect_rratio 0.25)
			(net 488 "/FPGA MGT Interface/HDMI_REC_CLK_C_P")
			(pintype "passive")
		)
	)
	(footprint "antmicro-footprints:C_0402_1005Metric"
		(layer "B.Cu")
		(at 115.55 159.75 90)
		(descr "Capacitor SMD 0402")
		(tags "capacitor SMD 0402")
		(property "Reference" "C129"
			(at 0.949 0.375501 90)
			(layer "B.SilkS")
			(effects
				(font
					(size 0.7 0.7)
					(thickness 0.15)
				)
				(justify right bottom mirror)
			)
		)
		(property "Value" "C_1u_0402"
			(at -1.022927 -2.155213 90)
			(layer "B.Fab")
			(effects
				(font
					(size 0.7 0.7)
					(thickness 0.15)
				)
				(justify right bottom mirror)
			)
		)
		(property "Datasheet" "https://product.tdk.com/en/search/capacitor/ceramic/mlcc/info?part_no=C1005X6S1A105K050BC"
			(at 0 0 90)
			(layer "F.Fab")
			(hide yes)
			(effects
				(font
					(size 1.27 1.27)
					(thickness 0.15)
				)
			)
		)
		(property "Manufacturer" "TDK"
			(at 0 0 90)
			(unlocked yes)
			(layer "B.Fab")
			(hide yes)
			(effects
				(font
					(size 1 1)
					(thickness 0.15)
				)
				(justify mirror)
			)
		)
		(property "MPN" "C1005X6S1A105K050BC"
			(at 0 0 90)
			(unlocked yes)
			(layer "B.Fab")
			(hide yes)
			(effects
				(font
					(size 1 1)
					(thickness 0.15)
				)
				(justify mirror)
			)
		)
		(property "Val" "1u"
			(at 0 0 90)
			(unlocked yes)
			(layer "B.Fab")
			(hide yes)
			(effects
				(font
					(size 1 1)
					(thickness 0.15)
				)
				(justify mirror)
			)
		)
		(property "License" "Apache-2.0"
			(at 0 0 90)
			(unlocked yes)
			(layer "B.Fab")
			(hide yes)
			(effects
				(font
					(size 1 1)
					(thickness 0.15)
				)
				(justify mirror)
			)
		)
		(property "Author" "Antmicro"
			(at 0 0 90)
			(unlocked yes)
			(layer "B.Fab")
			(hide yes)
			(effects
				(font
					(size 1 1)
					(thickness 0.15)
				)
				(justify mirror)
			)
		)
		(property "Voltage" ""
			(at 0 0 90)
			(unlocked yes)
			(layer "B.Fab")
			(hide yes)
			(effects
				(font
					(size 1 1)
					(thickness 0.15)
				)
				(justify mirror)
			)
		)
		(property "Dielectric" ""
			(at 0 0 90)
			(unlocked yes)
			(layer "B.Fab")
			(hide yes)
			(effects
				(font
					(size 1 1)
					(thickness 0.15)
				)
				(justify mirror)
			)
		)
		(sheetname "/HDMI + SD Card/")
		(sheetfile "hdmi-sd-card.kicad_sch")
		(attr smd)
		(fp_rect
			(start -0.925 0.47)
			(end 0.925 -0.47)
			(stroke
				(width 0.05)
				(type default)
			)
			(fill no)
			(layer "B.CrtYd")
		)
		(fp_line
			(start 0.504 -0.248)
			(end -0.494 -0.248)
			(stroke
				(width 0.15)
				(type solid)
			)
			(layer "B.Fab")
		)
		(fp_line
			(start -0.494 -0.248)
			(end -0.494 0.25)
			(stroke
				(width 0.15)
				(type solid)
			)
			(layer "B.Fab")
		)
		(fp_line
			(start 0.504 0.25)
			(end 0.504 -0.248)
			(stroke
				(width 0.15)
				(type solid)
			)
			(layer "B.Fab")
		)
		(fp_line
			(start -0.494 0.25)
			(end 0.504 0.25)
			(stroke
				(width 0.15)
				(type solid)
			)
			(layer "B.Fab")
		)
		(fp_text user "License: Apache-2.0"
			(at -0.939 -5.799 270)
			(layer "B.Fab")
			(effects
				(font
					(size 0.7 0.7)
					(thickness 0.15)
				)
				(justify left bottom mirror)
			)
		)
		(fp_text user "${REFERENCE}"
			(at -0.939 -4.599 270)
			(layer "B.Fab")
			(effects
				(font
					(size 0.7 0.7)
					(thickness 0.15)
				)
				(justify left bottom mirror)
			)
		)
		(fp_text user "Author: Antmicro"
			(at -0.939 -3.399 270)
			(layer "B.Fab")
			(effects
				(font
					(size 0.7 0.7)
					(thickness 0.15)
				)
				(justify left bottom mirror)
			)
		)
		(pad "1" smd roundrect
			(at -0.48 0 90)
			(size 0.59 0.64)
			(layers "B.Cu" "B.Mask" "B.Paste")
			(roundrect_rratio 0.25)
			(net 151 "+3V3")
			(pintype "passive")
		)
		(pad "2" smd roundrect
			(at 0.48 0 90)
			(size 0.59 0.64)
			(layers "B.Cu" "B.Mask" "B.Paste")
			(roundrect_rratio 0.25)
			(net 1 "GND")
			(pintype "passive")
		)
	)
	(footprint "antmicro-footprints:R_0402_1005Metric"
		(layer "B.Cu")
		(at 254.324499 150.399 180)
		(descr "Resistor SMD 0402")
		(tags "resistor SMD 0402")
		(property "Reference" "R158"
			(at -3.8 -0.3 0)
			(layer "B.SilkS")
			(effects
				(font
					(size 0.7 0.7)
					(thickness 0.15)
				)
				(justify left bottom mirror)
			)
		)
		(property "Value" "R_0R_0402"
			(at -1.011843 -1.772047 0)
			(layer "B.Fab")
			(effects
				(font
					(size 0.7 0.7)
					(thickness 0.15)
				)
				(justify left bottom mirror)
			)
		)
		(property "Datasheet" "https://industrial.panasonic.com/cdbs/www-data/pdf/RDA0000/AOA0000C301.pdf"
			(at 0 0 180)
			(layer "F.Fab")
			(hide yes)
			(effects
				(font
					(size 1.27 1.27)
					(thickness 0.15)
				)
			)
		)
		(property "Manufacturer" "Panasonic"
			(at 0 0 180)
			(unlocked yes)
			(layer "B.Fab")
			(hide yes)
			(effects
				(font
					(size 1 1)
					(thickness 0.15)
				)
				(justify mirror)
			)
		)
		(property "MPN" "ERJ2GE0R00X"
			(at 0 0 180)
			(unlocked yes)
			(layer "B.Fab")
			(hide yes)
			(effects
				(font
					(size 1 1)
					(thickness 0.15)
				)
				(justify mirror)
			)
		)
		(property "Val" "0R"
			(at 0 0 180)
			(unlocked yes)
			(layer "B.Fab")
			(hide yes)
			(effects
				(font
					(size 1 1)
					(thickness 0.15)
				)
				(justify mirror)
			)
		)
		(property "License" "Apache-2.0"
			(at 0 0 180)
			(unlocked yes)
			(layer "B.Fab")
			(hide yes)
			(effects
				(font
					(size 1 1)
					(thickness 0.15)
				)
				(justify mirror)
			)
		)
		(property "Author" "Antmicro"
			(at 0 0 180)
			(unlocked yes)
			(layer "B.Fab")
			(hide yes)
			(effects
				(font
					(size 1 1)
					(thickness 0.15)
				)
				(justify mirror)
			)
		)
		(property "Tolerance" "~"
			(at 0 0 180)
			(unlocked yes)
			(layer "B.Fab")
			(hide yes)
			(effects
				(font
					(size 1 1)
					(thickness 0.15)
				)
				(justify mirror)
			)
		)
		(property "Current" "1A"
			(at 0 0 180)
			(unlocked yes)
			(layer "B.Fab")
			(hide yes)
			(effects
				(font
					(size 1 1)
					(thickness 0.15)
				)
				(justify mirror)
			)
		)
		(sheetname "/Supply/DC-DC IO/")
		(sheetfile "dc-dc-io.kicad_sch")
		(attr smd exclude_from_bom dnp)
		(fp_rect
			(start -0.925 0.47)
			(end 0.925 -0.47)
			(stroke
				(width 0.05)
				(type default)
			)
			(fill no)
			(layer "B.CrtYd")
		)
		(fp_rect
			(start -0.5 0.25)
			(end 0.5 -0.25)
			(stroke
				(width 0.15)
				(type solid)
			)
			(fill no)
			(layer "B.Fab")
		)
		(fp_text user "License: Apache-2.0"
			(at -0.95 -5.169 0)
			(layer "B.Fab")
			(effects
				(font
					(size 0.7 0.7)
					(thickness 0.15)
				)
				(justify left bottom mirror)
			)
		)
		(fp_text user "${REFERENCE}"
			(at -0.95 -3.168 0)
			(layer "B.Fab")
			(effects
				(font
					(size 0.7 0.7)
					(thickness 0.15)
				)
				(justify left bottom mirror)
			)
		)
		(fp_text user "Author: Antmicro"
			(at -0.95 -4.169 0)
			(layer "B.Fab")
			(effects
				(font
					(size 0.7 0.7)
					(thickness 0.15)
				)
				(justify left bottom mirror)
			)
		)
		(pad "1" smd roundrect
			(at -0.48 0 180)
			(size 0.59 0.64)
			(layers "B.Cu" "B.Mask" "B.Paste")
			(roundrect_rratio 0.25)
			(net 1 "GND")
			(pintype "passive")
		)
		(pad "2" smd roundrect
			(at 0.48 0 180)
			(size 0.59 0.64)
			(layers "B.Cu" "B.Mask" "B.Paste")
			(roundrect_rratio 0.25)
			(net 715 "/Supply/DC-DC IO/FB6")
			(pintype "passive")
		)
	)
	(footprint "antmicro-footprints:C_0603_1608Metric"
		(layer "B.Cu")
		(at 186.575 152.525 180)
		(descr "Capacitor SMD 0603")
		(tags "capacitor 0603")
		(property "Reference" "C85"
			(at 29.95 10.3 0)
			(layer "B.SilkS")
			(effects
				(font
					(size 0.7 0.7)
					(thickness 0.15)
				)
				(justify left bottom mirror)
			)
		)
		(property "Value" "C_47u_0603"
			(at -1.42757 -1.770288 0)
			(layer "B.Fab")
			(effects
				(font
					(size 0.7 0.7)
					(thickness 0.15)
				)
				(justify left bottom mirror)
			)
		)
		(property "Datasheet" "https://www.murata.com/products/productdetail?partno=GRM188R60J476ME15%23"
			(at 0 0 180)
			(layer "F.Fab")
			(hide yes)
			(effects
				(font
					(size 1.27 1.27)
					(thickness 0.15)
				)
			)
		)
		(property "Manufacturer" "Murata"
			(at 0 0 180)
			(unlocked yes)
			(layer "B.Fab")
			(hide yes)
			(effects
				(font
					(size 1 1)
					(thickness 0.15)
				)
				(justify mirror)
			)
		)
		(property "MPN" "GRM188R60J476ME15D"
			(at 0 0 180)
			(unlocked yes)
			(layer "B.Fab")
			(hide yes)
			(effects
				(font
					(size 1 1)
					(thickness 0.15)
				)
				(justify mirror)
			)
		)
		(property "Val" "47u"
			(at 0 0 180)
			(unlocked yes)
			(layer "B.Fab")
			(hide yes)
			(effects
				(font
					(size 1 1)
					(thickness 0.15)
				)
				(justify mirror)
			)
		)
		(property "License" "Apache-2.0"
			(at 0 0 180)
			(unlocked yes)
			(layer "B.Fab")
			(hide yes)
			(effects
				(font
					(size 1 1)
					(thickness 0.15)
				)
				(justify mirror)
			)
		)
		(property "Author" "Antmicro"
			(at 0 0 180)
			(unlocked yes)
			(layer "B.Fab")
			(hide yes)
			(effects
				(font
					(size 1 1)
					(thickness 0.15)
				)
				(justify mirror)
			)
		)
		(property "Voltage" ""
			(at 0 0 180)
			(unlocked yes)
			(layer "B.Fab")
			(hide yes)
			(effects
				(font
					(size 1 1)
					(thickness 0.15)
				)
				(justify mirror)
			)
		)
		(property "Dielectric" ""
			(at 0 0 180)
			(unlocked yes)
			(layer "B.Fab")
			(hide yes)
			(effects
				(font
					(size 1 1)
					(thickness 0.15)
				)
				(justify mirror)
			)
		)
		(sheetname "/FPGA power/")
		(sheetfile "fpga-power.kicad_sch")
		(attr smd)
		(fp_line
			(start -0.15 0.4)
			(end 0.15 0.4)
			(stroke
				(width 0.15)
				(type solid)
			)
			(layer "B.SilkS")
		)
		(fp_line
			(start -0.15 -0.4)
			(end 0.15 -0.4)
			(stroke
				(width 0.15)
				(type solid)
			)
			(layer "B.SilkS")
		)
		(fp_rect
			(start -1.25 0.65)
			(end 1.25 -0.65)
			(stroke
				(width 0.05)
				(type solid)
			)
			(fill no)
			(layer "B.CrtYd")
		)
		(fp_rect
			(start -0.8 0.4)
			(end 0.8 -0.4)
			(stroke
				(width 0.15)
				(type solid)
			)
			(fill no)
			(layer "B.Fab")
		)
		(fp_text user "License: Apache-2.0"
			(at -1.682 -5.895 0)
			(layer "B.Fab")
			(effects
				(font
					(size 0.7 0.7)
					(thickness 0.15)
				)
				(justify left bottom mirror)
			)
		)
		(fp_text user "${REFERENCE}"
			(at -1.682 -3.895 0)
			(layer "B.Fab")
			(effects
				(font
					(size 0.7 0.7)
					(thickness 0.15)
				)
				(justify left bottom mirror)
			)
		)
		(fp_text user "Author: Antmicro"
			(at -1.682 -4.894 0)
			(layer "B.Fab")
			(effects
				(font
					(size 0.7 0.7)
					(thickness 0.15)
				)
				(justify left bottom mirror)
			)
		)
		(pad "1" smd roundrect
			(at -0.7 0 180)
			(size 0.8 1)
			(layers "B.Cu" "B.Mask" "B.Paste")
			(roundrect_rratio 0.2)
			(net 797 "+1V8")
			(pintype "passive")
		)
		(pad "2" smd roundrect
			(at 0.7 0 180)
			(size 0.8 1)
			(layers "B.Cu" "B.Mask" "B.Paste")
			(roundrect_rratio 0.2)
			(net 1 "GND")
			(pintype "passive")
		)
	)
	(footprint "antmicro-footprints:C_0402_1005Metric_EIA"
		(layer "B.Cu")
		(at 195 148.5 -90)
		(descr "Capacitor SMD 0402 (1005 Metric), square (rectangular) end terminal, IPC_7351 nominal, (Body size source: IPC-SM-782 page 76, https://www.pcb-3d.com/wordpress/wp-content/uploads/ipc-sm-782a_amendment_1_and_2.pdf)")
		(tags "capacitor 0402")
		(property "Reference" "C333"
			(at -12.4 30.6 90)
			(layer "B.SilkS")
			(effects
				(font
					(size 0.7 0.7)
					(thickness 0.15)
				)
				(justify left bottom mirror)
			)
		)
		(property "Value" "C_100n_0402"
			(at 0 -1.169 90)
			(layer "B.Fab")
			(effects
				(font
					(size 0.7 0.7)
					(thickness 0.15)
				)
				(justify left bottom mirror)
			)
		)
		(property "Manufacturer" "Murata"
			(at 0 0 270)
			(unlocked yes)
			(layer "B.Fab")
			(hide yes)
			(effects
				(font
					(size 1 1)
					(thickness 0.15)
				)
				(justify mirror)
			)
		)
		(property "MPN" "GRM155R61H104KE14D"
			(at 0 0 270)
			(unlocked yes)
			(layer "B.Fab")
			(hide yes)
			(effects
				(font
					(size 1 1)
					(thickness 0.15)
				)
				(justify mirror)
			)
		)
		(property "Val" "100n"
			(at 0 0 270)
			(unlocked yes)
			(layer "B.Fab")
			(hide yes)
			(effects
				(font
					(size 1 1)
					(thickness 0.15)
				)
				(justify mirror)
			)
		)
		(property "License" "Apache-2.0"
			(at 0 0 270)
			(unlocked yes)
			(layer "B.Fab")
			(hide yes)
			(effects
				(font
					(size 1 1)
					(thickness 0.15)
				)
				(justify mirror)
			)
		)
		(property "Author" "Antmicro"
			(at 0 0 270)
			(unlocked yes)
			(layer "B.Fab")
			(hide yes)
			(effects
				(font
					(size 1 1)
					(thickness 0.15)
				)
				(justify mirror)
			)
		)
		(property "Voltage" "50V"
			(at 0 0 270)
			(unlocked yes)
			(layer "B.Fab")
			(hide yes)
			(effects
				(font
					(size 1 1)
					(thickness 0.15)
				)
				(justify mirror)
			)
		)
		(property "Dielectric" "X5R"
			(at 0 0 270)
			(unlocked yes)
			(layer "B.Fab")
			(hide yes)
			(effects
				(font
					(size 1 1)
					(thickness 0.15)
				)
				(justify mirror)
			)
		)
		(sheetname "/FPGA banks HP/")
		(sheetfile "fpga-hp-banks.kicad_sch")
		(attr smd)
		(fp_rect
			(start -0.95 0.45)
			(end 0.95 -0.45)
			(stroke
				(width 0.05)
				(type default)
			)
			(fill no)
			(layer "B.CrtYd")
		)
		(fp_line
			(start -0.5 0.25)
			(end 0.498 0.25)
			(stroke
				(width 0.15)
				(type solid)
			)
			(layer "B.Fab")
		)
		(fp_line
			(start 0.498 0.25)
			(end 0.498 -0.248)
			(stroke
				(width 0.15)
				(type solid)
			)
			(layer "B.Fab")
		)
		(fp_line
			(start -0.5 -0.248)
			(end -0.5 0.25)
			(stroke
				(width 0.15)
				(type solid)
			)
			(layer "B.Fab")
		)
		(fp_line
			(start 0.498 -0.248)
			(end -0.5 -0.248)
			(stroke
				(width 0.15)
				(type solid)
			)
			(layer "B.Fab")
		)
		(fp_text user "Author: Antmicro"
			(at -0.9656 -5.569 90)
			(layer "B.Fab")
			(effects
				(font
					(size 0.7 0.7)
					(thickness 0.15)
				)
				(justify left bottom mirror)
			)
		)
		(fp_text user "${REFERENCE}"
			(at -0.9656 -3.169 90)
			(layer "B.Fab")
			(effects
				(font
					(size 0.7 0.7)
					(thickness 0.15)
				)
				(justify left bottom mirror)
			)
		)
		(fp_text user "License: Apache-2.0"
			(at -0.9656 -4.369 90)
			(layer "B.Fab")
			(effects
				(font
					(size 0.7 0.7)
					(thickness 0.15)
				)
				(justify left bottom mirror)
			)
		)
		(pad "1" smd roundrect
			(at -0.5 0 180)
			(size 0.6 0.6)
			(layers "B.Cu" "B.Mask" "B.Paste")
			(roundrect_rratio 0.25)
			(net 535 "/FPGA banks HP/VREF_64")
			(pintype "passive")
		)
		(pad "2" smd roundrect
			(at 0.498 0 270)
			(size 0.6 0.6)
			(layers "B.Cu" "B.Mask" "B.Paste")
			(roundrect_rratio 0.25)
			(net 1 "GND")
			(pintype "passive")
		)
	)
	(footprint "antmicro-footprints:I-PEX_CABLINE-VS_1x20_20455-A20E-76"
		(layer "B.Cu")
		(at 103.367 160.619 90)
		(property "Reference" "J11"
			(at -9.511 0.433 0)
			(layer "B.SilkS")
			(effects
				(font
					(size 0.7 0.7)
					(thickness 0.15)
				)
				(justify right bottom mirror)
			)
		)
		(property "Value" "I-PEX_CABLINE-VS_1x20_20455-A20E-76"
			(at 0 -3.5 90)
			(layer "B.Fab")
			(effects
				(font
					(size 0.7 0.7)
					(thickness 0.15)
				)
				(justify right bottom mirror)
			)
		)
		(property "Datasheet" "https://www.i-pex.com/sites/default/files/downloads/pdf/MANUAL_CABLINE-VS_HIM-08004-07EN.pdf"
			(at 0 0 90)
			(layer "F.Fab")
			(hide yes)
			(effects
				(font
					(size 1.27 1.27)
					(thickness 0.15)
				)
			)
		)
		(property "MPN" "20455-A20E-76"
			(at 0 0 90)
			(unlocked yes)
			(layer "B.Fab")
			(hide yes)
			(effects
				(font
					(size 1 1)
					(thickness 0.15)
				)
				(justify mirror)
			)
		)
		(property "Manufacturer" "I-PEX"
			(at 0 0 90)
			(unlocked yes)
			(layer "B.Fab")
			(hide yes)
			(effects
				(font
					(size 1 1)
					(thickness 0.15)
				)
				(justify mirror)
			)
		)
		(property "Author" "Antmicro"
			(at 0 0 90)
			(unlocked yes)
			(layer "B.Fab")
			(hide yes)
			(effects
				(font
					(size 1 1)
					(thickness 0.15)
				)
				(justify mirror)
			)
		)
		(property "License" "Apache-2.0"
			(at 0 0 90)
			(unlocked yes)
			(layer "B.Fab")
			(hide yes)
			(effects
				(font
					(size 1 1)
					(thickness 0.15)
				)
				(justify mirror)
			)
		)
		(sheetname "/HDMI + SD Card/")
		(sheetfile "hdmi-sd-card.kicad_sch")
		(attr smd)
		(fp_line
			(start 8.7 -2.2)
			(end 8.7 0.103)
			(stroke
				(width 0.15)
				(type solid)
			)
			(layer "B.SilkS")
		)
		(fp_line
			(start -8.702 -2.2)
			(end 8.7 -2.2)
			(stroke
				(width 0.15)
				(type solid)
			)
			(layer "B.SilkS")
		)
		(fp_line
			(start 8.7 0.103)
			(end 8.3 0.103)
			(stroke
				(width 0.15)
				(type solid)
			)
			(layer "B.SilkS")
		)
		(fp_line
			(start 8.3 0.103)
			(end 8.3 2.4)
			(stroke
				(width 0.15)
				(type solid)
			)
			(layer "B.SilkS")
		)
		(fp_line
			(start -8.301 0.103)
			(end -8.702 0.103)
			(stroke
				(width 0.15)
				(type solid)
			)
			(layer "B.SilkS")
		)
		(fp_line
			(start -8.702 0.103)
			(end -8.702 -2.2)
			(stroke
				(width 0.15)
				(type solid)
			)
			(layer "B.SilkS")
		)
		(fp_line
			(start 8.3 2.4)
			(end -8.301 2.4)
			(stroke
				(width 0.15)
				(type solid)
			)
			(layer "B.SilkS")
		)
		(fp_line
			(start -8.301 2.4)
			(end -8.301 0.103)
			(stroke
				(width 0.15)
				(type solid)
			)
			(layer "B.SilkS")
		)
		(fp_circle
			(center -5.1 1.8)
			(end -5.052 1.8)
			(stroke
				(width 0.15)
				(type solid)
			)
			(fill yes)
			(layer "B.SilkS")
		)
		(fp_rect
			(start -9.1 2.7)
			(end 9 -2.5)
			(stroke
				(width 0.05)
				(type solid)
			)
			(fill no)
			(layer "B.CrtYd")
		)
		(fp_line
			(start 8.7 -2.2)
			(end 8.7 0.101)
			(stroke
				(width 0.15)
				(type solid)
			)
			(layer "B.Fab")
		)
		(fp_line
			(start -8.701 -2.2)
			(end 8.7 -2.2)
			(stroke
				(width 0.15)
				(type solid)
			)
			(layer "B.Fab")
		)
		(fp_line
			(start 8.7 0.101)
			(end 8.3 0.101)
			(stroke
				(width 0.15)
				(type solid)
			)
			(layer "B.Fab")
		)
		(fp_line
			(start 8.3 0.101)
			(end 8.3 2.4)
			(stroke
				(width 0.15)
				(type solid)
			)
			(layer "B.Fab")
		)
		(fp_line
			(start -8.301 0.101)
			(end -8.701 0.101)
			(stroke
				(width 0.15)
				(type solid)
			)
			(layer "B.Fab")
		)
		(fp_line
			(start -8.701 0.101)
			(end -8.701 -2.2)
			(stroke
				(width 0.15)
				(type solid)
			)
			(layer "B.Fab")
		)
		(fp_line
			(start -8.3 1.8)
			(end -8.301 0.101)
			(stroke
				(width 0.15)
				(type solid)
			)
			(layer "B.Fab")
		)
		(fp_line
			(start 8.3 2.4)
			(end -7.7 2.4)
			(stroke
				(width 0.15)
				(type solid)
			)
			(layer "B.Fab")
		)
		(fp_line
			(start -7.7 2.4)
			(end -8.3 1.8)
			(stroke
				(width 0.15)
				(type solid)
			)
			(layer "B.Fab")
		)
		(fp_text user "${REFERENCE}"
			(at -9.625 -7.89 270)
			(layer "B.Fab")
			(effects
				(font
					(size 0.7 0.7)
					(thickness 0.15)
				)
				(justify left bottom mirror)
			)
		)
		(fp_text user "Author: Antmicro"
			(at -9.625 -9.09 270)
			(layer "B.Fab")
			(effects
				(font
					(size 0.7 0.7)
					(thickness 0.15)
				)
				(justify left bottom mirror)
			)
		)
		(fp_text user "License: Apache-2.0"
			(at -9.625 -6.69 270)
			(layer "B.Fab")
			(effects
				(font
					(size 0.7 0.7)
					(thickness 0.15)
				)
				(justify left bottom mirror)
			)
		)
		(pad "1" smd rect
			(at -4.75 1.803 90)
			(size 0.25 0.9)
			(layers "B.Cu" "B.Mask" "B.Paste")
			(net 490 "unconnected-(J11-Pad1)")
			(pinfunction "1")
			(pintype "passive+no_connect")
		)
		(pad "2" smd rect
			(at -4.25 1.803 90)
			(size 0.25 0.9)
			(layers "B.Cu" "B.Mask" "B.Paste")
			(net 604 "/HDMI + SD Card/HDMI_IN_HPD_CONN")
			(pinfunction "2")
			(pintype "passive")
		)
		(pad "3" smd rect
			(at -3.75 1.803 90)
			(size 0.25 0.9)
			(layers "B.Cu" "B.Mask" "B.Paste")
			(net 297 "/HDMI + SD Card/HDMI_IN_5V")
			(pinfunction "3")
			(pintype "passive")
		)
		(pad "4" smd rect
			(at -3.25 1.803 90)
			(size 0.25 0.9)
			(layers "B.Cu" "B.Mask" "B.Paste")
			(net 1 "GND")
			(pinfunction "4")
			(pintype "passive")
		)
		(pad "5" smd rect
			(at -2.75 1.803 90)
			(size 0.25 0.9)
			(layers "B.Cu" "B.Mask" "B.Paste")
			(net 499 "/HDMI + SD Card/HDMI_IN_5V.SCL")
			(pinfunction "5")
			(pintype "passive")
		)
		(pad "6" smd rect
			(at -2.25 1.803 90)
			(size 0.25 0.9)
			(layers "B.Cu" "B.Mask" "B.Paste")
			(net 480 "/HDMI + SD Card/HDMI_IN_5V.SDA")
			(pinfunction "6")
			(pintype "passive")
		)
		(pad "7" smd rect
			(at -1.75 1.803 90)
			(size 0.25 0.9)
			(layers "B.Cu" "B.Mask" "B.Paste")
			(net 496 "unconnected-(J11-Pad7)")
			(pinfunction "7")
			(pintype "passive+no_connect")
		)
		(pad "8" smd rect
			(at -1.25 1.803 90)
			(size 0.25 0.9)
			(layers "B.Cu" "B.Mask" "B.Paste")
			(net 504 "unconnected-(J11-Pad8)")
			(pinfunction "8")
			(pintype "passive+no_connect")
		)
		(pad "9" smd rect
			(at -0.75 1.803 90)
			(size 0.25 0.9)
			(layers "B.Cu" "B.Mask" "B.Paste")
			(net 292 "/FPGA MGT Interface/HDMI_IN.CLK_N")
			(pinfunction "9")
			(pintype "passive")
		)
		(pad "10" smd rect
			(at -0.25 1.803 90)
			(size 0.25 0.9)
			(layers "B.Cu" "B.Mask" "B.Paste")
			(net 1 "GND")
			(pinfunction "10")
			(pintype "passive")
		)
		(pad "11" smd rect
			(at 0.24 1.803 90)
			(size 0.25 0.9)
			(layers "B.Cu" "B.Mask" "B.Paste")
			(net 269 "/FPGA MGT Interface/HDMI_IN.CLK_P")
			(pinfunction "11")
			(pintype "passive")
		)
		(pad "12" smd rect
			(at 0.74 1.803 90)
			(size 0.25 0.9)
			(layers "B.Cu" "B.Mask" "B.Paste")
			(net 349 "/FPGA MGT Interface/HDMI_IN.D0_N")
			(pinfunction "12")
			(pintype "passive")
		)
		(pad "13" smd rect
			(at 1.249 1.803 90)
			(size 0.25 0.9)
			(layers "B.Cu" "B.Mask" "B.Paste")
			(net 1 "GND")
			(pinfunction "13")
			(pintype "passive")
		)
		(pad "14" smd rect
			(at 1.749 1.803 90)
			(size 0.25 0.9)
			(layers "B.Cu" "B.Mask" "B.Paste")
			(net 380 "/FPGA MGT Interface/HDMI_IN.D0_P")
			(pinfunction "14")
			(pintype "passive")
		)
		(pad "15" smd rect
			(at 2.249 1.803 90)
			(size 0.25 0.9)
			(layers "B.Cu" "B.Mask" "B.Paste")
			(net 346 "/FPGA MGT Interface/HDMI_IN.D1_N")
			(pinfunction "15")
			(pintype "passive")
		)
		(pad "16" smd rect
			(at 2.749 1.803 90)
			(size 0.25 0.9)
			(layers "B.Cu" "B.Mask" "B.Paste")
			(net 1 "GND")
			(pinfunction "16")
			(pintype "passive")
		)
		(pad "17" smd rect
			(at 3.249 1.803 90)
			(size 0.25 0.9)
			(layers "B.Cu" "B.Mask" "B.Paste")
			(net 348 "/FPGA MGT Interface/HDMI_IN.D1_P")
			(pinfunction "17")
			(pintype "passive")
		)
		(pad "18" smd rect
			(at 3.749 1.803 90)
			(size 0.25 0.9)
			(layers "B.Cu" "B.Mask" "B.Paste")
			(net 342 "/FPGA MGT Interface/HDMI_IN.D2_N")
			(pinfunction "18")
			(pintype "passive")
		)
		(pad "19" smd rect
			(at 4.248 1.803 90)
			(size 0.25 0.9)
			(layers "B.Cu" "B.Mask" "B.Paste")
			(net 1 "GND")
			(pinfunction "19")
			(pintype "passive")
		)
		(pad "20" smd rect
			(at 4.748 1.803 90)
			(size 0.25 0.9)
			(layers "B.Cu" "B.Mask" "B.Paste")
			(net 344 "/FPGA MGT Interface/HDMI_IN.D2_P")
			(pinfunction "20")
			(pintype "passive")
		)
		(pad "SH" smd rect
			(at -7.851 -1.017 90)
			(size 1.4 1.9)
			(layers "B.Cu" "B.Mask" "B.Paste")
			(net 1 "GND")
			(pinfunction "SH")
			(pintype "passive")
		)
		(pad "SH" smd rect
			(at -7.771 1.349 90)
			(size 0.7 1.27)
			(layers "B.Cu" "B.Mask" "B.Paste")
			(net 1 "GND")
			(pinfunction "SH")
			(pintype "passive")
		)
		(pad "SH" smd rect
			(at -5.651 1.803 90)
			(size 0.55 0.9)
			(layers "B.Cu" "B.Mask" "B.Paste")
			(net 1 "GND")
			(pinfunction "SH")
			(pintype "passive")
		)
		(pad "SH" smd rect
			(at 5.65 1.803 90)
			(size 0.55 0.9)
			(layers "B.Cu" "B.Mask" "B.Paste")
			(net 1 "GND")
			(pinfunction "SH")
			(pintype "passive")
		)
		(pad "SH" smd rect
			(at 7.767 1.349 90)
			(size 0.7 1.27)
			(layers "B.Cu" "B.Mask" "B.Paste")
			(net 1 "GND")
			(pinfunction "SH")
			(pintype "passive")
		)
		(pad "SH" smd rect
			(at 7.849 -1.017 90)
			(size 1.4 1.9)
			(layers "B.Cu" "B.Mask" "B.Paste")
			(net 1 "GND")
			(pinfunction "SH")
			(pintype "passive")
		)
	)
	(footprint "antmicro-footprints:R_0402_1005Metric"
		(layer "B.Cu")
		(at 253.039499 141.3)
		(descr "Resistor SMD 0402")
		(tags "resistor SMD 0402")
		(property "Reference" "R184"
			(at -4.089499 0.4 0)
			(layer "B.SilkS")
			(effects
				(font
					(size 0.7 0.7)
					(thickness 0.15)
				)
				(justify right bottom mirror)
			)
		)
		(property "Value" "R_47k_0402"
			(at -1.011843 -1.772047 0)
			(layer "B.Fab")
			(effects
				(font
					(size 0.7 0.7)
					(thickness 0.15)
				)
				(justify right bottom mirror)
			)
		)
		(property "Datasheet" "https://www.bourns.com/docs/product-datasheets/cr.pdf"
			(at 0 0 0)
			(layer "F.Fab")
			(hide yes)
			(effects
				(font
					(size 1.27 1.27)
					(thickness 0.15)
				)
			)
		)
		(property "Manufacturer" "Bourns"
			(at 0 0 0)
			(unlocked yes)
			(layer "B.Fab")
			(hide yes)
			(effects
				(font
					(size 1 1)
					(thickness 0.15)
				)
				(justify mirror)
			)
		)
		(property "MPN" "CR0402-FX-4702GLF"
			(at 0 0 0)
			(unlocked yes)
			(layer "B.Fab")
			(hide yes)
			(effects
				(font
					(size 1 1)
					(thickness 0.15)
				)
				(justify mirror)
			)
		)
		(property "Val" "47k"
			(at 0 0 0)
			(unlocked yes)
			(layer "B.Fab")
			(hide yes)
			(effects
				(font
					(size 1 1)
					(thickness 0.15)
				)
				(justify mirror)
			)
		)
		(property "License" "Apache-2.0"
			(at 0 0 0)
			(unlocked yes)
			(layer "B.Fab")
			(hide yes)
			(effects
				(font
					(size 1 1)
					(thickness 0.15)
				)
				(justify mirror)
			)
		)
		(property "Author" "Antmicro"
			(at 0 0 0)
			(unlocked yes)
			(layer "B.Fab")
			(hide yes)
			(effects
				(font
					(size 1 1)
					(thickness 0.15)
				)
				(justify mirror)
			)
		)
		(property "Tolerance" "1%"
			(at 0 0 0)
			(unlocked yes)
			(layer "B.Fab")
			(hide yes)
			(effects
				(font
					(size 1 1)
					(thickness 0.15)
				)
				(justify mirror)
			)
		)
		(sheetname "/Supply/")
		(sheetfile "supply.kicad_sch")
		(attr smd)
		(fp_rect
			(start -0.925 0.47)
			(end 0.925 -0.47)
			(stroke
				(width 0.05)
				(type default)
			)
			(fill no)
			(layer "B.CrtYd")
		)
		(fp_rect
			(start -0.5 0.25)
			(end 0.5 -0.25)
			(stroke
				(width 0.15)
				(type solid)
			)
			(fill no)
			(layer "B.Fab")
		)
		(fp_text user "License: Apache-2.0"
			(at -0.95 -5.169 180)
			(layer "B.Fab")
			(effects
				(font
					(size 0.7 0.7)
					(thickness 0.15)
				)
				(justify left bottom mirror)
			)
		)
		(fp_text user "${REFERENCE}"
			(at -0.95 -3.168 180)
			(layer "B.Fab")
			(effects
				(font
					(size 0.7 0.7)
					(thickness 0.15)
				)
				(justify left bottom mirror)
			)
		)
		(fp_text user "Author: Antmicro"
			(at -0.95 -4.169 180)
			(layer "B.Fab")
			(effects
				(font
					(size 0.7 0.7)
					(thickness 0.15)
				)
				(justify left bottom mirror)
			)
		)
		(pad "1" smd roundrect
			(at -0.48 0)
			(size 0.59 0.64)
			(layers "B.Cu" "B.Mask" "B.Paste")
			(roundrect_rratio 0.25)
			(net 168 "/Supply/EN1")
			(pintype "passive")
		)
		(pad "2" smd roundrect
			(at 0.48 0)
			(size 0.59 0.64)
			(layers "B.Cu" "B.Mask" "B.Paste")
			(roundrect_rratio 0.25)
			(net 38 "+3V3_AON")
			(pintype "passive")
		)
	)
	(footprint "antmicro-footprints:R_0402_1005Metric"
		(layer "B.Cu")
		(at 238.777999 141.151 180)
		(descr "Resistor SMD 0402")
		(tags "resistor SMD 0402")
		(property "Reference" "R140"
			(at -4.365499 -0.4225 0)
			(layer "B.SilkS")
			(effects
				(font
					(size 0.7 0.7)
					(thickness 0.15)
				)
				(justify left bottom mirror)
			)
		)
		(property "Value" "R_47k_0402"
			(at -1.011843 -1.772047 0)
			(layer "B.Fab")
			(effects
				(font
					(size 0.7 0.7)
					(thickness 0.15)
				)
				(justify left bottom mirror)
			)
		)
		(property "Datasheet" "https://www.bourns.com/docs/product-datasheets/cr.pdf"
			(at 0 0 180)
			(layer "F.Fab")
			(hide yes)
			(effects
				(font
					(size 1.27 1.27)
					(thickness 0.15)
				)
			)
		)
		(property "Manufacturer" "Bourns"
			(at 0 0 180)
			(unlocked yes)
			(layer "B.Fab")
			(hide yes)
			(effects
				(font
					(size 1 1)
					(thickness 0.15)
				)
				(justify mirror)
			)
		)
		(property "MPN" "CR0402-FX-4702GLF"
			(at 0 0 180)
			(unlocked yes)
			(layer "B.Fab")
			(hide yes)
			(effects
				(font
					(size 1 1)
					(thickness 0.15)
				)
				(justify mirror)
			)
		)
		(property "Val" "47k"
			(at 0 0 180)
			(unlocked yes)
			(layer "B.Fab")
			(hide yes)
			(effects
				(font
					(size 1 1)
					(thickness 0.15)
				)
				(justify mirror)
			)
		)
		(property "License" "Apache-2.0"
			(at 0 0 180)
			(unlocked yes)
			(layer "B.Fab")
			(hide yes)
			(effects
				(font
					(size 1 1)
					(thickness 0.15)
				)
				(justify mirror)
			)
		)
		(property "Author" "Antmicro"
			(at 0 0 180)
			(unlocked yes)
			(layer "B.Fab")
			(hide yes)
			(effects
				(font
					(size 1 1)
					(thickness 0.15)
				)
				(justify mirror)
			)
		)
		(property "Tolerance" "1%"
			(at 0 0 180)
			(unlocked yes)
			(layer "B.Fab")
			(hide yes)
			(effects
				(font
					(size 1 1)
					(thickness 0.15)
				)
				(justify mirror)
			)
		)
		(sheetname "/Supply/")
		(sheetfile "supply.kicad_sch")
		(attr smd)
		(fp_rect
			(start -0.925 0.47)
			(end 0.925 -0.47)
			(stroke
				(width 0.05)
				(type default)
			)
			(fill no)
			(layer "B.CrtYd")
		)
		(fp_rect
			(start -0.5 0.25)
			(end 0.5 -0.25)
			(stroke
				(width 0.15)
				(type solid)
			)
			(fill no)
			(layer "B.Fab")
		)
		(fp_text user "License: Apache-2.0"
			(at -0.95 -5.169 0)
			(layer "B.Fab")
			(effects
				(font
					(size 0.7 0.7)
					(thickness 0.15)
				)
				(justify left bottom mirror)
			)
		)
		(fp_text user "${REFERENCE}"
			(at -0.95 -3.168 0)
			(layer "B.Fab")
			(effects
				(font
					(size 0.7 0.7)
					(thickness 0.15)
				)
				(justify left bottom mirror)
			)
		)
		(fp_text user "Author: Antmicro"
			(at -0.95 -4.169 0)
			(layer "B.Fab")
			(effects
				(font
					(size 0.7 0.7)
					(thickness 0.15)
				)
				(justify left bottom mirror)
			)
		)
		(pad "1" smd roundrect
			(at -0.48 0 180)
			(size 0.59 0.64)
			(layers "B.Cu" "B.Mask" "B.Paste")
			(roundrect_rratio 0.25)
			(net 405 "IN2")
			(pintype "passive")
		)
		(pad "2" smd roundrect
			(at 0.48 0 180)
			(size 0.59 0.64)
			(layers "B.Cu" "B.Mask" "B.Paste")
			(roundrect_rratio 0.25)
			(net 38 "+3V3_AON")
			(pintype "passive")
		)
	)
	(footprint "antmicro-footprints:NetTie-2_SMD_Pad0.127mm"
		(layer "B.Cu")
		(at 205.823 150.8 180)
		(descr "Net tie, 2 pin, 0.127mm  SMD pads")
		(tags "net tie")
		(property "Reference" "TP3"
			(at -0.128 1.345 0)
			(layer "B.SilkS")
			(hide yes)
			(effects
				(font
					(size 0.7 0.7)
					(thickness 0.15)
				)
				(justify left bottom mirror)
			)
		)
		(property "Value" "Net-Tie_P0.127mm"
			(at 0 -1.199 0)
			(layer "B.Fab")
			(effects
				(font
					(size 0.7 0.7)
					(thickness 0.15)
				)
				(justify left bottom mirror)
			)
		)
		(property "MPN" ""
			(at 0 0 180)
			(unlocked yes)
			(layer "B.Fab")
			(hide yes)
			(effects
				(font
					(size 1 1)
					(thickness 0.15)
				)
				(justify mirror)
			)
		)
		(property "Manufacturer" ""
			(at 0 0 180)
			(unlocked yes)
			(layer "B.Fab")
			(hide yes)
			(effects
				(font
					(size 1 1)
					(thickness 0.15)
				)
				(justify mirror)
			)
		)
		(property "Author" "Antmicro"
			(at 0 0 180)
			(unlocked yes)
			(layer "B.Fab")
			(hide yes)
			(effects
				(font
					(size 1 1)
					(thickness 0.15)
				)
				(justify mirror)
			)
		)
		(property "License" "Apache-2.0"
			(at 0 0 180)
			(unlocked yes)
			(layer "B.Fab")
			(hide yes)
			(effects
				(font
					(size 1 1)
					(thickness 0.15)
				)
				(justify mirror)
			)
		)
		(property ki_fp_filters "Net*Tie*")
		(sheetname "/FPGA Config/")
		(sheetfile "fpga-config.kicad_sch")
		(attr through_hole exclude_from_pos_files exclude_from_bom)
		(net_tie_pad_groups "1, 2")
		(fp_poly
			(pts
				(xy -0.0635 0.0635) (xy 0.0625 0.0635) (xy 0.0625 -0.0635) (xy -0.0635 -0.0635)
			)
			(stroke
				(width 0)
				(type solid)
			)
			(fill yes)
			(layer "B.Cu")
		)
		(fp_poly
			(pts
				(xy 0.2 0.16) (xy 0.29 0.07) (xy 0.29 -0.07) (xy 0.2 -0.16) (xy -0.2 -0.16) (xy -0.29 -0.07) (xy -0.29 0.06)
				(xy -0.19 0.16)
			)
			(stroke
				(width 0.05)
				(type solid)
			)
			(fill no)
			(layer "B.CrtYd")
		)
		(fp_text user "Author: Antmicro"
			(at -0.128 -4.4 0)
			(layer "B.Fab")
			(effects
				(font
					(size 0.7 0.7)
					(thickness 0.15)
				)
				(justify left bottom mirror)
			)
		)
		(fp_text user "License: Apache-2.0"
			(at -0.128 -5.6 0)
			(layer "B.Fab")
			(effects
				(font
					(size 0.7 0.7)
					(thickness 0.15)
				)
				(justify left bottom mirror)
			)
		)
		(fp_text user "${REFERENCE}"
			(at -0.128 -3.2 0)
			(layer "B.Fab")
			(effects
				(font
					(size 0.7 0.7)
					(thickness 0.15)
				)
				(justify left bottom mirror)
			)
		)
		(pad "1" smd roundrect
			(at -0.127 0)
			(size 0.127 0.127)
			(layers "B.Cu")
			(roundrect_rratio 0.5)
			(chamfer_ratio 0)
			(chamfer top_left bottom_left)
			(net 160 "Net-(U30-OUT)")
			(pinfunction "1")
			(pintype "passive")
		)
		(pad "2" smd roundrect
			(at 0.126 0 180)
			(size 0.127 0.127)
			(layers "B.Cu")
			(roundrect_rratio 0.5)
			(chamfer_ratio 0)
			(chamfer top_left bottom_left)
			(net 599 "/FPGA Config/VREFP")
			(pinfunction "2")
			(pintype "passive")
		)
	)
	(footprint "antmicro-footprints:C_0402_1005Metric"
		(layer "B.Cu")
		(at 146.464499 164.653 90)
		(descr "Capacitor SMD 0402")
		(tags "capacitor SMD 0402")
		(property "Reference" "C235"
			(at 1.331 0.347501 90)
			(layer "B.SilkS")
			(effects
				(font
					(size 0.7 0.7)
					(thickness 0.15)
				)
				(justify right bottom mirror)
			)
		)
		(property "Value" "C_100n_0402"
			(at -1.022927 -2.155213 90)
			(layer "B.Fab")
			(effects
				(font
					(size 0.7 0.7)
					(thickness 0.15)
				)
				(justify right bottom mirror)
			)
		)
		(property "Datasheet" "https://www.murata.com/products/productdetail?partno=GRM155R61H104KE14%23"
			(at 0 0 90)
			(layer "F.Fab")
			(hide yes)
			(effects
				(font
					(size 1.27 1.27)
					(thickness 0.15)
				)
			)
		)
		(property "MPN" "GRM155R61H104KE14D"
			(at 0 0 90)
			(unlocked yes)
			(layer "B.Fab")
			(hide yes)
			(effects
				(font
					(size 1 1)
					(thickness 0.15)
				)
				(justify mirror)
			)
		)
		(property "Manufacturer" "Murata"
			(at 0 0 90)
			(unlocked yes)
			(layer "B.Fab")
			(hide yes)
			(effects
				(font
					(size 1 1)
					(thickness 0.15)
				)
				(justify mirror)
			)
		)
		(property "License" "Apache-2.0"
			(at 0 0 90)
			(unlocked yes)
			(layer "B.Fab")
			(hide yes)
			(effects
				(font
					(size 1 1)
					(thickness 0.15)
				)
				(justify mirror)
			)
		)
		(property "Author" "Antmicro"
			(at 0 0 90)
			(unlocked yes)
			(layer "B.Fab")
			(hide yes)
			(effects
				(font
					(size 1 1)
					(thickness 0.15)
				)
				(justify mirror)
			)
		)
		(property "Val" "100n"
			(at 0 0 90)
			(unlocked yes)
			(layer "B.Fab")
			(hide yes)
			(effects
				(font
					(size 1 1)
					(thickness 0.15)
				)
				(justify mirror)
			)
		)
		(property "Voltage" "50V"
			(at 0 0 90)
			(unlocked yes)
			(layer "B.Fab")
			(hide yes)
			(effects
				(font
					(size 1 1)
					(thickness 0.15)
				)
				(justify mirror)
			)
		)
		(property "Dielectric" "X5R"
			(at 0 0 90)
			(unlocked yes)
			(layer "B.Fab")
			(hide yes)
			(effects
				(font
					(size 1 1)
					(thickness 0.15)
				)
				(justify mirror)
			)
		)
		(sheetname "/Debug FTDI + VNA/")
		(sheetfile "debug-ftdi.kicad_sch")
		(attr smd)
		(fp_rect
			(start -0.925 0.47)
			(end 0.925 -0.47)
			(stroke
				(width 0.05)
				(type default)
			)
			(fill no)
			(layer "B.CrtYd")
		)
		(fp_line
			(start 0.504 -0.248)
			(end -0.494 -0.248)
			(stroke
				(width 0.15)
				(type solid)
			)
			(layer "B.Fab")
		)
		(fp_line
			(start -0.494 -0.248)
			(end -0.494 0.25)
			(stroke
				(width 0.15)
				(type solid)
			)
			(layer "B.Fab")
		)
		(fp_line
			(start 0.504 0.25)
			(end 0.504 -0.248)
			(stroke
				(width 0.15)
				(type solid)
			)
			(layer "B.Fab")
		)
		(fp_line
			(start -0.494 0.25)
			(end 0.504 0.25)
			(stroke
				(width 0.15)
				(type solid)
			)
			(layer "B.Fab")
		)
		(fp_text user "${REFERENCE}"
			(at -0.939 -4.599 270)
			(layer "B.Fab")
			(effects
				(font
					(size 0.7 0.7)
					(thickness 0.15)
				)
				(justify left bottom mirror)
			)
		)
		(fp_text user "License: Apache-2.0"
			(at -0.939 -5.799 270)
			(layer "B.Fab")
			(effects
				(font
					(size 0.7 0.7)
					(thickness 0.15)
				)
				(justify left bottom mirror)
			)
		)
		(fp_text user "Author: Antmicro"
			(at -0.939 -3.399 270)
			(layer "B.Fab")
			(effects
				(font
					(size 0.7 0.7)
					(thickness 0.15)
				)
				(justify left bottom mirror)
			)
		)
		(pad "1" smd roundrect
			(at -0.48 0 90)
			(size 0.59 0.64)
			(layers "B.Cu" "B.Mask" "B.Paste")
			(roundrect_rratio 0.25)
			(net 1 "GND")
			(pintype "passive")
		)
		(pad "2" smd roundrect
			(at 0.48 0 90)
			(size 0.59 0.64)
			(layers "B.Cu" "B.Mask" "B.Paste")
			(roundrect_rratio 0.25)
			(net 6 "/Debug FTDI + VNA/FTDI_3V3")
			(pintype "passive")
		)
	)
	(footprint "antmicro-footprints:C_0402_1005Metric_EIA"
		(layer "B.Cu")
		(at 184 162.502 -90)
		(descr "Capacitor SMD 0402 (1005 Metric), square (rectangular) end terminal, IPC_7351 nominal, (Body size source: IPC-SM-782 page 76, https://www.pcb-3d.com/wordpress/wp-content/uploads/ipc-sm-782a_amendment_1_and_2.pdf)")
		(tags "capacitor 0402")
		(property "Reference" "C72"
			(at 1.098 -0.2 90)
			(layer "B.SilkS")
			(effects
				(font
					(size 0.7 0.7)
					(thickness 0.15)
				)
				(justify left bottom mirror)
			)
		)
		(property "Value" "C_4u7_0402"
			(at 0 -1.169 90)
			(layer "B.Fab")
			(effects
				(font
					(size 0.7 0.7)
					(thickness 0.15)
				)
				(justify left bottom mirror)
			)
		)
		(property "Datasheet" "https://www.murata.com/products/productdetail?partno=GRM155R61A475MEAA%23"
			(at 0 0 270)
			(layer "F.Fab")
			(hide yes)
			(effects
				(font
					(size 1.27 1.27)
					(thickness 0.15)
				)
			)
		)
		(property "Manufacturer" "Murata"
			(at 0 0 270)
			(unlocked yes)
			(layer "B.Fab")
			(hide yes)
			(effects
				(font
					(size 1 1)
					(thickness 0.15)
				)
				(justify mirror)
			)
		)
		(property "MPN" "GRM155R61A475MEAAD"
			(at 0 0 270)
			(unlocked yes)
			(layer "B.Fab")
			(hide yes)
			(effects
				(font
					(size 1 1)
					(thickness 0.15)
				)
				(justify mirror)
			)
		)
		(property "Val" "4u7"
			(at 0 0 270)
			(unlocked yes)
			(layer "B.Fab")
			(hide yes)
			(effects
				(font
					(size 1 1)
					(thickness 0.15)
				)
				(justify mirror)
			)
		)
		(property "License" "Apache-2.0"
			(at 0 0 270)
			(unlocked yes)
			(layer "B.Fab")
			(hide yes)
			(effects
				(font
					(size 1 1)
					(thickness 0.15)
				)
				(justify mirror)
			)
		)
		(property "Author" "Antmicro"
			(at 0 0 270)
			(unlocked yes)
			(layer "B.Fab")
			(hide yes)
			(effects
				(font
					(size 1 1)
					(thickness 0.15)
				)
				(justify mirror)
			)
		)
		(property "Voltage" ""
			(at 0 0 270)
			(unlocked yes)
			(layer "B.Fab")
			(hide yes)
			(effects
				(font
					(size 1 1)
					(thickness 0.15)
				)
				(justify mirror)
			)
		)
		(property "Dielectric" ""
			(at 0 0 270)
			(unlocked yes)
			(layer "B.Fab")
			(hide yes)
			(effects
				(font
					(size 1 1)
					(thickness 0.15)
				)
				(justify mirror)
			)
		)
		(sheetname "/FPGA power/")
		(sheetfile "fpga-power.kicad_sch")
		(attr smd)
		(fp_rect
			(start -0.95 0.45)
			(end 0.95 -0.45)
			(stroke
				(width 0.05)
				(type default)
			)
			(fill no)
			(layer "B.CrtYd")
		)
		(fp_line
			(start -0.5 0.25)
			(end 0.498 0.25)
			(stroke
				(width 0.15)
				(type solid)
			)
			(layer "B.Fab")
		)
		(fp_line
			(start 0.498 0.25)
			(end 0.498 -0.248)
			(stroke
				(width 0.15)
				(type solid)
			)
			(layer "B.Fab")
		)
		(fp_line
			(start -0.5 -0.248)
			(end -0.5 0.25)
			(stroke
				(width 0.15)
				(type solid)
			)
			(layer "B.Fab")
		)
		(fp_line
			(start 0.498 -0.248)
			(end -0.5 -0.248)
			(stroke
				(width 0.15)
				(type solid)
			)
			(layer "B.Fab")
		)
		(fp_text user "License: Apache-2.0"
			(at -0.9656 -4.369 90)
			(layer "B.Fab")
			(effects
				(font
					(size 0.7 0.7)
					(thickness 0.15)
				)
				(justify left bottom mirror)
			)
		)
		(fp_text user "Author: Antmicro"
			(at -0.9656 -5.569 90)
			(layer "B.Fab")
			(effects
				(font
					(size 0.7 0.7)
					(thickness 0.15)
				)
				(justify left bottom mirror)
			)
		)
		(fp_text user "${REFERENCE}"
			(at -0.9656 -3.169 90)
			(layer "B.Fab")
			(effects
				(font
					(size 0.7 0.7)
					(thickness 0.15)
				)
				(justify left bottom mirror)
			)
		)
		(pad "1" smd roundrect
			(at -0.5 0 180)
			(size 0.6 0.6)
			(layers "B.Cu" "B.Mask" "B.Paste")
			(roundrect_rratio 0.25)
			(net 172 "+1V2_MGTAVTT")
			(pintype "passive")
		)
		(pad "2" smd roundrect
			(at 0.498 0 270)
			(size 0.6 0.6)
			(layers "B.Cu" "B.Mask" "B.Paste")
			(roundrect_rratio 0.25)
			(net 1 "GND")
			(pintype "passive")
		)
	)
	(footprint "antmicro-footprints:C_0402_1005Metric_EIA"
		(layer "B.Cu")
		(at 195.5 156)
		(descr "Capacitor SMD 0402 (1005 Metric), square (rectangular) end terminal, IPC_7351 nominal, (Body size source: IPC-SM-782 page 76, https://www.pcb-3d.com/wordpress/wp-content/uploads/ipc-sm-782a_amendment_1_and_2.pdf)")
		(tags "capacitor 0402")
		(property "Reference" "C76"
			(at -32.125 -10.4 0)
			(layer "B.SilkS")
			(effects
				(font
					(size 0.7 0.7)
					(thickness 0.15)
				)
				(justify right bottom mirror)
			)
		)
		(property "Value" "C_100n_0402"
			(at 0 -1.169 0)
			(layer "B.Fab")
			(effects
				(font
					(size 0.7 0.7)
					(thickness 0.15)
				)
				(justify right bottom mirror)
			)
		)
		(property "Datasheet" "https://www.murata.com/products/productdetail?partno=GRM155R61H104KE14%23"
			(at 0 0 0)
			(layer "F.Fab")
			(hide yes)
			(effects
				(font
					(size 1.27 1.27)
					(thickness 0.15)
				)
			)
		)
		(property "MPN" "GRM155R61H104KE14D"
			(at 0 0 0)
			(unlocked yes)
			(layer "B.Fab")
			(hide yes)
			(effects
				(font
					(size 1 1)
					(thickness 0.15)
				)
				(justify mirror)
			)
		)
		(property "Manufacturer" "Murata"
			(at 0 0 0)
			(unlocked yes)
			(layer "B.Fab")
			(hide yes)
			(effects
				(font
					(size 1 1)
					(thickness 0.15)
				)
				(justify mirror)
			)
		)
		(property "License" "Apache-2.0"
			(at 0 0 0)
			(unlocked yes)
			(layer "B.Fab")
			(hide yes)
			(effects
				(font
					(size 1 1)
					(thickness 0.15)
				)
				(justify mirror)
			)
		)
		(property "Author" "Antmicro"
			(at 0 0 0)
			(unlocked yes)
			(layer "B.Fab")
			(hide yes)
			(effects
				(font
					(size 1 1)
					(thickness 0.15)
				)
				(justify mirror)
			)
		)
		(property "Val" "100n"
			(at 0 0 0)
			(unlocked yes)
			(layer "B.Fab")
			(hide yes)
			(effects
				(font
					(size 1 1)
					(thickness 0.15)
				)
				(justify mirror)
			)
		)
		(property "Voltage" "50V"
			(at 0 0 0)
			(unlocked yes)
			(layer "B.Fab")
			(hide yes)
			(effects
				(font
					(size 1 1)
					(thickness 0.15)
				)
				(justify mirror)
			)
		)
		(property "Dielectric" "X5R"
			(at 0 0 0)
			(unlocked yes)
			(layer "B.Fab")
			(hide yes)
			(effects
				(font
					(size 1 1)
					(thickness 0.15)
				)
				(justify mirror)
			)
		)
		(sheetname "/FPGA power/")
		(sheetfile "fpga-power.kicad_sch")
		(attr smd)
		(fp_rect
			(start -0.95 0.45)
			(end 0.95 -0.45)
			(stroke
				(width 0.05)
				(type default)
			)
			(fill no)
			(layer "B.CrtYd")
		)
		(fp_line
			(start -0.5 -0.248)
			(end -0.5 0.25)
			(stroke
				(width 0.15)
				(type solid)
			)
			(layer "B.Fab")
		)
		(fp_line
			(start -0.5 0.25)
			(end 0.498 0.25)
			(stroke
				(width 0.15)
				(type solid)
			)
			(layer "B.Fab")
		)
		(fp_line
			(start 0.498 -0.248)
			(end -0.5 -0.248)
			(stroke
				(width 0.15)
				(type solid)
			)
			(layer "B.Fab")
		)
		(fp_line
			(start 0.498 0.25)
			(end 0.498 -0.248)
			(stroke
				(width 0.15)
				(type solid)
			)
			(layer "B.Fab")
		)
		(fp_text user "License: Apache-2.0"
			(at -0.9656 -4.369 180)
			(layer "B.Fab")
			(effects
				(font
					(size 0.7 0.7)
					(thickness 0.15)
				)
				(justify left bottom mirror)
			)
		)
		(fp_text user "${REFERENCE}"
			(at -0.9656 -3.169 180)
			(layer "B.Fab")
			(effects
				(font
					(size 0.7 0.7)
					(thickness 0.15)
				)
				(justify left bottom mirror)
			)
		)
		(fp_text user "Author: Antmicro"
			(at -0.9656 -5.569 180)
			(layer "B.Fab")
			(effects
				(font
					(size 0.7 0.7)
					(thickness 0.15)
				)
				(justify left bottom mirror)
			)
		)
		(pad "1" smd roundrect
			(at -0.5 0 270)
			(size 0.6 0.6)
			(layers "B.Cu" "B.Mask" "B.Paste")
			(roundrect_rratio 0.25)
			(net 1 "GND")
			(pintype "passive")
		)
		(pad "2" smd roundrect
			(at 0.498 0)
			(size 0.6 0.6)
			(layers "B.Cu" "B.Mask" "B.Paste")
			(roundrect_rratio 0.25)
			(net 797 "+1V8")
			(pintype "passive")
		)
	)
	(footprint "antmicro-footprints:SC70-3"
		(layer "B.Cu")
		(at 114.755 112.95 180)
		(property "Reference" "Q7"
			(at -3.355 -0.334 0)
			(layer "B.SilkS")
			(effects
				(font
					(size 0.7 0.7)
					(thickness 0.15)
				)
				(justify left bottom mirror)
			)
		)
		(property "Value" "BSS138PW"
			(at 0 -2.3 0)
			(layer "B.Fab")
			(effects
				(font
					(size 0.7 0.7)
					(thickness 0.15)
				)
				(justify left bottom mirror)
			)
		)
		(property "Datasheet" "https://assets.nexperia.com/documents/data-sheet/BSS138PW.pdf"
			(at 0 0 180)
			(layer "F.Fab")
			(hide yes)
			(effects
				(font
					(size 1.27 1.27)
					(thickness 0.15)
				)
			)
		)
		(property "MPN" "BSS138PW"
			(at 0 0 180)
			(unlocked yes)
			(layer "B.Fab")
			(hide yes)
			(effects
				(font
					(size 1 1)
					(thickness 0.15)
				)
				(justify mirror)
			)
		)
		(property "Manufacturer" "Nexperia"
			(at 0 0 180)
			(unlocked yes)
			(layer "B.Fab")
			(hide yes)
			(effects
				(font
					(size 1 1)
					(thickness 0.15)
				)
				(justify mirror)
			)
		)
		(property "Author" "Antmicro"
			(at 0 0 180)
			(unlocked yes)
			(layer "B.Fab")
			(hide yes)
			(effects
				(font
					(size 1 1)
					(thickness 0.15)
				)
				(justify mirror)
			)
		)
		(property "License" "Apache-2.0"
			(at 0 0 180)
			(unlocked yes)
			(layer "B.Fab")
			(hide yes)
			(effects
				(font
					(size 1 1)
					(thickness 0.15)
				)
				(justify mirror)
			)
		)
		(sheetname "/FPGA banks HD/")
		(sheetfile "fpga-hd-banks.kicad_sch")
		(attr smd)
		(fp_line
			(start 0.627 0.6)
			(end 0.627 0.999)
			(stroke
				(width 0.15)
				(type solid)
			)
			(layer "B.SilkS")
		)
		(fp_line
			(start 0.627 -0.6)
			(end 0.627 -1.001)
			(stroke
				(width 0.15)
				(type solid)
			)
			(layer "B.SilkS")
		)
		(fp_line
			(start -0.3 1)
			(end 0.627 0.999)
			(stroke
				(width 0.15)
				(type solid)
			)
			(layer "B.SilkS")
		)
		(fp_line
			(start -0.3 -1)
			(end 0.627 -1.001)
			(stroke
				(width 0.15)
				(type solid)
			)
			(layer "B.SilkS")
		)
		(fp_line
			(start 1.4 0.4)
			(end 1.4 -0.4)
			(stroke
				(width 0.05)
				(type solid)
			)
			(layer "B.CrtYd")
		)
		(fp_line
			(start 1.4 -0.4)
			(end 0.9 -0.4)
			(stroke
				(width 0.05)
				(type solid)
			)
			(layer "B.CrtYd")
		)
		(fp_line
			(start 0.9 1.3)
			(end 0.9 0.4)
			(stroke
				(width 0.05)
				(type solid)
			)
			(layer "B.CrtYd")
		)
		(fp_line
			(start 0.9 0.4)
			(end 1.4 0.4)
			(stroke
				(width 0.05)
				(type solid)
			)
			(layer "B.CrtYd")
		)
		(fp_line
			(start 0.9 -0.4)
			(end 0.9 -1.3)
			(stroke
				(width 0.05)
				(type solid)
			)
			(layer "B.CrtYd")
		)
		(fp_line
			(start 0.9 -1.3)
			(end -0.9 -1.3)
			(stroke
				(width 0.05)
				(type solid)
			)
			(layer "B.CrtYd")
		)
		(fp_line
			(start -0.9 1.3)
			(end 0.9 1.3)
			(stroke
				(width 0.05)
				(type solid)
			)
			(layer "B.CrtYd")
		)
		(fp_line
			(start -0.9 1.3)
			(end -0.9 1)
			(stroke
				(width 0.05)
				(type solid)
			)
			(layer "B.CrtYd")
		)
		(fp_line
			(start -0.9 1)
			(end -1.4 1)
			(stroke
				(width 0.05)
				(type solid)
			)
			(layer "B.CrtYd")
		)
		(fp_line
			(start -0.9 -1)
			(end -1.4 -1)
			(stroke
				(width 0.05)
				(type solid)
			)
			(layer "B.CrtYd")
		)
		(fp_line
			(start -0.9 -1.3)
			(end -0.9 -1)
			(stroke
				(width 0.05)
				(type solid)
			)
			(layer "B.CrtYd")
		)
		(fp_line
			(start -1.4 -1)
			(end -1.4 1)
			(stroke
				(width 0.05)
				(type solid)
			)
			(layer "B.CrtYd")
		)
		(fp_rect
			(start -0.623 0.999)
			(end 0.627 -1.001)
			(stroke
				(width 0.15)
				(type solid)
			)
			(fill no)
			(layer "B.Fab")
		)
		(fp_text user "License: Apache-2.0"
			(at -1.45 -6.782 0)
			(layer "B.Fab")
			(effects
				(font
					(size 0.7 0.7)
					(thickness 0.15)
				)
				(justify left bottom mirror)
			)
		)
		(fp_text user "${REFERENCE}"
			(at -1.45 -4.783 0)
			(layer "B.Fab")
			(effects
				(font
					(size 0.7 0.7)
					(thickness 0.15)
				)
				(justify left bottom mirror)
			)
		)
		(fp_text user "Author: Antmicro"
			(at -1.45 -5.782 0)
			(layer "B.Fab")
			(effects
				(font
					(size 0.7 0.7)
					(thickness 0.15)
				)
				(justify left bottom mirror)
			)
		)
		(pad "1" smd rect
			(at -1.051 0.65 90)
			(size 0.6 0.6)
			(layers "B.Cu" "B.Mask" "B.Paste")
			(net 698 "/FPGA banks HD/USR_LED2")
			(pinfunction "G")
			(pintype "passive")
		)
		(pad "2" smd rect
			(at -1.051 -0.65 90)
			(size 0.6 0.6)
			(layers "B.Cu" "B.Mask" "B.Paste")
			(net 1 "GND")
			(pinfunction "S")
			(pintype "passive")
		)
		(pad "3" smd rect
			(at 1.05 0 90)
			(size 0.6 0.6)
			(layers "B.Cu" "B.Mask" "B.Paste")
			(net 275 "Net-(Q7-D)")
			(pinfunction "D")
			(pintype "passive")
		)
	)
	(footprint "antmicro-footprints:C_0402_1005Metric_EIA"
		(layer "B.Cu")
		(at 193 148.5 -90)
		(descr "Capacitor SMD 0402 (1005 Metric), square (rectangular) end terminal, IPC_7351 nominal, (Body size source: IPC-SM-782 page 76, https://www.pcb-3d.com/wordpress/wp-content/uploads/ipc-sm-782a_amendment_1_and_2.pdf)")
		(tags "capacitor 0402")
		(property "Reference" "C84"
			(at -12.375 30.65 90)
			(layer "B.SilkS")
			(effects
				(font
					(size 0.7 0.7)
					(thickness 0.15)
				)
				(justify left bottom mirror)
			)
		)
		(property "Value" "C_1u_25V_0402"
			(at 0 -1.169 90)
			(layer "B.Fab")
			(effects
				(font
					(size 0.7 0.7)
					(thickness 0.15)
				)
				(justify left bottom mirror)
			)
		)
		(property "Datasheet" "https://www.murata.com/products/productdetail?partno=GRM155R61E105KE11%23"
			(at 0 0 270)
			(layer "F.Fab")
			(hide yes)
			(effects
				(font
					(size 1.27 1.27)
					(thickness 0.15)
				)
			)
		)
		(property "MPN" "GRM155R61E105KE11J"
			(at 0 0 270)
			(unlocked yes)
			(layer "B.Fab")
			(hide yes)
			(effects
				(font
					(size 1 1)
					(thickness 0.15)
				)
				(justify mirror)
			)
		)
		(property "Manufacturer" "Murata"
			(at 0 0 270)
			(unlocked yes)
			(layer "B.Fab")
			(hide yes)
			(effects
				(font
					(size 1 1)
					(thickness 0.15)
				)
				(justify mirror)
			)
		)
		(property "License" "Apache-2.0"
			(at 0 0 270)
			(unlocked yes)
			(layer "B.Fab")
			(hide yes)
			(effects
				(font
					(size 1 1)
					(thickness 0.15)
				)
				(justify mirror)
			)
		)
		(property "Author" "Antmicro"
			(at 0 0 270)
			(unlocked yes)
			(layer "B.Fab")
			(hide yes)
			(effects
				(font
					(size 1 1)
					(thickness 0.15)
				)
				(justify mirror)
			)
		)
		(property "Val" "1u"
			(at 0 0 270)
			(unlocked yes)
			(layer "B.Fab")
			(hide yes)
			(effects
				(font
					(size 1 1)
					(thickness 0.15)
				)
				(justify mirror)
			)
		)
		(property "Voltage" "25V"
			(at 0 0 270)
			(unlocked yes)
			(layer "B.Fab")
			(hide yes)
			(effects
				(font
					(size 1 1)
					(thickness 0.15)
				)
				(justify mirror)
			)
		)
		(property "Dielectric" "X5R"
			(at 0 0 270)
			(unlocked yes)
			(layer "B.Fab")
			(hide yes)
			(effects
				(font
					(size 1 1)
					(thickness 0.15)
				)
				(justify mirror)
			)
		)
		(sheetname "/FPGA power/")
		(sheetfile "fpga-power.kicad_sch")
		(attr smd)
		(fp_rect
			(start -0.95 0.45)
			(end 0.95 -0.45)
			(stroke
				(width 0.05)
				(type default)
			)
			(fill no)
			(layer "B.CrtYd")
		)
		(fp_line
			(start -0.5 0.25)
			(end 0.498 0.25)
			(stroke
				(width 0.15)
				(type solid)
			)
			(layer "B.Fab")
		)
		(fp_line
			(start 0.498 0.25)
			(end 0.498 -0.248)
			(stroke
				(width 0.15)
				(type solid)
			)
			(layer "B.Fab")
		)
		(fp_line
			(start -0.5 -0.248)
			(end -0.5 0.25)
			(stroke
				(width 0.15)
				(type solid)
			)
			(layer "B.Fab")
		)
		(fp_line
			(start 0.498 -0.248)
			(end -0.5 -0.248)
			(stroke
				(width 0.15)
				(type solid)
			)
			(layer "B.Fab")
		)
		(fp_text user "Author: Antmicro"
			(at -0.9656 -5.569 90)
			(layer "B.Fab")
			(effects
				(font
					(size 0.7 0.7)
					(thickness 0.15)
				)
				(justify left bottom mirror)
			)
		)
		(fp_text user "${REFERENCE}"
			(at -0.9656 -3.169 90)
			(layer "B.Fab")
			(effects
				(font
					(size 0.7 0.7)
					(thickness 0.15)
				)
				(justify left bottom mirror)
			)
		)
		(fp_text user "License: Apache-2.0"
			(at -0.9656 -4.369 90)
			(layer "B.Fab")
			(effects
				(font
					(size 0.7 0.7)
					(thickness 0.15)
				)
				(justify left bottom mirror)
			)
		)
		(pad "1" smd roundrect
			(at -0.5 0 180)
			(size 0.6 0.6)
			(layers "B.Cu" "B.Mask" "B.Paste")
			(roundrect_rratio 0.25)
			(net 1 "GND")
			(pintype "passive")
		)
		(pad "2" smd roundrect
			(at 0.498 0 270)
			(size 0.6 0.6)
			(layers "B.Cu" "B.Mask" "B.Paste")
			(roundrect_rratio 0.25)
			(net 553 "+0V85")
			(pintype "passive")
		)
	)
	(footprint "antmicro-footprints:R_0402_1005Metric"
		(layer "B.Cu")
		(at 219.91 151.85 180)
		(descr "Resistor SMD 0402")
		(tags "resistor SMD 0402")
		(property "Reference" "R5"
			(at -2.51 -0.48 0)
			(layer "B.SilkS")
			(effects
				(font
					(size 0.7 0.7)
					(thickness 0.15)
				)
				(justify left bottom mirror)
			)
		)
		(property "Value" "R_4k7_0402"
			(at 6.885407 -0.258797 0)
			(layer "B.Fab")
			(effects
				(font
					(size 0.7 0.7)
					(thickness 0.15)
				)
				(justify left bottom mirror)
			)
		)
		(property "Datasheet" "https://www.bourns.com/docs/product-datasheets/cr.pdf"
			(at 0 0 180)
			(layer "F.Fab")
			(hide yes)
			(effects
				(font
					(size 1.27 1.27)
					(thickness 0.15)
				)
			)
		)
		(property "Manufacturer" "Bourns"
			(at 0 0 180)
			(unlocked yes)
			(layer "B.Fab")
			(hide yes)
			(effects
				(font
					(size 1 1)
					(thickness 0.15)
				)
				(justify mirror)
			)
		)
		(property "MPN" "CR0402-FX-4701GLF"
			(at 0 0 180)
			(unlocked yes)
			(layer "B.Fab")
			(hide yes)
			(effects
				(font
					(size 1 1)
					(thickness 0.15)
				)
				(justify mirror)
			)
		)
		(property "Val" "4k7"
			(at 0 0 180)
			(unlocked yes)
			(layer "B.Fab")
			(hide yes)
			(effects
				(font
					(size 1 1)
					(thickness 0.15)
				)
				(justify mirror)
			)
		)
		(property "License" "Apache-2.0"
			(at 0 0 180)
			(unlocked yes)
			(layer "B.Fab")
			(hide yes)
			(effects
				(font
					(size 1 1)
					(thickness 0.15)
				)
				(justify mirror)
			)
		)
		(property "Author" "Antmicro"
			(at 0 0 180)
			(unlocked yes)
			(layer "B.Fab")
			(hide yes)
			(effects
				(font
					(size 1 1)
					(thickness 0.15)
				)
				(justify mirror)
			)
		)
		(property "Tolerance" "1%"
			(at 0 0 180)
			(unlocked yes)
			(layer "B.Fab")
			(hide yes)
			(effects
				(font
					(size 1 1)
					(thickness 0.15)
				)
				(justify mirror)
			)
		)
		(sheetname "/HyperRAM + QSPI Flash/")
		(sheetfile "hyperram-flash.kicad_sch")
		(attr smd)
		(fp_rect
			(start -0.925 0.47)
			(end 0.925 -0.47)
			(stroke
				(width 0.05)
				(type default)
			)
			(fill no)
			(layer "B.CrtYd")
		)
		(fp_rect
			(start -0.5 0.25)
			(end 0.5 -0.25)
			(stroke
				(width 0.15)
				(type solid)
			)
			(fill no)
			(layer "B.Fab")
		)
		(fp_text user "Author: Antmicro"
			(at -0.95 -4.169 0)
			(layer "B.Fab")
			(effects
				(font
					(size 0.7 0.7)
					(thickness 0.15)
				)
				(justify left bottom mirror)
			)
		)
		(fp_text user "${REFERENCE}"
			(at -0.95 -3.168 0)
			(layer "B.Fab")
			(effects
				(font
					(size 0.7 0.7)
					(thickness 0.15)
				)
				(justify left bottom mirror)
			)
		)
		(fp_text user "License: Apache-2.0"
			(at -0.95 -5.169 0)
			(layer "B.Fab")
			(effects
				(font
					(size 0.7 0.7)
					(thickness 0.15)
				)
				(justify left bottom mirror)
			)
		)
		(pad "1" smd roundrect
			(at -0.48 0 180)
			(size 0.59 0.64)
			(layers "B.Cu" "B.Mask" "B.Paste")
			(roundrect_rratio 0.25)
			(net 797 "+1V8")
			(pintype "passive")
		)
		(pad "2" smd roundrect
			(at 0.48 0 180)
			(size 0.59 0.64)
			(layers "B.Cu" "B.Mask" "B.Paste")
			(roundrect_rratio 0.25)
			(net 280 "/HyperRAM + QSPI Flash/IO2")
			(pintype "passive")
		)
	)
	(footprint "antmicro-footprints:C_0402_1005Metric_EIA"
		(layer "B.Cu")
		(at 197.5 145 180)
		(descr "Capacitor SMD 0402 (1005 Metric), square (rectangular) end terminal, IPC_7351 nominal, (Body size source: IPC-SM-782 page 76, https://www.pcb-3d.com/wordpress/wp-content/uploads/ipc-sm-782a_amendment_1_and_2.pdf)")
		(tags "capacitor 0402")
		(property "Reference" "C60"
			(at -3.05 -0.425 0)
			(layer "B.SilkS")
			(effects
				(font
					(size 0.7 0.7)
					(thickness 0.15)
				)
				(justify left bottom mirror)
			)
		)
		(property "Value" "C_100n_0402"
			(at 0 -1.169 0)
			(layer "B.Fab")
			(effects
				(font
					(size 0.7 0.7)
					(thickness 0.15)
				)
				(justify left bottom mirror)
			)
		)
		(property "Datasheet" "https://www.murata.com/products/productdetail?partno=GRM155R61H104KE14%23"
			(at 0 0 180)
			(layer "F.Fab")
			(hide yes)
			(effects
				(font
					(size 1.27 1.27)
					(thickness 0.15)
				)
			)
		)
		(property "MPN" "GRM155R61H104KE14D"
			(at 0 0 180)
			(unlocked yes)
			(layer "B.Fab")
			(hide yes)
			(effects
				(font
					(size 1 1)
					(thickness 0.15)
				)
				(justify mirror)
			)
		)
		(property "Manufacturer" "Murata"
			(at 0 0 180)
			(unlocked yes)
			(layer "B.Fab")
			(hide yes)
			(effects
				(font
					(size 1 1)
					(thickness 0.15)
				)
				(justify mirror)
			)
		)
		(property "License" "Apache-2.0"
			(at 0 0 180)
			(unlocked yes)
			(layer "B.Fab")
			(hide yes)
			(effects
				(font
					(size 1 1)
					(thickness 0.15)
				)
				(justify mirror)
			)
		)
		(property "Author" "Antmicro"
			(at 0 0 180)
			(unlocked yes)
			(layer "B.Fab")
			(hide yes)
			(effects
				(font
					(size 1 1)
					(thickness 0.15)
				)
				(justify mirror)
			)
		)
		(property "Val" "100n"
			(at 0 0 180)
			(unlocked yes)
			(layer "B.Fab")
			(hide yes)
			(effects
				(font
					(size 1 1)
					(thickness 0.15)
				)
				(justify mirror)
			)
		)
		(property "Voltage" "50V"
			(at 0 0 180)
			(unlocked yes)
			(layer "B.Fab")
			(hide yes)
			(effects
				(font
					(size 1 1)
					(thickness 0.15)
				)
				(justify mirror)
			)
		)
		(property "Dielectric" "X5R"
			(at 0 0 180)
			(unlocked yes)
			(layer "B.Fab")
			(hide yes)
			(effects
				(font
					(size 1 1)
					(thickness 0.15)
				)
				(justify mirror)
			)
		)
		(sheetname "/FPGA power/")
		(sheetfile "fpga-power.kicad_sch")
		(attr smd)
		(fp_rect
			(start -0.95 0.45)
			(end 0.95 -0.45)
			(stroke
				(width 0.05)
				(type default)
			)
			(fill no)
			(layer "B.CrtYd")
		)
		(fp_line
			(start 0.498 0.25)
			(end 0.498 -0.248)
			(stroke
				(width 0.15)
				(type solid)
			)
			(layer "B.Fab")
		)
		(fp_line
			(start 0.498 -0.248)
			(end -0.5 -0.248)
			(stroke
				(width 0.15)
				(type solid)
			)
			(layer "B.Fab")
		)
		(fp_line
			(start -0.5 0.25)
			(end 0.498 0.25)
			(stroke
				(width 0.15)
				(type solid)
			)
			(layer "B.Fab")
		)
		(fp_line
			(start -0.5 -0.248)
			(end -0.5 0.25)
			(stroke
				(width 0.15)
				(type solid)
			)
			(layer "B.Fab")
		)
		(fp_text user "License: Apache-2.0"
			(at -0.9656 -4.369 0)
			(layer "B.Fab")
			(effects
				(font
					(size 0.7 0.7)
					(thickness 0.15)
				)
				(justify left bottom mirror)
			)
		)
		(fp_text user "${REFERENCE}"
			(at -0.9656 -3.169 0)
			(layer "B.Fab")
			(effects
				(font
					(size 0.7 0.7)
					(thickness 0.15)
				)
				(justify left bottom mirror)
			)
		)
		(fp_text user "Author: Antmicro"
			(at -0.9656 -5.569 0)
			(layer "B.Fab")
			(effects
				(font
					(size 0.7 0.7)
					(thickness 0.15)
				)
				(justify left bottom mirror)
			)
		)
		(pad "1" smd roundrect
			(at -0.5 0 90)
			(size 0.6 0.6)
			(layers "B.Cu" "B.Mask" "B.Paste")
			(roundrect_rratio 0.25)
			(net 1 "GND")
			(pintype "passive")
		)
		(pad "2" smd roundrect
			(at 0.498 0 180)
			(size 0.6 0.6)
			(layers "B.Cu" "B.Mask" "B.Paste")
			(roundrect_rratio 0.25)
			(net 687 "VDDQ")
			(pintype "passive")
		)
	)
	(footprint "antmicro-footprints:C_0402_1005Metric_EIA"
		(layer "B.Cu")
		(at 191 156.5 -90)
		(descr "Capacitor SMD 0402 (1005 Metric), square (rectangular) end terminal, IPC_7351 nominal, (Body size source: IPC-SM-782 page 76, https://www.pcb-3d.com/wordpress/wp-content/uploads/ipc-sm-782a_amendment_1_and_2.pdf)")
		(tags "capacitor 0402")
		(property "Reference" "C67"
			(at -12.15 30.7 90)
			(layer "B.SilkS")
			(effects
				(font
					(size 0.7 0.7)
					(thickness 0.15)
				)
				(justify left bottom mirror)
			)
		)
		(property "Value" "C_10u_10V_0402"
			(at 0 -1.169 90)
			(layer "B.Fab")
			(effects
				(font
					(size 0.7 0.7)
					(thickness 0.15)
				)
				(justify left bottom mirror)
			)
		)
		(property "Datasheet" "https://www.murata.com/products/productdetail?partno=GRM155R61A106ME11%23"
			(at 0 0 270)
			(layer "F.Fab")
			(hide yes)
			(effects
				(font
					(size 1.27 1.27)
					(thickness 0.15)
				)
			)
		)
		(property "MPN" "GRM155R61A106ME11D"
			(at 0 0 270)
			(unlocked yes)
			(layer "B.Fab")
			(hide yes)
			(effects
				(font
					(size 1 1)
					(thickness 0.15)
				)
				(justify mirror)
			)
		)
		(property "Manufacturer" "Murata"
			(at 0 0 270)
			(unlocked yes)
			(layer "B.Fab")
			(hide yes)
			(effects
				(font
					(size 1 1)
					(thickness 0.15)
				)
				(justify mirror)
			)
		)
		(property "License" "Apache-2.0"
			(at 0 0 270)
			(unlocked yes)
			(layer "B.Fab")
			(hide yes)
			(effects
				(font
					(size 1 1)
					(thickness 0.15)
				)
				(justify mirror)
			)
		)
		(property "Author" "Antmicro"
			(at 0 0 270)
			(unlocked yes)
			(layer "B.Fab")
			(hide yes)
			(effects
				(font
					(size 1 1)
					(thickness 0.15)
				)
				(justify mirror)
			)
		)
		(property "Val" "10u"
			(at 0 0 270)
			(unlocked yes)
			(layer "B.Fab")
			(hide yes)
			(effects
				(font
					(size 1 1)
					(thickness 0.15)
				)
				(justify mirror)
			)
		)
		(property "Voltage" "10V"
			(at 0 0 270)
			(unlocked yes)
			(layer "B.Fab")
			(hide yes)
			(effects
				(font
					(size 1 1)
					(thickness 0.15)
				)
				(justify mirror)
			)
		)
		(property "Dielectric" "X5R"
			(at 0 0 270)
			(unlocked yes)
			(layer "B.Fab")
			(hide yes)
			(effects
				(font
					(size 1 1)
					(thickness 0.15)
				)
				(justify mirror)
			)
		)
		(sheetname "/FPGA power/")
		(sheetfile "fpga-power.kicad_sch")
		(attr smd)
		(fp_rect
			(start -0.95 0.45)
			(end 0.95 -0.45)
			(stroke
				(width 0.05)
				(type default)
			)
			(fill no)
			(layer "B.CrtYd")
		)
		(fp_line
			(start -0.5 0.25)
			(end 0.498 0.25)
			(stroke
				(width 0.15)
				(type solid)
			)
			(layer "B.Fab")
		)
		(fp_line
			(start 0.498 0.25)
			(end 0.498 -0.248)
			(stroke
				(width 0.15)
				(type solid)
			)
			(layer "B.Fab")
		)
		(fp_line
			(start -0.5 -0.248)
			(end -0.5 0.25)
			(stroke
				(width 0.15)
				(type solid)
			)
			(layer "B.Fab")
		)
		(fp_line
			(start 0.498 -0.248)
			(end -0.5 -0.248)
			(stroke
				(width 0.15)
				(type solid)
			)
			(layer "B.Fab")
		)
		(fp_text user "License: Apache-2.0"
			(at -0.9656 -4.369 90)
			(layer "B.Fab")
			(effects
				(font
					(size 0.7 0.7)
					(thickness 0.15)
				)
				(justify left bottom mirror)
			)
		)
		(fp_text user "Author: Antmicro"
			(at -0.9656 -5.569 90)
			(layer "B.Fab")
			(effects
				(font
					(size 0.7 0.7)
					(thickness 0.15)
				)
				(justify left bottom mirror)
			)
		)
		(fp_text user "${REFERENCE}"
			(at -0.9656 -3.169 90)
			(layer "B.Fab")
			(effects
				(font
					(size 0.7 0.7)
					(thickness 0.15)
				)
				(justify left bottom mirror)
			)
		)
		(pad "1" smd roundrect
			(at -0.5 0 180)
			(size 0.6 0.6)
			(layers "B.Cu" "B.Mask" "B.Paste")
			(roundrect_rratio 0.25)
			(net 1 "GND")
			(pintype "passive")
		)
		(pad "2" smd roundrect
			(at 0.498 0 270)
			(size 0.6 0.6)
			(layers "B.Cu" "B.Mask" "B.Paste")
			(roundrect_rratio 0.25)
			(net 553 "+0V85")
			(pintype "passive")
		)
	)
	(footprint "antmicro-footprints:C_0402_1005Metric"
		(layer "B.Cu")
		(at 204.75 138.5245 90)
		(descr "Capacitor SMD 0402")
		(tags "capacitor SMD 0402")
		(property "Reference" "C332"
			(at -2.3755 -0.15 90)
			(layer "B.SilkS")
			(effects
				(font
					(size 0.7 0.7)
					(thickness 0.15)
				)
				(justify mirror)
			)
		)
		(property "Value" "C_100n_0402"
			(at -1.022927 -2.155213 90)
			(layer "B.Fab")
			(effects
				(font
					(size 0.7 0.7)
					(thickness 0.15)
				)
				(justify right top mirror)
			)
		)
		(property "Datasheet" "https://www.murata.com/products/productdetail?partno=GRM155R61H104KE14%23"
			(at 0 0 90)
			(layer "B.Fab")
			(hide yes)
			(effects
				(font
					(size 1.27 1.27)
					(thickness 0.15)
				)
				(justify mirror)
			)
		)
		(property "Manufacturer" "Murata"
			(at 0 0 270)
			(unlocked yes)
			(layer "B.Fab")
			(hide yes)
			(effects
				(font
					(size 1 1)
					(thickness 0.15)
				)
				(justify mirror)
			)
		)
		(property "MPN" "GRM155R61H104KE14D"
			(at 0 0 270)
			(unlocked yes)
			(layer "B.Fab")
			(hide yes)
			(effects
				(font
					(size 1 1)
					(thickness 0.15)
				)
				(justify mirror)
			)
		)
		(property "Val" "100n"
			(at 0 0 270)
			(unlocked yes)
			(layer "B.Fab")
			(hide yes)
			(effects
				(font
					(size 1 1)
					(thickness 0.15)
				)
				(justify mirror)
			)
		)
		(property "License" "Apache-2.0"
			(at 0 0 270)
			(unlocked yes)
			(layer "B.Fab")
			(hide yes)
			(effects
				(font
					(size 1 1)
					(thickness 0.15)
				)
				(justify mirror)
			)
		)
		(property "Author" "Antmicro"
			(at 0 0 270)
			(unlocked yes)
			(layer "B.Fab")
			(hide yes)
			(effects
				(font
					(size 1 1)
					(thickness 0.15)
				)
				(justify mirror)
			)
		)
		(property "Voltage" "50V"
			(at 0 0 270)
			(unlocked yes)
			(layer "B.Fab")
			(hide yes)
			(effects
				(font
					(size 1 1)
					(thickness 0.15)
				)
				(justify mirror)
			)
		)
		(property "Dielectric" "X5R"
			(at 0 0 270)
			(unlocked yes)
			(layer "B.Fab")
			(hide yes)
			(effects
				(font
					(size 1 1)
					(thickness 0.15)
				)
				(justify mirror)
			)
		)
		(sheetname "/Supply/")
		(sheetfile "supply.kicad_sch")
		(attr smd)
		(fp_rect
			(start -0.925 0.47)
			(end 0.925 -0.47)
			(stroke
				(width 0.05)
				(type default)
			)
			(fill no)
			(layer "B.CrtYd")
		)
		(fp_line
			(start 0.504 -0.248)
			(end -0.494 -0.248)
			(stroke
				(width 0.15)
				(type solid)
			)
			(layer "B.Fab")
		)
		(fp_line
			(start -0.494 -0.248)
			(end -0.494 0.25)
			(stroke
				(width 0.15)
				(type solid)
			)
			(layer "B.Fab")
		)
		(fp_line
			(start 0.504 0.25)
			(end 0.504 -0.248)
			(stroke
				(width 0.15)
				(type solid)
			)
			(layer "B.Fab")
		)
		(fp_line
			(start -0.494 0.25)
			(end 0.504 0.25)
			(stroke
				(width 0.15)
				(type solid)
			)
			(layer "B.Fab")
		)
		(fp_text user "${REFERENCE}"
			(at -0.939 -4.599 90)
			(layer "B.Fab")
			(effects
				(font
					(size 0.7 0.7)
					(thickness 0.15)
				)
				(justify right top mirror)
			)
		)
		(fp_text user "License: Apache-2.0"
			(at -0.939 -5.799 90)
			(layer "B.Fab")
			(effects
				(font
					(size 0.7 0.7)
					(thickness 0.15)
				)
				(justify right top mirror)
			)
		)
		(fp_text user "Author: Antmicro"
			(at -0.939 -3.399 90)
			(layer "B.Fab")
			(effects
				(font
					(size 0.7 0.7)
					(thickness 0.15)
				)
				(justify right top mirror)
			)
		)
		(pad "1" smd roundrect
			(at -0.48 0 90)
			(size 0.59 0.64)
			(layers "B.Cu" "B.Mask" "B.Paste")
			(roundrect_rratio 0.25)
			(net 1 "GND")
			(pintype "passive")
		)
		(pad "2" smd roundrect
			(at 0.48 0 90)
			(size 0.59 0.64)
			(layers "B.Cu" "B.Mask" "B.Paste")
			(roundrect_rratio 0.25)
			(net 825 "DAC_VREF")
			(pintype "passive")
		)
	)
	(footprint "antmicro-footprints:C_0402_1005Metric_EIA"
		(layer "B.Cu")
		(at 181.5 150)
		(descr "Capacitor SMD 0402 (1005 Metric), square (rectangular) end terminal, IPC_7351 nominal, (Body size source: IPC-SM-782 page 76, https://www.pcb-3d.com/wordpress/wp-content/uploads/ipc-sm-782a_amendment_1_and_2.pdf)")
		(tags "capacitor 0402")
		(property "Reference" "C23"
			(at -32.125 -10.325 0)
			(layer "B.SilkS")
			(effects
				(font
					(size 0.7 0.7)
					(thickness 0.15)
				)
				(justify right bottom mirror)
			)
		)
		(property "Value" "C_10u_10V_0402"
			(at 0 -1.169 0)
			(layer "B.Fab")
			(effects
				(font
					(size 0.7 0.7)
					(thickness 0.15)
				)
				(justify right bottom mirror)
			)
		)
		(property "Datasheet" "https://www.murata.com/products/productdetail?partno=GRM155R61A106ME11%23"
			(at 0 0 0)
			(layer "F.Fab")
			(hide yes)
			(effects
				(font
					(size 1.27 1.27)
					(thickness 0.15)
				)
			)
		)
		(property "MPN" "GRM155R61A106ME11D"
			(at 0 0 0)
			(unlocked yes)
			(layer "B.Fab")
			(hide yes)
			(effects
				(font
					(size 1 1)
					(thickness 0.15)
				)
				(justify mirror)
			)
		)
		(property "Manufacturer" "Murata"
			(at 0 0 0)
			(unlocked yes)
			(layer "B.Fab")
			(hide yes)
			(effects
				(font
					(size 1 1)
					(thickness 0.15)
				)
				(justify mirror)
			)
		)
		(property "License" "Apache-2.0"
			(at 0 0 0)
			(unlocked yes)
			(layer "B.Fab")
			(hide yes)
			(effects
				(font
					(size 1 1)
					(thickness 0.15)
				)
				(justify mirror)
			)
		)
		(property "Author" "Antmicro"
			(at 0 0 0)
			(unlocked yes)
			(layer "B.Fab")
			(hide yes)
			(effects
				(font
					(size 1 1)
					(thickness 0.15)
				)
				(justify mirror)
			)
		)
		(property "Val" "10u"
			(at 0 0 0)
			(unlocked yes)
			(layer "B.Fab")
			(hide yes)
			(effects
				(font
					(size 1 1)
					(thickness 0.15)
				)
				(justify mirror)
			)
		)
		(property "Voltage" "10V"
			(at 0 0 0)
			(unlocked yes)
			(layer "B.Fab")
			(hide yes)
			(effects
				(font
					(size 1 1)
					(thickness 0.15)
				)
				(justify mirror)
			)
		)
		(property "Dielectric" "X5R"
			(at 0 0 0)
			(unlocked yes)
			(layer "B.Fab")
			(hide yes)
			(effects
				(font
					(size 1 1)
					(thickness 0.15)
				)
				(justify mirror)
			)
		)
		(sheetname "/FPGA power/")
		(sheetfile "fpga-power.kicad_sch")
		(attr smd)
		(fp_rect
			(start -0.95 0.45)
			(end 0.95 -0.45)
			(stroke
				(width 0.05)
				(type default)
			)
			(fill no)
			(layer "B.CrtYd")
		)
		(fp_line
			(start -0.5 -0.248)
			(end -0.5 0.25)
			(stroke
				(width 0.15)
				(type solid)
			)
			(layer "B.Fab")
		)
		(fp_line
			(start -0.5 0.25)
			(end 0.498 0.25)
			(stroke
				(width 0.15)
				(type solid)
			)
			(layer "B.Fab")
		)
		(fp_line
			(start 0.498 -0.248)
			(end -0.5 -0.248)
			(stroke
				(width 0.15)
				(type solid)
			)
			(layer "B.Fab")
		)
		(fp_line
			(start 0.498 0.25)
			(end 0.498 -0.248)
			(stroke
				(width 0.15)
				(type solid)
			)
			(layer "B.Fab")
		)
		(fp_text user "Author: Antmicro"
			(at -0.9656 -5.569 180)
			(layer "B.Fab")
			(effects
				(font
					(size 0.7 0.7)
					(thickness 0.15)
				)
				(justify left bottom mirror)
			)
		)
		(fp_text user "${REFERENCE}"
			(at -0.9656 -3.169 180)
			(layer "B.Fab")
			(effects
				(font
					(size 0.7 0.7)
					(thickness 0.15)
				)
				(justify left bottom mirror)
			)
		)
		(fp_text user "License: Apache-2.0"
			(at -0.9656 -4.369 180)
			(layer "B.Fab")
			(effects
				(font
					(size 0.7 0.7)
					(thickness 0.15)
				)
				(justify left bottom mirror)
			)
		)
		(pad "1" smd roundrect
			(at -0.5 0 270)
			(size 0.6 0.6)
			(layers "B.Cu" "B.Mask" "B.Paste")
			(roundrect_rratio 0.25)
			(net 1 "GND")
			(pintype "passive")
		)
		(pad "2" smd roundrect
			(at 0.498 0)
			(size 0.6 0.6)
			(layers "B.Cu" "B.Mask" "B.Paste")
			(roundrect_rratio 0.25)
			(net 151 "+3V3")
			(pintype "passive")
		)
	)
	(footprint "antmicro-footprints:R_0402_1005Metric"
		(layer "B.Cu")
		(at 238.424499 186.849 180)
		(descr "Resistor SMD 0402")
		(tags "resistor SMD 0402")
		(property "Reference" "R175"
			(at -3.95 -0.5 0)
			(layer "B.SilkS")
			(effects
				(font
					(size 0.7 0.7)
					(thickness 0.15)
				)
				(justify left bottom mirror)
			)
		)
		(property "Value" "R_0R_0402"
			(at -1.011843 -1.772047 0)
			(layer "B.Fab")
			(effects
				(font
					(size 0.7 0.7)
					(thickness 0.15)
				)
				(justify left bottom mirror)
			)
		)
		(property "Datasheet" "https://industrial.panasonic.com/cdbs/www-data/pdf/RDA0000/AOA0000C301.pdf"
			(at 0 0 180)
			(layer "F.Fab")
			(hide yes)
			(effects
				(font
					(size 1.27 1.27)
					(thickness 0.15)
				)
			)
		)
		(property "Manufacturer" "Panasonic"
			(at 0 0 180)
			(unlocked yes)
			(layer "B.Fab")
			(hide yes)
			(effects
				(font
					(size 1 1)
					(thickness 0.15)
				)
				(justify mirror)
			)
		)
		(property "MPN" "ERJ2GE0R00X"
			(at 0 0 180)
			(unlocked yes)
			(layer "B.Fab")
			(hide yes)
			(effects
				(font
					(size 1 1)
					(thickness 0.15)
				)
				(justify mirror)
			)
		)
		(property "Val" "0R"
			(at 0 0 180)
			(unlocked yes)
			(layer "B.Fab")
			(hide yes)
			(effects
				(font
					(size 1 1)
					(thickness 0.15)
				)
				(justify mirror)
			)
		)
		(property "License" "Apache-2.0"
			(at 0 0 180)
			(unlocked yes)
			(layer "B.Fab")
			(hide yes)
			(effects
				(font
					(size 1 1)
					(thickness 0.15)
				)
				(justify mirror)
			)
		)
		(property "Author" "Antmicro"
			(at 0 0 180)
			(unlocked yes)
			(layer "B.Fab")
			(hide yes)
			(effects
				(font
					(size 1 1)
					(thickness 0.15)
				)
				(justify mirror)
			)
		)
		(property "Tolerance" "~"
			(at 0 0 180)
			(unlocked yes)
			(layer "B.Fab")
			(hide yes)
			(effects
				(font
					(size 1 1)
					(thickness 0.15)
				)
				(justify mirror)
			)
		)
		(property "Current" "1A"
			(at 0 0 180)
			(unlocked yes)
			(layer "B.Fab")
			(hide yes)
			(effects
				(font
					(size 1 1)
					(thickness 0.15)
				)
				(justify mirror)
			)
		)
		(sheetname "/I^{2}C + I3C/")
		(sheetfile "i2c.kicad_sch")
		(attr smd exclude_from_bom dnp)
		(fp_rect
			(start -0.925 0.47)
			(end 0.925 -0.47)
			(stroke
				(width 0.05)
				(type default)
			)
			(fill no)
			(layer "B.CrtYd")
		)
		(fp_rect
			(start -0.5 0.25)
			(end 0.5 -0.25)
			(stroke
				(width 0.15)
				(type solid)
			)
			(fill no)
			(layer "B.Fab")
		)
		(fp_text user "Author: Antmicro"
			(at -0.95 -4.169 0)
			(layer "B.Fab")
			(effects
				(font
					(size 0.7 0.7)
					(thickness 0.15)
				)
				(justify left bottom mirror)
			)
		)
		(fp_text user "${REFERENCE}"
			(at -0.95 -3.168 0)
			(layer "B.Fab")
			(effects
				(font
					(size 0.7 0.7)
					(thickness 0.15)
				)
				(justify left bottom mirror)
			)
		)
		(fp_text user "License: Apache-2.0"
			(at -0.95 -5.169 0)
			(layer "B.Fab")
			(effects
				(font
					(size 0.7 0.7)
					(thickness 0.15)
				)
				(justify left bottom mirror)
			)
		)
		(pad "1" smd roundrect
			(at -0.48 0 180)
			(size 0.59 0.64)
			(layers "B.Cu" "B.Mask" "B.Paste")
			(roundrect_rratio 0.25)
			(net 533 "/I^{2}C + I3C/PWR.SDA")
			(pintype "passive")
		)
		(pad "2" smd roundrect
			(at 0.48 0 180)
			(size 0.59 0.64)
			(layers "B.Cu" "B.Mask" "B.Paste")
			(roundrect_rratio 0.25)
			(net 746 "/FPGA Config/FPGA_PWR.SDA")
			(pintype "passive")
		)
	)
	(footprint "antmicro-footprints:R_0402_1005Metric"
		(layer "B.Cu")
		(at 110.7 102.1 -90)
		(descr "Resistor SMD 0402")
		(tags "resistor SMD 0402")
		(property "Reference" "R41"
			(at -1.122484 0.772697 90)
			(layer "B.SilkS")
			(effects
				(font
					(size 0.7 0.7)
					(thickness 0.15)
				)
				(justify left bottom mirror)
			)
		)
		(property "Value" "R_330R_0402"
			(at -1.011843 -1.772047 90)
			(layer "B.Fab")
			(effects
				(font
					(size 0.7 0.7)
					(thickness 0.15)
				)
				(justify left bottom mirror)
			)
		)
		(property "Datasheet" "https://www.bourns.com/docs/product-datasheets/cr.pdf"
			(at 0 0 270)
			(layer "F.Fab")
			(hide yes)
			(effects
				(font
					(size 1.27 1.27)
					(thickness 0.15)
				)
			)
		)
		(property "Manufacturer" "Bourns"
			(at 0 0 270)
			(unlocked yes)
			(layer "B.Fab")
			(hide yes)
			(effects
				(font
					(size 1 1)
					(thickness 0.15)
				)
				(justify mirror)
			)
		)
		(property "MPN" "CR0402-FX-3300GLF"
			(at 0 0 270)
			(unlocked yes)
			(layer "B.Fab")
			(hide yes)
			(effects
				(font
					(size 1 1)
					(thickness 0.15)
				)
				(justify mirror)
			)
		)
		(property "Val" "330R"
			(at 0 0 270)
			(unlocked yes)
			(layer "B.Fab")
			(hide yes)
			(effects
				(font
					(size 1 1)
					(thickness 0.15)
				)
				(justify mirror)
			)
		)
		(property "License" "Apache-2.0"
			(at 0 0 270)
			(unlocked yes)
			(layer "B.Fab")
			(hide yes)
			(effects
				(font
					(size 1 1)
					(thickness 0.15)
				)
				(justify mirror)
			)
		)
		(property "Author" "Antmicro"
			(at 0 0 270)
			(unlocked yes)
			(layer "B.Fab")
			(hide yes)
			(effects
				(font
					(size 1 1)
					(thickness 0.15)
				)
				(justify mirror)
			)
		)
		(property "Tolerance" "1%"
			(at 0 0 270)
			(unlocked yes)
			(layer "B.Fab")
			(hide yes)
			(effects
				(font
					(size 1 1)
					(thickness 0.15)
				)
				(justify mirror)
			)
		)
		(sheetname "/FPGA banks HD/")
		(sheetfile "fpga-hd-banks.kicad_sch")
		(attr smd)
		(fp_rect
			(start -0.925 0.47)
			(end 0.925 -0.47)
			(stroke
				(width 0.05)
				(type default)
			)
			(fill no)
			(layer "B.CrtYd")
		)
		(fp_rect
			(start -0.5 0.25)
			(end 0.5 -0.25)
			(stroke
				(width 0.15)
				(type solid)
			)
			(fill no)
			(layer "B.Fab")
		)
		(fp_text user "${REFERENCE}"
			(at -0.95 -3.168 90)
			(layer "B.Fab")
			(effects
				(font
					(size 0.7 0.7)
					(thickness 0.15)
				)
				(justify left bottom mirror)
			)
		)
		(fp_text user "Author: Antmicro"
			(at -0.95 -4.169 90)
			(layer "B.Fab")
			(effects
				(font
					(size 0.7 0.7)
					(thickness 0.15)
				)
				(justify left bottom mirror)
			)
		)
		(fp_text user "License: Apache-2.0"
			(at -0.95 -5.169 90)
			(layer "B.Fab")
			(effects
				(font
					(size 0.7 0.7)
					(thickness 0.15)
				)
				(justify left bottom mirror)
			)
		)
		(pad "1" smd roundrect
			(at -0.48 0 270)
			(size 0.59 0.64)
			(layers "B.Cu" "B.Mask" "B.Paste")
			(roundrect_rratio 0.25)
			(net 230 "Net-(D5-A)")
			(pintype "passive")
		)
		(pad "2" smd roundrect
			(at 0.48 0 270)
			(size 0.59 0.64)
			(layers "B.Cu" "B.Mask" "B.Paste")
			(roundrect_rratio 0.25)
			(net 273 "Net-(Q5-D)")
			(pintype "passive")
		)
	)
	(footprint "antmicro-footprints:C_0603_1608Metric"
		(layer "B.Cu")
		(at 188.5 156.25 90)
		(descr "Capacitor SMD 0603")
		(tags "capacitor 0603")
		(property "Reference" "C31"
			(at 9.7 -30.8 90)
			(layer "B.SilkS")
			(effects
				(font
					(size 0.7 0.7)
					(thickness 0.15)
				)
				(justify right bottom mirror)
			)
		)
		(property "Value" "C_47u_0603"
			(at -1.42757 -1.770288 90)
			(layer "B.Fab")
			(effects
				(font
					(size 0.7 0.7)
					(thickness 0.15)
				)
				(justify right bottom mirror)
			)
		)
		(property "Datasheet" "https://www.murata.com/products/productdetail?partno=GRM188R60J476ME15%23"
			(at 0 0 90)
			(layer "F.Fab")
			(hide yes)
			(effects
				(font
					(size 1.27 1.27)
					(thickness 0.15)
				)
			)
		)
		(property "Manufacturer" "Murata"
			(at 0 0 90)
			(unlocked yes)
			(layer "B.Fab")
			(hide yes)
			(effects
				(font
					(size 1 1)
					(thickness 0.15)
				)
				(justify mirror)
			)
		)
		(property "MPN" "GRM188R60J476ME15D"
			(at 0 0 90)
			(unlocked yes)
			(layer "B.Fab")
			(hide yes)
			(effects
				(font
					(size 1 1)
					(thickness 0.15)
				)
				(justify mirror)
			)
		)
		(property "Val" "47u"
			(at 0 0 90)
			(unlocked yes)
			(layer "B.Fab")
			(hide yes)
			(effects
				(font
					(size 1 1)
					(thickness 0.15)
				)
				(justify mirror)
			)
		)
		(property "License" "Apache-2.0"
			(at 0 0 90)
			(unlocked yes)
			(layer "B.Fab")
			(hide yes)
			(effects
				(font
					(size 1 1)
					(thickness 0.15)
				)
				(justify mirror)
			)
		)
		(property "Author" "Antmicro"
			(at 0 0 90)
			(unlocked yes)
			(layer "B.Fab")
			(hide yes)
			(effects
				(font
					(size 1 1)
					(thickness 0.15)
				)
				(justify mirror)
			)
		)
		(property "Voltage" ""
			(at 0 0 90)
			(unlocked yes)
			(layer "B.Fab")
			(hide yes)
			(effects
				(font
					(size 1 1)
					(thickness 0.15)
				)
				(justify mirror)
			)
		)
		(property "Dielectric" ""
			(at 0 0 90)
			(unlocked yes)
			(layer "B.Fab")
			(hide yes)
			(effects
				(font
					(size 1 1)
					(thickness 0.15)
				)
				(justify mirror)
			)
		)
		(sheetname "/FPGA power/")
		(sheetfile "fpga-power.kicad_sch")
		(attr smd)
		(fp_line
			(start -0.15 -0.4)
			(end 0.15 -0.4)
			(stroke
				(width 0.15)
				(type solid)
			)
			(layer "B.SilkS")
		)
		(fp_line
			(start -0.15 0.4)
			(end 0.15 0.4)
			(stroke
				(width 0.15)
				(type solid)
			)
			(layer "B.SilkS")
		)
		(fp_rect
			(start -1.25 0.65)
			(end 1.25 -0.65)
			(stroke
				(width 0.05)
				(type solid)
			)
			(fill no)
			(layer "B.CrtYd")
		)
		(fp_rect
			(start -0.8 0.4)
			(end 0.8 -0.4)
			(stroke
				(width 0.15)
				(type solid)
			)
			(fill no)
			(layer "B.Fab")
		)
		(fp_text user "License: Apache-2.0"
			(at -1.682 -5.895 270)
			(layer "B.Fab")
			(effects
				(font
					(size 0.7 0.7)
					(thickness 0.15)
				)
				(justify left bottom mirror)
			)
		)
		(fp_text user "Author: Antmicro"
			(at -1.682 -4.894 270)
			(layer "B.Fab")
			(effects
				(font
					(size 0.7 0.7)
					(thickness 0.15)
				)
				(justify left bottom mirror)
			)
		)
		(fp_text user "${REFERENCE}"
			(at -1.682 -3.895 270)
			(layer "B.Fab")
			(effects
				(font
					(size 0.7 0.7)
					(thickness 0.15)
				)
				(justify left bottom mirror)
			)
		)
		(pad "1" smd roundrect
			(at -0.7 0 90)
			(size 0.8 1)
			(layers "B.Cu" "B.Mask" "B.Paste")
			(roundrect_rratio 0.2)
			(net 573 "+1V8_MGTVCCAUX")
			(pintype "passive")
		)
		(pad "2" smd roundrect
			(at 0.7 0 90)
			(size 0.8 1)
			(layers "B.Cu" "B.Mask" "B.Paste")
			(roundrect_rratio 0.2)
			(net 1 "GND")
			(pintype "passive")
		)
	)
	(footprint "antmicro-footprints:R_0402_1005Metric"
		(layer "B.Cu")
		(at 113.4 102.1 -90)
		(descr "Resistor SMD 0402")
		(tags "resistor SMD 0402")
		(property "Reference" "R40"
			(at -1.122484 0.772697 90)
			(layer "B.SilkS")
			(effects
				(font
					(size 0.7 0.7)
					(thickness 0.15)
				)
				(justify left bottom mirror)
			)
		)
		(property "Value" "R_330R_0402"
			(at -1.011843 -1.772047 90)
			(layer "B.Fab")
			(effects
				(font
					(size 0.7 0.7)
					(thickness 0.15)
				)
				(justify left bottom mirror)
			)
		)
		(property "Datasheet" "https://www.bourns.com/docs/product-datasheets/cr.pdf"
			(at 0 0 270)
			(layer "F.Fab")
			(hide yes)
			(effects
				(font
					(size 1.27 1.27)
					(thickness 0.15)
				)
			)
		)
		(property "Manufacturer" "Bourns"
			(at 0 0 270)
			(unlocked yes)
			(layer "B.Fab")
			(hide yes)
			(effects
				(font
					(size 1 1)
					(thickness 0.15)
				)
				(justify mirror)
			)
		)
		(property "MPN" "CR0402-FX-3300GLF"
			(at 0 0 270)
			(unlocked yes)
			(layer "B.Fab")
			(hide yes)
			(effects
				(font
					(size 1 1)
					(thickness 0.15)
				)
				(justify mirror)
			)
		)
		(property "Val" "330R"
			(at 0 0 270)
			(unlocked yes)
			(layer "B.Fab")
			(hide yes)
			(effects
				(font
					(size 1 1)
					(thickness 0.15)
				)
				(justify mirror)
			)
		)
		(property "License" "Apache-2.0"
			(at 0 0 270)
			(unlocked yes)
			(layer "B.Fab")
			(hide yes)
			(effects
				(font
					(size 1 1)
					(thickness 0.15)
				)
				(justify mirror)
			)
		)
		(property "Author" "Antmicro"
			(at 0 0 270)
			(unlocked yes)
			(layer "B.Fab")
			(hide yes)
			(effects
				(font
					(size 1 1)
					(thickness 0.15)
				)
				(justify mirror)
			)
		)
		(property "Tolerance" "1%"
			(at 0 0 270)
			(unlocked yes)
			(layer "B.Fab")
			(hide yes)
			(effects
				(font
					(size 1 1)
					(thickness 0.15)
				)
				(justify mirror)
			)
		)
		(sheetname "/FPGA banks HD/")
		(sheetfile "fpga-hd-banks.kicad_sch")
		(attr smd)
		(fp_rect
			(start -0.925 0.47)
			(end 0.925 -0.47)
			(stroke
				(width 0.05)
				(type default)
			)
			(fill no)
			(layer "B.CrtYd")
		)
		(fp_rect
			(start -0.5 0.25)
			(end 0.5 -0.25)
			(stroke
				(width 0.15)
				(type solid)
			)
			(fill no)
			(layer "B.Fab")
		)
		(fp_text user "License: Apache-2.0"
			(at -0.95 -5.169 90)
			(layer "B.Fab")
			(effects
				(font
					(size 0.7 0.7)
					(thickness 0.15)
				)
				(justify left bottom mirror)
			)
		)
		(fp_text user "Author: Antmicro"
			(at -0.95 -4.169 90)
			(layer "B.Fab")
			(effects
				(font
					(size 0.7 0.7)
					(thickness 0.15)
				)
				(justify left bottom mirror)
			)
		)
		(fp_text user "${REFERENCE}"
			(at -0.95 -3.168 90)
			(layer "B.Fab")
			(effects
				(font
					(size 0.7 0.7)
					(thickness 0.15)
				)
				(justify left bottom mirror)
			)
		)
		(pad "1" smd roundrect
			(at -0.48 0 270)
			(size 0.59 0.64)
			(layers "B.Cu" "B.Mask" "B.Paste")
			(roundrect_rratio 0.25)
			(net 32 "Net-(D4-A)")
			(pintype "passive")
		)
		(pad "2" smd roundrect
			(at 0.48 0 270)
			(size 0.59 0.64)
			(layers "B.Cu" "B.Mask" "B.Paste")
			(roundrect_rratio 0.25)
			(net 272 "Net-(Q4-D)")
			(pintype "passive")
		)
	)
	(footprint "antmicro-footprints:C_0402_1005Metric_EIA"
		(layer "B.Cu")
		(at 186.002 150.501999 90)
		(descr "Capacitor SMD 0402 (1005 Metric), square (rectangular) end terminal, IPC_7351 nominal, (Body size source: IPC-SM-782 page 76, https://www.pcb-3d.com/wordpress/wp-content/uploads/ipc-sm-782a_amendment_1_and_2.pdf)")
		(tags "capacitor 0402")
		(property "Reference" "C39"
			(at 9.326999 -30.627 90)
			(layer "B.SilkS")
			(effects
				(font
					(size 0.7 0.7)
					(thickness 0.15)
				)
				(justify right bottom mirror)
			)
		)
		(property "Value" "C_1u_25V_0402"
			(at 0 -1.169 90)
			(layer "B.Fab")
			(effects
				(font
					(size 0.7 0.7)
					(thickness 0.15)
				)
				(justify right bottom mirror)
			)
		)
		(property "Datasheet" "https://www.murata.com/products/productdetail?partno=GRM155R61E105KE11%23"
			(at 0 0 90)
			(layer "F.Fab")
			(hide yes)
			(effects
				(font
					(size 1.27 1.27)
					(thickness 0.15)
				)
			)
		)
		(property "MPN" "GRM155R61E105KE11J"
			(at 0 0 90)
			(unlocked yes)
			(layer "B.Fab")
			(hide yes)
			(effects
				(font
					(size 1 1)
					(thickness 0.15)
				)
				(justify mirror)
			)
		)
		(property "Manufacturer" "Murata"
			(at 0 0 90)
			(unlocked yes)
			(layer "B.Fab")
			(hide yes)
			(effects
				(font
					(size 1 1)
					(thickness 0.15)
				)
				(justify mirror)
			)
		)
		(property "License" "Apache-2.0"
			(at 0 0 90)
			(unlocked yes)
			(layer "B.Fab")
			(hide yes)
			(effects
				(font
					(size 1 1)
					(thickness 0.15)
				)
				(justify mirror)
			)
		)
		(property "Author" "Antmicro"
			(at 0 0 90)
			(unlocked yes)
			(layer "B.Fab")
			(hide yes)
			(effects
				(font
					(size 1 1)
					(thickness 0.15)
				)
				(justify mirror)
			)
		)
		(property "Val" "1u"
			(at 0 0 90)
			(unlocked yes)
			(layer "B.Fab")
			(hide yes)
			(effects
				(font
					(size 1 1)
					(thickness 0.15)
				)
				(justify mirror)
			)
		)
		(property "Voltage" "25V"
			(at 0 0 90)
			(unlocked yes)
			(layer "B.Fab")
			(hide yes)
			(effects
				(font
					(size 1 1)
					(thickness 0.15)
				)
				(justify mirror)
			)
		)
		(property "Dielectric" "X5R"
			(at 0 0 90)
			(unlocked yes)
			(layer "B.Fab")
			(hide yes)
			(effects
				(font
					(size 1 1)
					(thickness 0.15)
				)
				(justify mirror)
			)
		)
		(sheetname "/FPGA power/")
		(sheetfile "fpga-power.kicad_sch")
		(attr smd)
		(fp_rect
			(start -0.95 0.45)
			(end 0.95 -0.45)
			(stroke
				(width 0.05)
				(type default)
			)
			(fill no)
			(layer "B.CrtYd")
		)
		(fp_line
			(start 0.498 -0.248)
			(end -0.5 -0.248)
			(stroke
				(width 0.15)
				(type solid)
			)
			(layer "B.Fab")
		)
		(fp_line
			(start -0.5 -0.248)
			(end -0.5 0.25)
			(stroke
				(width 0.15)
				(type solid)
			)
			(layer "B.Fab")
		)
		(fp_line
			(start 0.498 0.25)
			(end 0.498 -0.248)
			(stroke
				(width 0.15)
				(type solid)
			)
			(layer "B.Fab")
		)
		(fp_line
			(start -0.5 0.25)
			(end 0.498 0.25)
			(stroke
				(width 0.15)
				(type solid)
			)
			(layer "B.Fab")
		)
		(fp_text user "License: Apache-2.0"
			(at -0.9656 -4.369 270)
			(layer "B.Fab")
			(effects
				(font
					(size 0.7 0.7)
					(thickness 0.15)
				)
				(justify left bottom mirror)
			)
		)
		(fp_text user "${REFERENCE}"
			(at -0.9656 -3.169 270)
			(layer "B.Fab")
			(effects
				(font
					(size 0.7 0.7)
					(thickness 0.15)
				)
				(justify left bottom mirror)
			)
		)
		(fp_text user "Author: Antmicro"
			(at -0.9656 -5.569 270)
			(layer "B.Fab")
			(effects
				(font
					(size 0.7 0.7)
					(thickness 0.15)
				)
				(justify left bottom mirror)
			)
		)
		(pad "1" smd roundrect
			(at -0.5 0)
			(size 0.6 0.6)
			(layers "B.Cu" "B.Mask" "B.Paste")
			(roundrect_rratio 0.25)
			(net 1 "GND")
			(pintype "passive")
		)
		(pad "2" smd roundrect
			(at 0.498 0 90)
			(size 0.6 0.6)
			(layers "B.Cu" "B.Mask" "B.Paste")
			(roundrect_rratio 0.25)
			(net 553 "+0V85")
			(pintype "passive")
		)
	)
	(footprint "antmicro-footprints:C_0603_1608Metric"
		(layer "B.Cu")
		(at 188.5 148.3 -90)
		(descr "Capacitor SMD 0603")
		(tags "capacitor 0603")
		(property "Reference" "C11"
			(at -11.925 30.7 90)
			(layer "B.SilkS")
			(effects
				(font
					(size 0.7 0.7)
					(thickness 0.15)
				)
				(justify left bottom mirror)
			)
		)
		(property "Value" "C_47u_0603"
			(at -1.42757 -1.770288 90)
			(layer "B.Fab")
			(effects
				(font
					(size 0.7 0.7)
					(thickness 0.15)
				)
				(justify left bottom mirror)
			)
		)
		(property "Datasheet" "https://www.murata.com/products/productdetail?partno=GRM188R60J476ME15%23"
			(at 0 0 270)
			(layer "F.Fab")
			(hide yes)
			(effects
				(font
					(size 1.27 1.27)
					(thickness 0.15)
				)
			)
		)
		(property "Manufacturer" "Murata"
			(at 0 0 270)
			(unlocked yes)
			(layer "B.Fab")
			(hide yes)
			(effects
				(font
					(size 1 1)
					(thickness 0.15)
				)
				(justify mirror)
			)
		)
		(property "MPN" "GRM188R60J476ME15D"
			(at 0 0 270)
			(unlocked yes)
			(layer "B.Fab")
			(hide yes)
			(effects
				(font
					(size 1 1)
					(thickness 0.15)
				)
				(justify mirror)
			)
		)
		(property "Val" "47u"
			(at 0 0 270)
			(unlocked yes)
			(layer "B.Fab")
			(hide yes)
			(effects
				(font
					(size 1 1)
					(thickness 0.15)
				)
				(justify mirror)
			)
		)
		(property "License" "Apache-2.0"
			(at 0 0 270)
			(unlocked yes)
			(layer "B.Fab")
			(hide yes)
			(effects
				(font
					(size 1 1)
					(thickness 0.15)
				)
				(justify mirror)
			)
		)
		(property "Author" "Antmicro"
			(at 0 0 270)
			(unlocked yes)
			(layer "B.Fab")
			(hide yes)
			(effects
				(font
					(size 1 1)
					(thickness 0.15)
				)
				(justify mirror)
			)
		)
		(property "Voltage" ""
			(at 0 0 270)
			(unlocked yes)
			(layer "B.Fab")
			(hide yes)
			(effects
				(font
					(size 1 1)
					(thickness 0.15)
				)
				(justify mirror)
			)
		)
		(property "Dielectric" ""
			(at 0 0 270)
			(unlocked yes)
			(layer "B.Fab")
			(hide yes)
			(effects
				(font
					(size 1 1)
					(thickness 0.15)
				)
				(justify mirror)
			)
		)
		(sheetname "/FPGA power/")
		(sheetfile "fpga-power.kicad_sch")
		(attr smd)
		(fp_line
			(start -0.15 0.4)
			(end 0.15 0.4)
			(stroke
				(width 0.15)
				(type solid)
			)
			(layer "B.SilkS")
		)
		(fp_line
			(start -0.15 -0.4)
			(end 0.15 -0.4)
			(stroke
				(width 0.15)
				(type solid)
			)
			(layer "B.SilkS")
		)
		(fp_rect
			(start -1.25 0.65)
			(end 1.25 -0.65)
			(stroke
				(width 0.05)
				(type solid)
			)
			(fill no)
			(layer "B.CrtYd")
		)
		(fp_rect
			(start -0.8 0.4)
			(end 0.8 -0.4)
			(stroke
				(width 0.15)
				(type solid)
			)
			(fill no)
			(layer "B.Fab")
		)
		(fp_text user "License: Apache-2.0"
			(at -1.682 -5.895 90)
			(layer "B.Fab")
			(effects
				(font
					(size 0.7 0.7)
					(thickness 0.15)
				)
				(justify left bottom mirror)
			)
		)
		(fp_text user "${REFERENCE}"
			(at -1.682 -3.895 90)
			(layer "B.Fab")
			(effects
				(font
					(size 0.7 0.7)
					(thickness 0.15)
				)
				(justify left bottom mirror)
			)
		)
		(fp_text user "Author: Antmicro"
			(at -1.682 -4.894 90)
			(layer "B.Fab")
			(effects
				(font
					(size 0.7 0.7)
					(thickness 0.15)
				)
				(justify left bottom mirror)
			)
		)
		(pad "1" smd roundrect
			(at -0.7 0 270)
			(size 0.8 1)
			(layers "B.Cu" "B.Mask" "B.Paste")
			(roundrect_rratio 0.2)
			(net 797 "+1V8")
			(pintype "passive")
		)
		(pad "2" smd roundrect
			(at 0.7 0 270)
			(size 0.8 1)
			(layers "B.Cu" "B.Mask" "B.Paste")
			(roundrect_rratio 0.2)
			(net 1 "GND")
			(pintype "passive")
		)
	)
	(footprint "antmicro-footprints:C_0402_1005Metric_EIA"
		(layer "B.Cu")
		(at 192 156.5 -90)
		(descr "Capacitor SMD 0402 (1005 Metric), square (rectangular) end terminal, IPC_7351 nominal, (Body size source: IPC-SM-782 page 76, https://www.pcb-3d.com/wordpress/wp-content/uploads/ipc-sm-782a_amendment_1_and_2.pdf)")
		(tags "capacitor 0402")
		(property "Reference" "C48"
			(at -12 30.65 90)
			(layer "B.SilkS")
			(effects
				(font
					(size 0.7 0.7)
					(thickness 0.15)
				)
				(justify left bottom mirror)
			)
		)
		(property "Value" "C_100n_0402"
			(at 0 -1.169 90)
			(layer "B.Fab")
			(effects
				(font
					(size 0.7 0.7)
					(thickness 0.15)
				)
				(justify left bottom mirror)
			)
		)
		(property "Datasheet" "https://www.murata.com/products/productdetail?partno=GRM155R61H104KE14%23"
			(at 0 0 270)
			(layer "F.Fab")
			(hide yes)
			(effects
				(font
					(size 1.27 1.27)
					(thickness 0.15)
				)
			)
		)
		(property "MPN" "GRM155R61H104KE14D"
			(at 0 0 270)
			(unlocked yes)
			(layer "B.Fab")
			(hide yes)
			(effects
				(font
					(size 1 1)
					(thickness 0.15)
				)
				(justify mirror)
			)
		)
		(property "Manufacturer" "Murata"
			(at 0 0 270)
			(unlocked yes)
			(layer "B.Fab")
			(hide yes)
			(effects
				(font
					(size 1 1)
					(thickness 0.15)
				)
				(justify mirror)
			)
		)
		(property "License" "Apache-2.0"
			(at 0 0 270)
			(unlocked yes)
			(layer "B.Fab")
			(hide yes)
			(effects
				(font
					(size 1 1)
					(thickness 0.15)
				)
				(justify mirror)
			)
		)
		(property "Author" "Antmicro"
			(at 0 0 270)
			(unlocked yes)
			(layer "B.Fab")
			(hide yes)
			(effects
				(font
					(size 1 1)
					(thickness 0.15)
				)
				(justify mirror)
			)
		)
		(property "Val" "100n"
			(at 0 0 270)
			(unlocked yes)
			(layer "B.Fab")
			(hide yes)
			(effects
				(font
					(size 1 1)
					(thickness 0.15)
				)
				(justify mirror)
			)
		)
		(property "Voltage" "50V"
			(at 0 0 270)
			(unlocked yes)
			(layer "B.Fab")
			(hide yes)
			(effects
				(font
					(size 1 1)
					(thickness 0.15)
				)
				(justify mirror)
			)
		)
		(property "Dielectric" "X5R"
			(at 0 0 270)
			(unlocked yes)
			(layer "B.Fab")
			(hide yes)
			(effects
				(font
					(size 1 1)
					(thickness 0.15)
				)
				(justify mirror)
			)
		)
		(sheetname "/FPGA power/")
		(sheetfile "fpga-power.kicad_sch")
		(attr smd)
		(fp_rect
			(start -0.95 0.45)
			(end 0.95 -0.45)
			(stroke
				(width 0.05)
				(type default)
			)
			(fill no)
			(layer "B.CrtYd")
		)
		(fp_line
			(start -0.5 0.25)
			(end 0.498 0.25)
			(stroke
				(width 0.15)
				(type solid)
			)
			(layer "B.Fab")
		)
		(fp_line
			(start 0.498 0.25)
			(end 0.498 -0.248)
			(stroke
				(width 0.15)
				(type solid)
			)
			(layer "B.Fab")
		)
		(fp_line
			(start -0.5 -0.248)
			(end -0.5 0.25)
			(stroke
				(width 0.15)
				(type solid)
			)
			(layer "B.Fab")
		)
		(fp_line
			(start 0.498 -0.248)
			(end -0.5 -0.248)
			(stroke
				(width 0.15)
				(type solid)
			)
			(layer "B.Fab")
		)
		(fp_text user "License: Apache-2.0"
			(at -0.9656 -4.369 90)
			(layer "B.Fab")
			(effects
				(font
					(size 0.7 0.7)
					(thickness 0.15)
				)
				(justify left bottom mirror)
			)
		)
		(fp_text user "Author: Antmicro"
			(at -0.9656 -5.569 90)
			(layer "B.Fab")
			(effects
				(font
					(size 0.7 0.7)
					(thickness 0.15)
				)
				(justify left bottom mirror)
			)
		)
		(fp_text user "${REFERENCE}"
			(at -0.9656 -3.169 90)
			(layer "B.Fab")
			(effects
				(font
					(size 0.7 0.7)
					(thickness 0.15)
				)
				(justify left bottom mirror)
			)
		)
		(pad "1" smd roundrect
			(at -0.5 0 180)
			(size 0.6 0.6)
			(layers "B.Cu" "B.Mask" "B.Paste")
			(roundrect_rratio 0.25)
			(net 1 "GND")
			(pintype "passive")
		)
		(pad "2" smd roundrect
			(at 0.498 0 270)
			(size 0.6 0.6)
			(layers "B.Cu" "B.Mask" "B.Paste")
			(roundrect_rratio 0.25)
			(net 553 "+0V85")
			(pintype "passive")
		)
	)
	(footprint "antmicro-footprints:R_0402_1005Metric"
		(layer "B.Cu")
		(at 211.91 153.15 180)
		(descr "Resistor SMD 0402")
		(tags "resistor SMD 0402")
		(property "Reference" "R4"
			(at -2.53 -0.46 0)
			(layer "B.SilkS")
			(effects
				(font
					(size 0.7 0.7)
					(thickness 0.15)
				)
				(justify left bottom mirror)
			)
		)
		(property "Value" "R_4k7_0402"
			(at -1.011843 -1.772047 0)
			(layer "B.Fab")
			(effects
				(font
					(size 0.7 0.7)
					(thickness 0.15)
				)
				(justify left bottom mirror)
			)
		)
		(property "Datasheet" "https://www.bourns.com/docs/product-datasheets/cr.pdf"
			(at 0 0 180)
			(layer "F.Fab")
			(hide yes)
			(effects
				(font
					(size 1.27 1.27)
					(thickness 0.15)
				)
			)
		)
		(property "Manufacturer" "Bourns"
			(at 0 0 180)
			(unlocked yes)
			(layer "B.Fab")
			(hide yes)
			(effects
				(font
					(size 1 1)
					(thickness 0.15)
				)
				(justify mirror)
			)
		)
		(property "MPN" "CR0402-FX-4701GLF"
			(at 0 0 180)
			(unlocked yes)
			(layer "B.Fab")
			(hide yes)
			(effects
				(font
					(size 1 1)
					(thickness 0.15)
				)
				(justify mirror)
			)
		)
		(property "Val" "4k7"
			(at 0 0 180)
			(unlocked yes)
			(layer "B.Fab")
			(hide yes)
			(effects
				(font
					(size 1 1)
					(thickness 0.15)
				)
				(justify mirror)
			)
		)
		(property "License" "Apache-2.0"
			(at 0 0 180)
			(unlocked yes)
			(layer "B.Fab")
			(hide yes)
			(effects
				(font
					(size 1 1)
					(thickness 0.15)
				)
				(justify mirror)
			)
		)
		(property "Author" "Antmicro"
			(at 0 0 180)
			(unlocked yes)
			(layer "B.Fab")
			(hide yes)
			(effects
				(font
					(size 1 1)
					(thickness 0.15)
				)
				(justify mirror)
			)
		)
		(property "Tolerance" "1%"
			(at 0 0 180)
			(unlocked yes)
			(layer "B.Fab")
			(hide yes)
			(effects
				(font
					(size 1 1)
					(thickness 0.15)
				)
				(justify mirror)
			)
		)
		(sheetname "/HyperRAM + QSPI Flash/")
		(sheetfile "hyperram-flash.kicad_sch")
		(attr smd)
		(fp_rect
			(start -0.925 0.47)
			(end 0.925 -0.47)
			(stroke
				(width 0.05)
				(type default)
			)
			(fill no)
			(layer "B.CrtYd")
		)
		(fp_rect
			(start -0.5 0.25)
			(end 0.5 -0.25)
			(stroke
				(width 0.15)
				(type solid)
			)
			(fill no)
			(layer "B.Fab")
		)
		(fp_text user "${REFERENCE}"
			(at -0.95 -3.168 0)
			(layer "B.Fab")
			(effects
				(font
					(size 0.7 0.7)
					(thickness 0.15)
				)
				(justify left bottom mirror)
			)
		)
		(fp_text user "License: Apache-2.0"
			(at -0.95 -5.169 0)
			(layer "B.Fab")
			(effects
				(font
					(size 0.7 0.7)
					(thickness 0.15)
				)
				(justify left bottom mirror)
			)
		)
		(fp_text user "Author: Antmicro"
			(at -0.95 -4.169 0)
			(layer "B.Fab")
			(effects
				(font
					(size 0.7 0.7)
					(thickness 0.15)
				)
				(justify left bottom mirror)
			)
		)
		(pad "1" smd roundrect
			(at -0.48 0 180)
			(size 0.59 0.64)
			(layers "B.Cu" "B.Mask" "B.Paste")
			(roundrect_rratio 0.25)
			(net 797 "+1V8")
			(pintype "passive")
		)
		(pad "2" smd roundrect
			(at 0.48 0 180)
			(size 0.59 0.64)
			(layers "B.Cu" "B.Mask" "B.Paste")
			(roundrect_rratio 0.25)
			(net 279 "/HyperRAM + QSPI Flash/IO3")
			(pintype "passive")
		)
	)
	(footprint "antmicro-footprints:Coax_Conn_U.FL"
		(layer "B.Cu")
		(at 123.9 120.664 -90)
		(descr "https://media.digikey.com/pdf/Data%20Sheets/Hirose%20PDFs/UFL%20Series.pdf")
		(property "Reference" "J9"
			(at 3.036 -2.05 180)
			(layer "B.SilkS")
			(hide yes)
			(effects
				(font
					(size 0.7 0.7)
					(thickness 0.15)
				)
				(justify left bottom mirror)
			)
		)
		(property "Value" "U_FL-R-SMT-1"
			(at -4.13 -2.52 90)
			(layer "B.Fab")
			(effects
				(font
					(size 0.7 0.7)
					(thickness 0.15)
				)
				(justify left bottom mirror)
			)
		)
		(property "Datasheet" "https://media.digikey.com/pdf/Data%20Sheets/Hirose%20PDFs/UFL%20Series.pdf"
			(at 0 0 270)
			(layer "F.Fab")
			(hide yes)
			(effects
				(font
					(size 1.27 1.27)
					(thickness 0.15)
				)
			)
		)
		(property "MPN" "U.FL-R-SMT-1(10)"
			(at 0 0 270)
			(unlocked yes)
			(layer "B.Fab")
			(hide yes)
			(effects
				(font
					(size 1 1)
					(thickness 0.15)
				)
				(justify mirror)
			)
		)
		(property "Manufacturer" "Hirose Electric"
			(at 0 0 270)
			(unlocked yes)
			(layer "B.Fab")
			(hide yes)
			(effects
				(font
					(size 1 1)
					(thickness 0.15)
				)
				(justify mirror)
			)
		)
		(property "Author" "Antmicro"
			(at 0 0 270)
			(unlocked yes)
			(layer "B.Fab")
			(hide yes)
			(effects
				(font
					(size 1 1)
					(thickness 0.15)
				)
				(justify mirror)
			)
		)
		(property "License" "Apache-2.0"
			(at 0 0 270)
			(unlocked yes)
			(layer "B.Fab")
			(hide yes)
			(effects
				(font
					(size 1 1)
					(thickness 0.15)
				)
				(justify mirror)
			)
		)
		(sheetname "/Debug FTDI + VNA/")
		(sheetfile "debug-ftdi.kicad_sch")
		(attr smd)
		(fp_line
			(start -1.613 1.651)
			(end -1.113 1.651)
			(stroke
				(width 0.15)
				(type solid)
			)
			(layer "B.SilkS")
		)
		(fp_line
			(start -1.613 1.651)
			(end -1.613 1.325)
			(stroke
				(width 0.15)
				(type solid)
			)
			(layer "B.SilkS")
		)
		(fp_line
			(start 1.588 1.651)
			(end 1.088 1.651)
			(stroke
				(width 0.15)
				(type solid)
			)
			(layer "B.SilkS")
		)
		(fp_line
			(start 1.588 1.651)
			(end 1.588 1.325)
			(stroke
				(width 0.15)
				(type solid)
			)
			(layer "B.SilkS")
		)
		(fp_line
			(start -1.613 -1.648)
			(end -1.613 -1.325)
			(stroke
				(width 0.15)
				(type solid)
			)
			(layer "B.SilkS")
		)
		(fp_line
			(start -1.613 -1.648)
			(end -1.113 -1.648)
			(stroke
				(width 0.15)
				(type solid)
			)
			(layer "B.SilkS")
		)
		(fp_line
			(start 1.588 -1.648)
			(end 1.588 -1.325)
			(stroke
				(width 0.15)
				(type solid)
			)
			(layer "B.SilkS")
		)
		(fp_line
			(start 1.588 -1.648)
			(end 1.088 -1.648)
			(stroke
				(width 0.15)
				(type solid)
			)
			(layer "B.SilkS")
		)
		(fp_rect
			(start -2 2.051)
			(end 1.999 -2.05)
			(stroke
				(width 0.05)
				(type solid)
			)
			(fill no)
			(layer "B.CrtYd")
		)
		(fp_line
			(start -1.512 1.551)
			(end 1.487 1.551)
			(stroke
				(width 0.15)
				(type solid)
			)
			(layer "B.Fab")
		)
		(fp_line
			(start -1.512 -1.55)
			(end -1.512 1.551)
			(stroke
				(width 0.15)
				(type solid)
			)
			(layer "B.Fab")
		)
		(fp_line
			(start -1.512 -1.55)
			(end 1.487 -1.55)
			(stroke
				(width 0.15)
				(type solid)
			)
			(layer "B.Fab")
		)
		(fp_line
			(start 1.487 -1.55)
			(end 1.487 1.551)
			(stroke
				(width 0.15)
				(type solid)
			)
			(layer "B.Fab")
		)
		(fp_text user "${REFERENCE}"
			(at -4.13 -6.92 90)
			(layer "B.Fab")
			(effects
				(font
					(size 0.7 0.7)
					(thickness 0.15)
				)
				(justify left bottom mirror)
			)
		)
		(fp_text user "Author: Antmicro"
			(at -4.13 -4.52 90)
			(layer "B.Fab")
			(effects
				(font
					(size 0.7 0.7)
					(thickness 0.15)
				)
				(justify left bottom mirror)
			)
		)
		(fp_text user "License: Apache-2.0"
			(at -4.13 -5.72 90)
			(layer "B.Fab")
			(effects
				(font
					(size 0.7 0.7)
					(thickness 0.15)
				)
				(justify left bottom mirror)
			)
		)
		(pad "1" smd rect
			(at -0.012 -1.499 270)
			(size 1 1.05)
			(layers "B.Cu" "B.Mask" "B.Paste")
			(net 367 "unconnected-(J9-Pad1)")
			(pintype "passive+no_connect")
		)
		(pad "SH1" smd rect
			(at 1.463 0 270)
			(size 1.05 2.2)
			(layers "B.Cu" "B.Mask" "B.Paste")
			(net 1 "GND")
			(pintype "passive")
		)
		(pad "SH2" smd rect
			(at -1.488 0 270)
			(size 1.05 2.2)
			(layers "B.Cu" "B.Mask" "B.Paste")
			(net 1 "GND")
			(pintype "passive")
		)
		(zone
			(net 0)
			(net_name "")
			(layer "B.Cu")
			(hatch edge 0.508)
			(connect_pads
				(clearance 0)
			)
			(min_thickness 0.254)
			(filled_areas_thickness no)
			(keepout
				(tracks not_allowed)
				(vias not_allowed)
				(pads not_allowed)
				(copperpour not_allowed)
				(footprints not_allowed)
			)
			(placement
				(enabled no)
				(sheetname "")
			)
			(fill
				(thermal_gap 0.508)
				(thermal_bridge_width 0.508)
			)
			(polygon
				(pts
					(xy 124.86 121.594) (xy 124.86 119.714) (xy 122.8 119.714) (xy 122.8 121.594)
				)
			)
		)
	)
	(footprint "antmicro-footprints:C_0402_1005Metric"
		(layer "B.Cu")
		(at 207.94 150.97 90)
		(descr "Capacitor SMD 0402")
		(tags "capacitor SMD 0402")
		(property "Reference" "C204"
			(at 1.05 0.33 90)
			(layer "B.SilkS")
			(effects
				(font
					(size 0.7 0.7)
					(thickness 0.15)
				)
				(justify right bottom mirror)
			)
		)
		(property "Value" "C_1u_0402"
			(at -1.022927 -2.155213 90)
			(layer "B.Fab")
			(effects
				(font
					(size 0.7 0.7)
					(thickness 0.15)
				)
				(justify right bottom mirror)
			)
		)
		(property "Datasheet" "https://product.tdk.com/en/search/capacitor/ceramic/mlcc/info?part_no=C1005X6S1A105K050BC"
			(at 0 0 90)
			(layer "F.Fab")
			(hide yes)
			(effects
				(font
					(size 1.27 1.27)
					(thickness 0.15)
				)
			)
		)
		(property "MPN" "C1005X6S1A105K050BC"
			(at 0 0 90)
			(unlocked yes)
			(layer "B.Fab")
			(hide yes)
			(effects
				(font
					(size 1 1)
					(thickness 0.15)
				)
				(justify mirror)
			)
		)
		(property "Manufacturer" "TDK"
			(at 0 0 90)
			(unlocked yes)
			(layer "B.Fab")
			(hide yes)
			(effects
				(font
					(size 1 1)
					(thickness 0.15)
				)
				(justify mirror)
			)
		)
		(property "License" "Apache-2.0"
			(at 0 0 90)
			(unlocked yes)
			(layer "B.Fab")
			(hide yes)
			(effects
				(font
					(size 1 1)
					(thickness 0.15)
				)
				(justify mirror)
			)
		)
		(property "Author" "Antmicro"
			(at 0 0 90)
			(unlocked yes)
			(layer "B.Fab")
			(hide yes)
			(effects
				(font
					(size 1 1)
					(thickness 0.15)
				)
				(justify mirror)
			)
		)
		(property "Val" "1u"
			(at 0 0 90)
			(unlocked yes)
			(layer "B.Fab")
			(hide yes)
			(effects
				(font
					(size 1 1)
					(thickness 0.15)
				)
				(justify mirror)
			)
		)
		(property "Voltage" ""
			(at 0 0 90)
			(unlocked yes)
			(layer "B.Fab")
			(hide yes)
			(effects
				(font
					(size 1 1)
					(thickness 0.15)
				)
				(justify mirror)
			)
		)
		(property "Dielectric" ""
			(at 0 0 90)
			(unlocked yes)
			(layer "B.Fab")
			(hide yes)
			(effects
				(font
					(size 1 1)
					(thickness 0.15)
				)
				(justify mirror)
			)
		)
		(sheetname "/FPGA Config/")
		(sheetfile "fpga-config.kicad_sch")
		(attr smd)
		(fp_rect
			(start -0.925 0.47)
			(end 0.925 -0.47)
			(stroke
				(width 0.05)
				(type default)
			)
			(fill no)
			(layer "B.CrtYd")
		)
		(fp_line
			(start 0.504 -0.248)
			(end -0.494 -0.248)
			(stroke
				(width 0.15)
				(type solid)
			)
			(layer "B.Fab")
		)
		(fp_line
			(start -0.494 -0.248)
			(end -0.494 0.25)
			(stroke
				(width 0.15)
				(type solid)
			)
			(layer "B.Fab")
		)
		(fp_line
			(start 0.504 0.25)
			(end 0.504 -0.248)
			(stroke
				(width 0.15)
				(type solid)
			)
			(layer "B.Fab")
		)
		(fp_line
			(start -0.494 0.25)
			(end 0.504 0.25)
			(stroke
				(width 0.15)
				(type solid)
			)
			(layer "B.Fab")
		)
		(fp_text user "${REFERENCE}"
			(at -0.939 -4.599 270)
			(layer "B.Fab")
			(effects
				(font
					(size 0.7 0.7)
					(thickness 0.15)
				)
				(justify left bottom mirror)
			)
		)
		(fp_text user "Author: Antmicro"
			(at -0.939 -3.399 270)
			(layer "B.Fab")
			(effects
				(font
					(size 0.7 0.7)
					(thickness 0.15)
				)
				(justify left bottom mirror)
			)
		)
		(fp_text user "License: Apache-2.0"
			(at -0.939 -5.799 270)
			(layer "B.Fab")
			(effects
				(font
					(size 0.7 0.7)
					(thickness 0.15)
				)
				(justify left bottom mirror)
			)
		)
		(pad "1" smd roundrect
			(at -0.48 0 90)
			(size 0.59 0.64)
			(layers "B.Cu" "B.Mask" "B.Paste")
			(roundrect_rratio 0.25)
			(net 1 "GND")
			(pintype "passive")
		)
		(pad "2" smd roundrect
			(at 0.48 0 90)
			(size 0.59 0.64)
			(layers "B.Cu" "B.Mask" "B.Paste")
			(roundrect_rratio 0.25)
			(net 797 "+1V8")
			(pintype "passive")
		)
	)
	(footprint "antmicro-footprints:R_0402_1005Metric"
		(layer "B.Cu")
		(at 234.25 182.505 90)
		(descr "Resistor SMD 0402")
		(tags "resistor SMD 0402")
		(property "Reference" "R252"
			(at -1.285 0.6 90)
			(layer "B.SilkS")
			(effects
				(font
					(size 0.7 0.7)
					(thickness 0.15)
				)
				(justify right top mirror)
			)
		)
		(property "Value" "R_47k_0402"
			(at -1.011843 -1.772047 90)
			(layer "B.Fab")
			(effects
				(font
					(size 0.7 0.7)
					(thickness 0.15)
				)
				(justify right top mirror)
			)
		)
		(property "Datasheet" "https://www.bourns.com/docs/product-datasheets/cr.pdf"
			(at 0 0 90)
			(layer "B.Fab")
			(hide yes)
			(effects
				(font
					(size 1.27 1.27)
					(thickness 0.15)
				)
				(justify mirror)
			)
		)
		(property "MPN" "CR0402-FX-4702GLF"
			(at 0 0 90)
			(unlocked yes)
			(layer "B.Fab")
			(hide yes)
			(effects
				(font
					(size 1 1)
					(thickness 0.15)
				)
				(justify mirror)
			)
		)
		(property "Manufacturer" "Bourns"
			(at 0 0 90)
			(unlocked yes)
			(layer "B.Fab")
			(hide yes)
			(effects
				(font
					(size 1 1)
					(thickness 0.15)
				)
				(justify mirror)
			)
		)
		(property "License" "Apache-2.0"
			(at 0 0 90)
			(unlocked yes)
			(layer "B.Fab")
			(hide yes)
			(effects
				(font
					(size 1 1)
					(thickness 0.15)
				)
				(justify mirror)
			)
		)
		(property "Author" "Antmicro"
			(at 0 0 90)
			(unlocked yes)
			(layer "B.Fab")
			(hide yes)
			(effects
				(font
					(size 1 1)
					(thickness 0.15)
				)
				(justify mirror)
			)
		)
		(property "Val" "47k"
			(at 0 0 90)
			(unlocked yes)
			(layer "B.Fab")
			(hide yes)
			(effects
				(font
					(size 1 1)
					(thickness 0.15)
				)
				(justify mirror)
			)
		)
		(property "Tolerance" "1%"
			(at 0 0 90)
			(unlocked yes)
			(layer "B.Fab")
			(hide yes)
			(effects
				(font
					(size 1 1)
					(thickness 0.15)
				)
				(justify mirror)
			)
		)
		(sheetname "/Supply/DC-DC VCCINT/")
		(sheetfile "dc-dc-vccint.kicad_sch")
		(attr smd)
		(fp_rect
			(start -0.925 0.47)
			(end 0.925 -0.47)
			(stroke
				(width 0.05)
				(type default)
			)
			(fill no)
			(layer "B.CrtYd")
		)
		(fp_rect
			(start -0.5 0.25)
			(end 0.5 -0.25)
			(stroke
				(width 0.15)
				(type solid)
			)
			(fill no)
			(layer "B.Fab")
		)
		(fp_text user "License: Apache-2.0"
			(at -0.95 -5.169 270)
			(layer "B.Fab")
			(effects
				(font
					(size 0.7 0.7)
					(thickness 0.15)
				)
				(justify left bottom mirror)
			)
		)
		(fp_text user "${REFERENCE}"
			(at -0.95 -3.168 270)
			(layer "B.Fab")
			(effects
				(font
					(size 0.7 0.7)
					(thickness 0.15)
				)
				(justify left bottom mirror)
			)
		)
		(fp_text user "Author: Antmicro"
			(at -0.95 -4.169 270)
			(layer "B.Fab")
			(effects
				(font
					(size 0.7 0.7)
					(thickness 0.15)
				)
				(justify left bottom mirror)
			)
		)
		(pad "1" smd roundrect
			(at -0.48 0 90)
			(size 0.59 0.64)
			(layers "B.Cu" "B.Mask" "B.Paste")
			(roundrect_rratio 0.25)
			(net 777 "/Supply/DC-DC VCCINT/~{PS}")
			(pintype "passive")
		)
		(pad "2" smd roundrect
			(at 0.48 0 90)
			(size 0.59 0.64)
			(layers "B.Cu" "B.Mask" "B.Paste")
			(roundrect_rratio 0.25)
			(net 163 "/Supply/DC-DC VCCINT/V_{CC}")
			(pintype "passive")
		)
	)
	(footprint "antmicro-footprints:C_0402_1005Metric"
		(layer "B.Cu")
		(at 149.084499 164.653 90)
		(descr "Capacitor SMD 0402")
		(tags "capacitor SMD 0402")
		(property "Reference" "C238"
			(at -3.749 0.521501 90)
			(layer "B.SilkS")
			(effects
				(font
					(size 0.7 0.7)
					(thickness 0.15)
				)
				(justify right bottom mirror)
			)
		)
		(property "Value" "C_100n_0402"
			(at -1.022927 -2.155213 90)
			(layer "B.Fab")
			(effects
				(font
					(size 0.7 0.7)
					(thickness 0.15)
				)
				(justify right bottom mirror)
			)
		)
		(property "Datasheet" "https://www.murata.com/products/productdetail?partno=GRM155R61H104KE14%23"
			(at 0 0 90)
			(layer "F.Fab")
			(hide yes)
			(effects
				(font
					(size 1.27 1.27)
					(thickness 0.15)
				)
			)
		)
		(property "MPN" "GRM155R61H104KE14D"
			(at 0 0 90)
			(unlocked yes)
			(layer "B.Fab")
			(hide yes)
			(effects
				(font
					(size 1 1)
					(thickness 0.15)
				)
				(justify mirror)
			)
		)
		(property "Manufacturer" "Murata"
			(at 0 0 90)
			(unlocked yes)
			(layer "B.Fab")
			(hide yes)
			(effects
				(font
					(size 1 1)
					(thickness 0.15)
				)
				(justify mirror)
			)
		)
		(property "License" "Apache-2.0"
			(at 0 0 90)
			(unlocked yes)
			(layer "B.Fab")
			(hide yes)
			(effects
				(font
					(size 1 1)
					(thickness 0.15)
				)
				(justify mirror)
			)
		)
		(property "Author" "Antmicro"
			(at 0 0 90)
			(unlocked yes)
			(layer "B.Fab")
			(hide yes)
			(effects
				(font
					(size 1 1)
					(thickness 0.15)
				)
				(justify mirror)
			)
		)
		(property "Val" "100n"
			(at 0 0 90)
			(unlocked yes)
			(layer "B.Fab")
			(hide yes)
			(effects
				(font
					(size 1 1)
					(thickness 0.15)
				)
				(justify mirror)
			)
		)
		(property "Voltage" "50V"
			(at 0 0 90)
			(unlocked yes)
			(layer "B.Fab")
			(hide yes)
			(effects
				(font
					(size 1 1)
					(thickness 0.15)
				)
				(justify mirror)
			)
		)
		(property "Dielectric" "X5R"
			(at 0 0 90)
			(unlocked yes)
			(layer "B.Fab")
			(hide yes)
			(effects
				(font
					(size 1 1)
					(thickness 0.15)
				)
				(justify mirror)
			)
		)
		(sheetname "/Debug FTDI + VNA/")
		(sheetfile "debug-ftdi.kicad_sch")
		(attr smd)
		(fp_rect
			(start -0.925 0.47)
			(end 0.925 -0.47)
			(stroke
				(width 0.05)
				(type default)
			)
			(fill no)
			(layer "B.CrtYd")
		)
		(fp_line
			(start 0.504 -0.248)
			(end -0.494 -0.248)
			(stroke
				(width 0.15)
				(type solid)
			)
			(layer "B.Fab")
		)
		(fp_line
			(start -0.494 -0.248)
			(end -0.494 0.25)
			(stroke
				(width 0.15)
				(type solid)
			)
			(layer "B.Fab")
		)
		(fp_line
			(start 0.504 0.25)
			(end 0.504 -0.248)
			(stroke
				(width 0.15)
				(type solid)
			)
			(layer "B.Fab")
		)
		(fp_line
			(start -0.494 0.25)
			(end 0.504 0.25)
			(stroke
				(width 0.15)
				(type solid)
			)
			(layer "B.Fab")
		)
		(fp_text user "${REFERENCE}"
			(at -0.939 -4.599 270)
			(layer "B.Fab")
			(effects
				(font
					(size 0.7 0.7)
					(thickness 0.15)
				)
				(justify left bottom mirror)
			)
		)
		(fp_text user "License: Apache-2.0"
			(at -0.939 -5.799 270)
			(layer "B.Fab")
			(effects
				(font
					(size 0.7 0.7)
					(thickness 0.15)
				)
				(justify left bottom mirror)
			)
		)
		(fp_text user "Author: Antmicro"
			(at -0.939 -3.399 270)
			(layer "B.Fab")
			(effects
				(font
					(size 0.7 0.7)
					(thickness 0.15)
				)
				(justify left bottom mirror)
			)
		)
		(pad "1" smd roundrect
			(at -0.48 0 90)
			(size 0.59 0.64)
			(layers "B.Cu" "B.Mask" "B.Paste")
			(roundrect_rratio 0.25)
			(net 1 "GND")
			(pintype "passive")
		)
		(pad "2" smd roundrect
			(at 0.48 0 90)
			(size 0.59 0.64)
			(layers "B.Cu" "B.Mask" "B.Paste")
			(roundrect_rratio 0.25)
			(net 151 "+3V3")
			(pintype "passive")
		)
	)
	(footprint "antmicro-footprints:C_0402_1005Metric"
		(layer "B.Cu")
		(at 120.411 167.35)
		(descr "Capacitor SMD 0402")
		(tags "capacitor SMD 0402")
		(property "Reference" "C82"
			(at 0.889 1.05 0)
			(layer "B.SilkS")
			(effects
				(font
					(size 0.7 0.7)
					(thickness 0.15)
				)
				(justify right bottom mirror)
			)
		)
		(property "Value" "C_100n_0402"
			(at -1.022927 -2.155213 0)
			(layer "B.Fab")
			(effects
				(font
					(size 0.7 0.7)
					(thickness 0.15)
				)
				(justify right bottom mirror)
			)
		)
		(property "Datasheet" "https://www.murata.com/products/productdetail?partno=GRM155R61H104KE14%23"
			(at 0 0 0)
			(layer "F.Fab")
			(hide yes)
			(effects
				(font
					(size 1.27 1.27)
					(thickness 0.15)
				)
			)
		)
		(property "MPN" "GRM155R61H104KE14D"
			(at 0 0 0)
			(unlocked yes)
			(layer "B.Fab")
			(hide yes)
			(effects
				(font
					(size 1 1)
					(thickness 0.15)
				)
				(justify mirror)
			)
		)
		(property "Manufacturer" "Murata"
			(at 0 0 0)
			(unlocked yes)
			(layer "B.Fab")
			(hide yes)
			(effects
				(font
					(size 1 1)
					(thickness 0.15)
				)
				(justify mirror)
			)
		)
		(property "License" "Apache-2.0"
			(at 0 0 0)
			(unlocked yes)
			(layer "B.Fab")
			(hide yes)
			(effects
				(font
					(size 1 1)
					(thickness 0.15)
				)
				(justify mirror)
			)
		)
		(property "Author" "Antmicro"
			(at 0 0 0)
			(unlocked yes)
			(layer "B.Fab")
			(hide yes)
			(effects
				(font
					(size 1 1)
					(thickness 0.15)
				)
				(justify mirror)
			)
		)
		(property "Val" "100n"
			(at 0 0 0)
			(unlocked yes)
			(layer "B.Fab")
			(hide yes)
			(effects
				(font
					(size 1 1)
					(thickness 0.15)
				)
				(justify mirror)
			)
		)
		(property "Voltage" "50V"
			(at 0 0 0)
			(unlocked yes)
			(layer "B.Fab")
			(hide yes)
			(effects
				(font
					(size 1 1)
					(thickness 0.15)
				)
				(justify mirror)
			)
		)
		(property "Dielectric" "X5R"
			(at 0 0 0)
			(unlocked yes)
			(layer "B.Fab")
			(hide yes)
			(effects
				(font
					(size 1 1)
					(thickness 0.15)
				)
				(justify mirror)
			)
		)
		(property "Public" ""
			(at 0 0 0)
			(unlocked yes)
			(layer "B.Fab")
			(hide yes)
			(effects
				(font
					(size 1 1)
					(thickness 0.15)
				)
				(justify mirror)
			)
		)
		(sheetname "/HDMI + SD Card/")
		(sheetfile "hdmi-sd-card.kicad_sch")
		(attr smd)
		(fp_rect
			(start -0.925 0.47)
			(end 0.925 -0.47)
			(stroke
				(width 0.05)
				(type default)
			)
			(fill no)
			(layer "B.CrtYd")
		)
		(fp_line
			(start -0.494 -0.248)
			(end -0.494 0.25)
			(stroke
				(width 0.15)
				(type solid)
			)
			(layer "B.Fab")
		)
		(fp_line
			(start -0.494 0.25)
			(end 0.504 0.25)
			(stroke
				(width 0.15)
				(type solid)
			)
			(layer "B.Fab")
		)
		(fp_line
			(start 0.504 -0.248)
			(end -0.494 -0.248)
			(stroke
				(width 0.15)
				(type solid)
			)
			(layer "B.Fab")
		)
		(fp_line
			(start 0.504 0.25)
			(end 0.504 -0.248)
			(stroke
				(width 0.15)
				(type solid)
			)
			(layer "B.Fab")
		)
		(fp_text user "Author: Antmicro"
			(at -0.939 -3.399 180)
			(layer "B.Fab")
			(effects
				(font
					(size 0.7 0.7)
					(thickness 0.15)
				)
				(justify left bottom mirror)
			)
		)
		(fp_text user "License: Apache-2.0"
			(at -0.939 -5.799 180)
			(layer "B.Fab")
			(effects
				(font
					(size 0.7 0.7)
					(thickness 0.15)
				)
				(justify left bottom mirror)
			)
		)
		(fp_text user "${REFERENCE}"
			(at -0.939 -4.599 180)
			(layer "B.Fab")
			(effects
				(font
					(size 0.7 0.7)
					(thickness 0.15)
				)
				(justify left bottom mirror)
			)
		)
		(pad "1" smd roundrect
			(at -0.48 0)
			(size 0.59 0.64)
			(layers "B.Cu" "B.Mask" "B.Paste")
			(roundrect_rratio 0.25)
			(net 151 "+3V3")
			(pintype "passive")
		)
		(pad "2" smd roundrect
			(at 0.48 0)
			(size 0.59 0.64)
			(layers "B.Cu" "B.Mask" "B.Paste")
			(roundrect_rratio 0.25)
			(net 1 "GND")
			(pintype "passive")
		)
	)
	(footprint "antmicro-footprints:C_0402_1005Metric"
		(layer "B.Cu")
		(at 164.03 154.5 -90)
		(descr "Capacitor SMD 0402")
		(tags "capacitor SMD 0402")
		(property "Reference" "C2"
			(at -2.4 -0.37 90)
			(layer "B.SilkS")
			(effects
				(font
					(size 0.7 0.7)
					(thickness 0.15)
				)
				(justify left bottom mirror)
			)
		)
		(property "Value" "C_100n_0402"
			(at -1.022927 -2.155213 90)
			(layer "B.Fab")
			(effects
				(font
					(size 0.7 0.7)
					(thickness 0.15)
				)
				(justify left bottom mirror)
			)
		)
		(property "Datasheet" "https://www.murata.com/products/productdetail?partno=GRM155R61H104KE14%23"
			(at 0 0 270)
			(layer "F.Fab")
			(hide yes)
			(effects
				(font
					(size 1.27 1.27)
					(thickness 0.15)
				)
			)
		)
		(property "Manufacturer" "Murata"
			(at 0 0 270)
			(unlocked yes)
			(layer "B.Fab")
			(hide yes)
			(effects
				(font
					(size 1 1)
					(thickness 0.15)
				)
				(justify mirror)
			)
		)
		(property "MPN" "GRM155R61H104KE14D"
			(at 0 0 270)
			(unlocked yes)
			(layer "B.Fab")
			(hide yes)
			(effects
				(font
					(size 1 1)
					(thickness 0.15)
				)
				(justify mirror)
			)
		)
		(property "Val" "100n"
			(at 0 0 270)
			(unlocked yes)
			(layer "B.Fab")
			(hide yes)
			(effects
				(font
					(size 1 1)
					(thickness 0.15)
				)
				(justify mirror)
			)
		)
		(property "License" "Apache-2.0"
			(at 0 0 270)
			(unlocked yes)
			(layer "B.Fab")
			(hide yes)
			(effects
				(font
					(size 1 1)
					(thickness 0.15)
				)
				(justify mirror)
			)
		)
		(property "Author" "Antmicro"
			(at 0 0 270)
			(unlocked yes)
			(layer "B.Fab")
			(hide yes)
			(effects
				(font
					(size 1 1)
					(thickness 0.15)
				)
				(justify mirror)
			)
		)
		(property "Voltage" "50V"
			(at 0 0 270)
			(unlocked yes)
			(layer "B.Fab")
			(hide yes)
			(effects
				(font
					(size 1 1)
					(thickness 0.15)
				)
				(justify mirror)
			)
		)
		(property "Dielectric" "X5R"
			(at 0 0 270)
			(unlocked yes)
			(layer "B.Fab")
			(hide yes)
			(effects
				(font
					(size 1 1)
					(thickness 0.15)
				)
				(justify mirror)
			)
		)
		(sheetname "/HyperRAM + QSPI Flash/")
		(sheetfile "hyperram-flash.kicad_sch")
		(attr smd)
		(fp_rect
			(start -0.925 0.47)
			(end 0.925 -0.47)
			(stroke
				(width 0.05)
				(type default)
			)
			(fill no)
			(layer "B.CrtYd")
		)
		(fp_line
			(start -0.494 0.25)
			(end 0.504 0.25)
			(stroke
				(width 0.15)
				(type solid)
			)
			(layer "B.Fab")
		)
		(fp_line
			(start 0.504 0.25)
			(end 0.504 -0.248)
			(stroke
				(width 0.15)
				(type solid)
			)
			(layer "B.Fab")
		)
		(fp_line
			(start -0.494 -0.248)
			(end -0.494 0.25)
			(stroke
				(width 0.15)
				(type solid)
			)
			(layer "B.Fab")
		)
		(fp_line
			(start 0.504 -0.248)
			(end -0.494 -0.248)
			(stroke
				(width 0.15)
				(type solid)
			)
			(layer "B.Fab")
		)
		(fp_text user "Author: Antmicro"
			(at -0.939 -3.399 90)
			(layer "B.Fab")
			(effects
				(font
					(size 0.7 0.7)
					(thickness 0.15)
				)
				(justify left bottom mirror)
			)
		)
		(fp_text user "${REFERENCE}"
			(at -0.939 -4.599 90)
			(layer "B.Fab")
			(effects
				(font
					(size 0.7 0.7)
					(thickness 0.15)
				)
				(justify left bottom mirror)
			)
		)
		(fp_text user "License: Apache-2.0"
			(at -0.939 -5.799 90)
			(layer "B.Fab")
			(effects
				(font
					(size 0.7 0.7)
					(thickness 0.15)
				)
				(justify left bottom mirror)
			)
		)
		(pad "1" smd roundrect
			(at -0.48 0 270)
			(size 0.59 0.64)
			(layers "B.Cu" "B.Mask" "B.Paste")
			(roundrect_rratio 0.25)
			(net 797 "+1V8")
			(pintype "passive")
		)
		(pad "2" smd roundrect
			(at 0.48 0 270)
			(size 0.59 0.64)
			(layers "B.Cu" "B.Mask" "B.Paste")
			(roundrect_rratio 0.25)
			(net 1 "GND")
			(pintype "passive")
		)
	)
	(footprint "antmicro-footprints:R_0402_1005Metric"
		(layer "B.Cu")
		(at 217.89 153.1205 180)
		(descr "Resistor SMD 0402")
		(tags "resistor SMD 0402")
		(property "Reference" "R7"
			(at 1.16 -0.47 0)
			(layer "B.SilkS")
			(effects
				(font
					(size 0.7 0.7)
					(thickness 0.15)
				)
				(justify left bottom mirror)
			)
		)
		(property "Value" "R_22R_0402"
			(at -1.011843 -1.772047 0)
			(layer "B.Fab")
			(effects
				(font
					(size 0.7 0.7)
					(thickness 0.15)
				)
				(justify left bottom mirror)
			)
		)
		(property "Datasheet" "https://www.bourns.com/docs/product-datasheets/cr.pdf"
			(at 0 0 180)
			(layer "F.Fab")
			(hide yes)
			(effects
				(font
					(size 1.27 1.27)
					(thickness 0.15)
				)
			)
		)
		(property "Manufacturer" "Bourns"
			(at 0 0 180)
			(unlocked yes)
			(layer "B.Fab")
			(hide yes)
			(effects
				(font
					(size 1 1)
					(thickness 0.15)
				)
				(justify mirror)
			)
		)
		(property "MPN" "CR0402-FX-22R0GLF"
			(at 0 0 180)
			(unlocked yes)
			(layer "B.Fab")
			(hide yes)
			(effects
				(font
					(size 1 1)
					(thickness 0.15)
				)
				(justify mirror)
			)
		)
		(property "Val" "22R"
			(at 0 0 180)
			(unlocked yes)
			(layer "B.Fab")
			(hide yes)
			(effects
				(font
					(size 1 1)
					(thickness 0.15)
				)
				(justify mirror)
			)
		)
		(property "License" "Apache-2.0"
			(at 0 0 180)
			(unlocked yes)
			(layer "B.Fab")
			(hide yes)
			(effects
				(font
					(size 1 1)
					(thickness 0.15)
				)
				(justify mirror)
			)
		)
		(property "Author" "Antmicro"
			(at 0 0 180)
			(unlocked yes)
			(layer "B.Fab")
			(hide yes)
			(effects
				(font
					(size 1 1)
					(thickness 0.15)
				)
				(justify mirror)
			)
		)
		(property "Tolerance" "1%"
			(at 0 0 180)
			(unlocked yes)
			(layer "B.Fab")
			(hide yes)
			(effects
				(font
					(size 1 1)
					(thickness 0.15)
				)
				(justify mirror)
			)
		)
		(sheetname "/HyperRAM + QSPI Flash/")
		(sheetfile "hyperram-flash.kicad_sch")
		(attr smd)
		(fp_rect
			(start -0.925 0.47)
			(end 0.925 -0.47)
			(stroke
				(width 0.05)
				(type default)
			)
			(fill no)
			(layer "B.CrtYd")
		)
		(fp_rect
			(start -0.5 0.25)
			(end 0.5 -0.25)
			(stroke
				(width 0.15)
				(type solid)
			)
			(fill no)
			(layer "B.Fab")
		)
		(fp_text user "License: Apache-2.0"
			(at -0.95 -5.169 0)
			(layer "B.Fab")
			(effects
				(font
					(size 0.7 0.7)
					(thickness 0.15)
				)
				(justify left bottom mirror)
			)
		)
		(fp_text user "Author: Antmicro"
			(at -0.95 -4.169 0)
			(layer "B.Fab")
			(effects
				(font
					(size 0.7 0.7)
					(thickness 0.15)
				)
				(justify left bottom mirror)
			)
		)
		(fp_text user "${REFERENCE}"
			(at -0.95 -3.168 0)
			(layer "B.Fab")
			(effects
				(font
					(size 0.7 0.7)
					(thickness 0.15)
				)
				(justify left bottom mirror)
			)
		)
		(pad "1" smd roundrect
			(at -0.48 0 180)
			(size 0.59 0.64)
			(layers "B.Cu" "B.Mask" "B.Paste")
			(roundrect_rratio 0.25)
			(net 282 "/HyperRAM + QSPI Flash/IO1")
			(pintype "passive")
		)
		(pad "2" smd roundrect
			(at 0.48 0 180)
			(size 0.59 0.64)
			(layers "B.Cu" "B.Mask" "B.Paste")
			(roundrect_rratio 0.25)
			(net 352 "/FPGA Config/FLASH.IO1")
			(pintype "passive")
		)
	)
	(footprint "antmicro-footprints:C_0402_1005Metric_EIA"
		(layer "B.Cu")
		(at 181.5 156)
		(descr "Capacitor SMD 0402 (1005 Metric), square (rectangular) end terminal, IPC_7351 nominal, (Body size source: IPC-SM-782 page 76, https://www.pcb-3d.com/wordpress/wp-content/uploads/ipc-sm-782a_amendment_1_and_2.pdf)")
		(tags "capacitor 0402")
		(property "Reference" "C16"
			(at -3.1 0.45 0)
			(layer "B.SilkS")
			(effects
				(font
					(size 0.7 0.7)
					(thickness 0.15)
				)
				(justify right bottom mirror)
			)
		)
		(property "Value" "C_10u_10V_0402"
			(at 0 -1.169 0)
			(layer "B.Fab")
			(effects
				(font
					(size 0.7 0.7)
					(thickness 0.15)
				)
				(justify right bottom mirror)
			)
		)
		(property "Datasheet" "https://www.murata.com/products/productdetail?partno=GRM155R61A106ME11%23"
			(at 0 0 0)
			(layer "F.Fab")
			(hide yes)
			(effects
				(font
					(size 1.27 1.27)
					(thickness 0.15)
				)
			)
		)
		(property "MPN" "GRM155R61A106ME11D"
			(at 0 0 0)
			(unlocked yes)
			(layer "B.Fab")
			(hide yes)
			(effects
				(font
					(size 1 1)
					(thickness 0.15)
				)
				(justify mirror)
			)
		)
		(property "Manufacturer" "Murata"
			(at 0 0 0)
			(unlocked yes)
			(layer "B.Fab")
			(hide yes)
			(effects
				(font
					(size 1 1)
					(thickness 0.15)
				)
				(justify mirror)
			)
		)
		(property "License" "Apache-2.0"
			(at 0 0 0)
			(unlocked yes)
			(layer "B.Fab")
			(hide yes)
			(effects
				(font
					(size 1 1)
					(thickness 0.15)
				)
				(justify mirror)
			)
		)
		(property "Author" "Antmicro"
			(at 0 0 0)
			(unlocked yes)
			(layer "B.Fab")
			(hide yes)
			(effects
				(font
					(size 1 1)
					(thickness 0.15)
				)
				(justify mirror)
			)
		)
		(property "Val" "10u"
			(at 0 0 0)
			(unlocked yes)
			(layer "B.Fab")
			(hide yes)
			(effects
				(font
					(size 1 1)
					(thickness 0.15)
				)
				(justify mirror)
			)
		)
		(property "Voltage" "10V"
			(at 0 0 0)
			(unlocked yes)
			(layer "B.Fab")
			(hide yes)
			(effects
				(font
					(size 1 1)
					(thickness 0.15)
				)
				(justify mirror)
			)
		)
		(property "Dielectric" "X5R"
			(at 0 0 0)
			(unlocked yes)
			(layer "B.Fab")
			(hide yes)
			(effects
				(font
					(size 1 1)
					(thickness 0.15)
				)
				(justify mirror)
			)
		)
		(sheetname "/FPGA power/")
		(sheetfile "fpga-power.kicad_sch")
		(attr smd)
		(fp_rect
			(start -0.95 0.45)
			(end 0.95 -0.45)
			(stroke
				(width 0.05)
				(type default)
			)
			(fill no)
			(layer "B.CrtYd")
		)
		(fp_line
			(start -0.5 -0.248)
			(end -0.5 0.25)
			(stroke
				(width 0.15)
				(type solid)
			)
			(layer "B.Fab")
		)
		(fp_line
			(start -0.5 0.25)
			(end 0.498 0.25)
			(stroke
				(width 0.15)
				(type solid)
			)
			(layer "B.Fab")
		)
		(fp_line
			(start 0.498 -0.248)
			(end -0.5 -0.248)
			(stroke
				(width 0.15)
				(type solid)
			)
			(layer "B.Fab")
		)
		(fp_line
			(start 0.498 0.25)
			(end 0.498 -0.248)
			(stroke
				(width 0.15)
				(type solid)
			)
			(layer "B.Fab")
		)
		(fp_text user "${REFERENCE}"
			(at -0.9656 -3.169 180)
			(layer "B.Fab")
			(effects
				(font
					(size 0.7 0.7)
					(thickness 0.15)
				)
				(justify left bottom mirror)
			)
		)
		(fp_text user "Author: Antmicro"
			(at -0.9656 -5.569 180)
			(layer "B.Fab")
			(effects
				(font
					(size 0.7 0.7)
					(thickness 0.15)
				)
				(justify left bottom mirror)
			)
		)
		(fp_text user "License: Apache-2.0"
			(at -0.9656 -4.369 180)
			(layer "B.Fab")
			(effects
				(font
					(size 0.7 0.7)
					(thickness 0.15)
				)
				(justify left bottom mirror)
			)
		)
		(pad "1" smd roundrect
			(at -0.5 0 270)
			(size 0.6 0.6)
			(layers "B.Cu" "B.Mask" "B.Paste")
			(roundrect_rratio 0.25)
			(net 1 "GND")
			(pintype "passive")
		)
		(pad "2" smd roundrect
			(at 0.498 0)
			(size 0.6 0.6)
			(layers "B.Cu" "B.Mask" "B.Paste")
			(roundrect_rratio 0.25)
			(net 151 "+3V3")
			(pintype "passive")
		)
	)
	(footprint "antmicro-footprints:C_0402_1005Metric"
		(layer "B.Cu")
		(at 188.4 108.3 180)
		(descr "Capacitor SMD 0402")
		(tags "capacitor SMD 0402")
		(property "Reference" "C9"
			(at -2.48 -0.43 0)
			(layer "B.SilkS")
			(effects
				(font
					(size 0.7 0.7)
					(thickness 0.15)
				)
				(justify left bottom mirror)
			)
		)
		(property "Value" "C_100n_0402"
			(at -1.022927 -2.155213 0)
			(layer "B.Fab")
			(effects
				(font
					(size 0.7 0.7)
					(thickness 0.15)
				)
				(justify left bottom mirror)
			)
		)
		(property "Datasheet" "https://www.murata.com/products/productdetail?partno=GRM155R61H104KE14%23"
			(at 0 0 180)
			(layer "F.Fab")
			(hide yes)
			(effects
				(font
					(size 1.27 1.27)
					(thickness 0.15)
				)
			)
		)
		(property "MPN" "GRM155R61H104KE14D"
			(at 0 0 180)
			(unlocked yes)
			(layer "B.Fab")
			(hide yes)
			(effects
				(font
					(size 1 1)
					(thickness 0.15)
				)
				(justify mirror)
			)
		)
		(property "Manufacturer" "Murata"
			(at 0 0 180)
			(unlocked yes)
			(layer "B.Fab")
			(hide yes)
			(effects
				(font
					(size 1 1)
					(thickness 0.15)
				)
				(justify mirror)
			)
		)
		(property "License" "Apache-2.0"
			(at 0 0 180)
			(unlocked yes)
			(layer "B.Fab")
			(hide yes)
			(effects
				(font
					(size 1 1)
					(thickness 0.15)
				)
				(justify mirror)
			)
		)
		(property "Author" "Antmicro"
			(at 0 0 180)
			(unlocked yes)
			(layer "B.Fab")
			(hide yes)
			(effects
				(font
					(size 1 1)
					(thickness 0.15)
				)
				(justify mirror)
			)
		)
		(property "Val" "100n"
			(at 0 0 180)
			(unlocked yes)
			(layer "B.Fab")
			(hide yes)
			(effects
				(font
					(size 1 1)
					(thickness 0.15)
				)
				(justify mirror)
			)
		)
		(property "Voltage" "50V"
			(at 0 0 180)
			(unlocked yes)
			(layer "B.Fab")
			(hide yes)
			(effects
				(font
					(size 1 1)
					(thickness 0.15)
				)
				(justify mirror)
			)
		)
		(property "Dielectric" "X5R"
			(at 0 0 180)
			(unlocked yes)
			(layer "B.Fab")
			(hide yes)
			(effects
				(font
					(size 1 1)
					(thickness 0.15)
				)
				(justify mirror)
			)
		)
		(sheetname "/DDR5 RDIMM/")
		(sheetfile "ddr5-rdimm.kicad_sch")
		(attr smd)
		(fp_rect
			(start -0.925 0.47)
			(end 0.925 -0.47)
			(stroke
				(width 0.05)
				(type default)
			)
			(fill no)
			(layer "B.CrtYd")
		)
		(fp_line
			(start 0.504 0.25)
			(end 0.504 -0.248)
			(stroke
				(width 0.15)
				(type solid)
			)
			(layer "B.Fab")
		)
		(fp_line
			(start 0.504 -0.248)
			(end -0.494 -0.248)
			(stroke
				(width 0.15)
				(type solid)
			)
			(layer "B.Fab")
		)
		(fp_line
			(start -0.494 0.25)
			(end 0.504 0.25)
			(stroke
				(width 0.15)
				(type solid)
			)
			(layer "B.Fab")
		)
		(fp_line
			(start -0.494 -0.248)
			(end -0.494 0.25)
			(stroke
				(width 0.15)
				(type solid)
			)
			(layer "B.Fab")
		)
		(fp_text user "License: Apache-2.0"
			(at -0.939 -5.799 0)
			(layer "B.Fab")
			(effects
				(font
					(size 0.7 0.7)
					(thickness 0.15)
				)
				(justify left bottom mirror)
			)
		)
		(fp_text user "Author: Antmicro"
			(at -0.939 -3.399 0)
			(layer "B.Fab")
			(effects
				(font
					(size 0.7 0.7)
					(thickness 0.15)
				)
				(justify left bottom mirror)
			)
		)
		(fp_text user "${REFERENCE}"
			(at -0.939 -4.599 0)
			(layer "B.Fab")
			(effects
				(font
					(size 0.7 0.7)
					(thickness 0.15)
				)
				(justify left bottom mirror)
			)
		)
		(pad "1" smd roundrect
			(at -0.48 0 180)
			(size 0.59 0.64)
			(layers "B.Cu" "B.Mask" "B.Paste")
			(roundrect_rratio 0.25)
			(net 1 "GND")
			(pintype "passive")
		)
		(pad "2" smd roundrect
			(at 0.48 0 180)
			(size 0.59 0.64)
			(layers "B.Cu" "B.Mask" "B.Paste")
			(roundrect_rratio 0.25)
			(net 687 "VDDQ")
			(pintype "passive")
		)
	)
	(footprint "antmicro-footprints:TP_SMD_1mm"
		(layer "B.Cu")
		(at 227.9 181.8 90)
		(property "Reference" "TP25"
			(at 0.65 0.5 90)
			(layer "B.SilkS")
			(effects
				(font
					(size 0.7 0.7)
					(thickness 0.15)
				)
				(justify right bottom mirror)
			)
		)
		(property "Value" "TP_1mm_SMD"
			(at 0 -1.4 90)
			(layer "B.Fab")
			(effects
				(font
					(size 0.7 0.7)
					(thickness 0.15)
				)
				(justify right bottom mirror)
			)
		)
		(property "MPN" ""
			(at 0 0 90)
			(unlocked yes)
			(layer "B.Fab")
			(hide yes)
			(effects
				(font
					(size 1 1)
					(thickness 0.15)
				)
				(justify mirror)
			)
		)
		(property "Manufacturer" ""
			(at 0 0 90)
			(unlocked yes)
			(layer "B.Fab")
			(hide yes)
			(effects
				(font
					(size 1 1)
					(thickness 0.15)
				)
				(justify mirror)
			)
		)
		(property "Author" "Antmicro"
			(at 0 0 90)
			(unlocked yes)
			(layer "B.Fab")
			(hide yes)
			(effects
				(font
					(size 1 1)
					(thickness 0.15)
				)
				(justify mirror)
			)
		)
		(property "License" "Apache-2.0"
			(at 0 0 90)
			(unlocked yes)
			(layer "B.Fab")
			(hide yes)
			(effects
				(font
					(size 1 1)
					(thickness 0.15)
				)
				(justify mirror)
			)
		)
		(sheetname "/Supply/DC-DC VCCINT/")
		(sheetfile "dc-dc-vccint.kicad_sch")
		(attr exclude_from_pos_files)
		(fp_circle
			(center 0 0)
			(end 0.6 0)
			(stroke
				(width 0.05)
				(type default)
			)
			(fill no)
			(layer "B.CrtYd")
		)
		(fp_text user "License: Apache-2.0"
			(at -0.5 -5.2 270)
			(layer "B.Fab")
			(effects
				(font
					(size 0.7 0.7)
					(thickness 0.15)
				)
				(justify left bottom mirror)
			)
		)
		(fp_text user "Author: Antmicro"
			(at -0.5 -4 270)
			(layer "B.Fab")
			(effects
				(font
					(size 0.7 0.7)
					(thickness 0.15)
				)
				(justify left bottom mirror)
			)
		)
		(fp_text user "${REFERENCE}"
			(at -0.5 -2.8 270)
			(layer "B.Fab")
			(effects
				(font
					(size 0.7 0.7)
					(thickness 0.15)
				)
				(justify left bottom mirror)
			)
		)
		(pad "1" smd circle
			(at 0 0 90)
			(size 1 1)
			(layers "B.Cu" "B.Mask")
			(net 748 "/Supply/DC-DC VCCINT/PWR.~{ALT}2")
			(pinfunction "1")
			(pintype "passive")
		)
	)
	(footprint "antmicro-footprints:C_0603_1608Metric"
		(layer "B.Cu")
		(at 188.5 150.85 -90)
		(descr "Capacitor SMD 0603")
		(tags "capacitor 0603")
		(property "Reference" "C239"
			(at -12.075 30.6 90)
			(layer "B.SilkS")
			(effects
				(font
					(size 0.7 0.7)
					(thickness 0.15)
				)
				(justify left bottom mirror)
			)
		)
		(property "Value" "C_47u_0603"
			(at -1.42757 -1.770288 90)
			(layer "B.Fab")
			(effects
				(font
					(size 0.7 0.7)
					(thickness 0.15)
				)
				(justify left bottom mirror)
			)
		)
		(property "Datasheet" "https://www.murata.com/products/productdetail?partno=GRM188R60J476ME15%23"
			(at 0 0 270)
			(layer "F.Fab")
			(hide yes)
			(effects
				(font
					(size 1.27 1.27)
					(thickness 0.15)
				)
			)
		)
		(property "Manufacturer" "Murata"
			(at 0 0 270)
			(unlocked yes)
			(layer "B.Fab")
			(hide yes)
			(effects
				(font
					(size 1 1)
					(thickness 0.15)
				)
				(justify mirror)
			)
		)
		(property "MPN" "GRM188R60J476ME15D"
			(at 0 0 270)
			(unlocked yes)
			(layer "B.Fab")
			(hide yes)
			(effects
				(font
					(size 1 1)
					(thickness 0.15)
				)
				(justify mirror)
			)
		)
		(property "Val" "47u"
			(at 0 0 270)
			(unlocked yes)
			(layer "B.Fab")
			(hide yes)
			(effects
				(font
					(size 1 1)
					(thickness 0.15)
				)
				(justify mirror)
			)
		)
		(property "License" "Apache-2.0"
			(at 0 0 270)
			(unlocked yes)
			(layer "B.Fab")
			(hide yes)
			(effects
				(font
					(size 1 1)
					(thickness 0.15)
				)
				(justify mirror)
			)
		)
		(property "Author" "Antmicro"
			(at 0 0 270)
			(unlocked yes)
			(layer "B.Fab")
			(hide yes)
			(effects
				(font
					(size 1 1)
					(thickness 0.15)
				)
				(justify mirror)
			)
		)
		(property "Voltage" ""
			(at 0 0 270)
			(unlocked yes)
			(layer "B.Fab")
			(hide yes)
			(effects
				(font
					(size 1 1)
					(thickness 0.15)
				)
				(justify mirror)
			)
		)
		(property "Dielectric" ""
			(at 0 0 270)
			(unlocked yes)
			(layer "B.Fab")
			(hide yes)
			(effects
				(font
					(size 1 1)
					(thickness 0.15)
				)
				(justify mirror)
			)
		)
		(sheetname "/FPGA power/")
		(sheetfile "fpga-power.kicad_sch")
		(attr smd)
		(fp_line
			(start -0.15 0.4)
			(end 0.15 0.4)
			(stroke
				(width 0.15)
				(type solid)
			)
			(layer "B.SilkS")
		)
		(fp_line
			(start -0.15 -0.4)
			(end 0.15 -0.4)
			(stroke
				(width 0.15)
				(type solid)
			)
			(layer "B.SilkS")
		)
		(fp_rect
			(start -1.25 0.65)
			(end 1.25 -0.65)
			(stroke
				(width 0.05)
				(type solid)
			)
			(fill no)
			(layer "B.CrtYd")
		)
		(fp_rect
			(start -0.8 0.4)
			(end 0.8 -0.4)
			(stroke
				(width 0.15)
				(type solid)
			)
			(fill no)
			(layer "B.Fab")
		)
		(fp_text user "License: Apache-2.0"
			(at -1.682 -5.895 90)
			(layer "B.Fab")
			(effects
				(font
					(size 0.7 0.7)
					(thickness 0.15)
				)
				(justify left bottom mirror)
			)
		)
		(fp_text user "Author: Antmicro"
			(at -1.682 -4.894 90)
			(layer "B.Fab")
			(effects
				(font
					(size 0.7 0.7)
					(thickness 0.15)
				)
				(justify left bottom mirror)
			)
		)
		(fp_text user "${REFERENCE}"
			(at -1.682 -3.895 90)
			(layer "B.Fab")
			(effects
				(font
					(size 0.7 0.7)
					(thickness 0.15)
				)
				(justify left bottom mirror)
			)
		)
		(pad "1" smd roundrect
			(at -0.7 0 270)
			(size 0.8 1)
			(layers "B.Cu" "B.Mask" "B.Paste")
			(roundrect_rratio 0.2)
			(net 553 "+0V85")
			(pintype "passive")
		)
		(pad "2" smd roundrect
			(at 0.7 0 270)
			(size 0.8 1)
			(layers "B.Cu" "B.Mask" "B.Paste")
			(roundrect_rratio 0.2)
			(net 1 "GND")
			(pintype "passive")
		)
	)
	(footprint "antmicro-footprints:C_0402_1005Metric"
		(layer "B.Cu")
		(at 143.57 148.17)
		(descr "Capacitor SMD 0402")
		(tags "capacitor SMD 0402")
		(property "Reference" "C160"
			(at 0.9 0.46 0)
			(layer "B.SilkS")
			(effects
				(font
					(size 0.7 0.7)
					(thickness 0.15)
				)
				(justify right bottom mirror)
			)
		)
		(property "Value" "C_100n_0402"
			(at -1.022927 -2.155213 0)
			(layer "B.Fab")
			(effects
				(font
					(size 0.7 0.7)
					(thickness 0.15)
				)
				(justify right bottom mirror)
			)
		)
		(property "Datasheet" "https://www.murata.com/products/productdetail?partno=GRM155R61H104KE14%23"
			(at 0 0 0)
			(layer "F.Fab")
			(hide yes)
			(effects
				(font
					(size 1.27 1.27)
					(thickness 0.15)
				)
			)
		)
		(property "MPN" "GRM155R61H104KE14D"
			(at 0 0 0)
			(unlocked yes)
			(layer "B.Fab")
			(hide yes)
			(effects
				(font
					(size 1 1)
					(thickness 0.15)
				)
				(justify mirror)
			)
		)
		(property "Manufacturer" "Murata"
			(at 0 0 0)
			(unlocked yes)
			(layer "B.Fab")
			(hide yes)
			(effects
				(font
					(size 1 1)
					(thickness 0.15)
				)
				(justify mirror)
			)
		)
		(property "License" "Apache-2.0"
			(at 0 0 0)
			(unlocked yes)
			(layer "B.Fab")
			(hide yes)
			(effects
				(font
					(size 1 1)
					(thickness 0.15)
				)
				(justify mirror)
			)
		)
		(property "Author" "Antmicro"
			(at 0 0 0)
			(unlocked yes)
			(layer "B.Fab")
			(hide yes)
			(effects
				(font
					(size 1 1)
					(thickness 0.15)
				)
				(justify mirror)
			)
		)
		(property "Val" "100n"
			(at 0 0 0)
			(unlocked yes)
			(layer "B.Fab")
			(hide yes)
			(effects
				(font
					(size 1 1)
					(thickness 0.15)
				)
				(justify mirror)
			)
		)
		(property "Voltage" "50V"
			(at 0 0 0)
			(unlocked yes)
			(layer "B.Fab")
			(hide yes)
			(effects
				(font
					(size 1 1)
					(thickness 0.15)
				)
				(justify mirror)
			)
		)
		(property "Dielectric" "X5R"
			(at 0 0 0)
			(unlocked yes)
			(layer "B.Fab")
			(hide yes)
			(effects
				(font
					(size 1 1)
					(thickness 0.15)
				)
				(justify mirror)
			)
		)
		(sheetname "/Ethernet/")
		(sheetfile "ethernet.kicad_sch")
		(attr smd)
		(fp_rect
			(start -0.925 0.47)
			(end 0.925 -0.47)
			(stroke
				(width 0.05)
				(type default)
			)
			(fill no)
			(layer "B.CrtYd")
		)
		(fp_line
			(start -0.494 -0.248)
			(end -0.494 0.25)
			(stroke
				(width 0.15)
				(type solid)
			)
			(layer "B.Fab")
		)
		(fp_line
			(start -0.494 0.25)
			(end 0.504 0.25)
			(stroke
				(width 0.15)
				(type solid)
			)
			(layer "B.Fab")
		)
		(fp_line
			(start 0.504 -0.248)
			(end -0.494 -0.248)
			(stroke
				(width 0.15)
				(type solid)
			)
			(layer "B.Fab")
		)
		(fp_line
			(start 0.504 0.25)
			(end 0.504 -0.248)
			(stroke
				(width 0.15)
				(type solid)
			)
			(layer "B.Fab")
		)
		(fp_text user "Author: Antmicro"
			(at -0.939 -3.399 180)
			(layer "B.Fab")
			(effects
				(font
					(size 0.7 0.7)
					(thickness 0.15)
				)
				(justify left bottom mirror)
			)
		)
		(fp_text user "${REFERENCE}"
			(at -0.939 -4.599 180)
			(layer "B.Fab")
			(effects
				(font
					(size 0.7 0.7)
					(thickness 0.15)
				)
				(justify left bottom mirror)
			)
		)
		(fp_text user "License: Apache-2.0"
			(at -0.939 -5.799 180)
			(layer "B.Fab")
			(effects
				(font
					(size 0.7 0.7)
					(thickness 0.15)
				)
				(justify left bottom mirror)
			)
		)
		(pad "1" smd roundrect
			(at -0.48 0)
			(size 0.59 0.64)
			(layers "B.Cu" "B.Mask" "B.Paste")
			(roundrect_rratio 0.25)
			(net 1 "GND")
			(pintype "passive")
		)
		(pad "2" smd roundrect
			(at 0.48 0)
			(size 0.59 0.64)
			(layers "B.Cu" "B.Mask" "B.Paste")
			(roundrect_rratio 0.25)
			(net 797 "+1V8")
			(pintype "passive")
		)
	)
	(footprint "antmicro-footprints:R_0402_1005Metric_EIA"
		(layer "B.Cu")
		(at 197 156.5 -90)
		(descr "Resistor SMD 0402 (1005 Metric), square (rectangular) end terminal, IPC_7351 nominal, (Body size source: IPC-SM-782 page 76, https://www.pcb-3d.com/wordpress/wp-content/uploads/ipc-sm-782a_amendment_1_and_2.pdf)")
		(tags "resistor 0402")
		(property "Reference" "R17"
			(at -11.9 30.575 90)
			(layer "B.SilkS")
			(effects
				(font
					(size 0.7 0.7)
					(thickness 0.15)
				)
				(justify left bottom mirror)
			)
		)
		(property "Value" "R_10k_0402"
			(at 0 -1.169 90)
			(layer "B.Fab")
			(effects
				(font
					(size 0.7 0.7)
					(thickness 0.15)
				)
				(justify left bottom mirror)
			)
		)
		(property "Datasheet" "https://www.bourns.com/docs/product-datasheets/cr.pdf"
			(at 0 0 270)
			(layer "F.Fab")
			(hide yes)
			(effects
				(font
					(size 1.27 1.27)
					(thickness 0.15)
				)
			)
		)
		(property "MPN" "CR0402-FX-1002GLF"
			(at 0 0 270)
			(unlocked yes)
			(layer "B.Fab")
			(hide yes)
			(effects
				(font
					(size 1 1)
					(thickness 0.15)
				)
				(justify mirror)
			)
		)
		(property "Manufacturer" "Bourns"
			(at 0 0 270)
			(unlocked yes)
			(layer "B.Fab")
			(hide yes)
			(effects
				(font
					(size 1 1)
					(thickness 0.15)
				)
				(justify mirror)
			)
		)
		(property "License" "Apache-2.0"
			(at 0 0 270)
			(unlocked yes)
			(layer "B.Fab")
			(hide yes)
			(effects
				(font
					(size 1 1)
					(thickness 0.15)
				)
				(justify mirror)
			)
		)
		(property "Author" "Antmicro"
			(at 0 0 270)
			(unlocked yes)
			(layer "B.Fab")
			(hide yes)
			(effects
				(font
					(size 1 1)
					(thickness 0.15)
				)
				(justify mirror)
			)
		)
		(property "Val" "10k"
			(at 0 0 270)
			(unlocked yes)
			(layer "B.Fab")
			(hide yes)
			(effects
				(font
					(size 1 1)
					(thickness 0.15)
				)
				(justify mirror)
			)
		)
		(property "Tolerance" "1%"
			(at 0 0 270)
			(unlocked yes)
			(layer "B.Fab")
			(hide yes)
			(effects
				(font
					(size 1 1)
					(thickness 0.15)
				)
				(justify mirror)
			)
		)
		(sheetname "/FPGA Config/")
		(sheetfile "fpga-config.kicad_sch")
		(attr smd)
		(fp_rect
			(start -0.95 0.45)
			(end 0.95 -0.45)
			(stroke
				(width 0.05)
				(type default)
			)
			(fill no)
			(layer "B.CrtYd")
		)
		(fp_line
			(start -0.5 0.25)
			(end 0.499 0.25)
			(stroke
				(width 0.15)
				(type solid)
			)
			(layer "B.Fab")
		)
		(fp_line
			(start 0.499 0.25)
			(end 0.499 -0.249)
			(stroke
				(width 0.15)
				(type solid)
			)
			(layer "B.Fab")
		)
		(fp_line
			(start -0.5 -0.249)
			(end -0.5 0.25)
			(stroke
				(width 0.15)
				(type solid)
			)
			(layer "B.Fab")
		)
		(fp_line
			(start 0.499 -0.249)
			(end -0.5 -0.249)
			(stroke
				(width 0.15)
				(type solid)
			)
			(layer "B.Fab")
		)
		(fp_text user "Author: Antmicro"
			(at -0.95 -5.569 90)
			(layer "B.Fab")
			(effects
				(font
					(size 0.7 0.7)
					(thickness 0.15)
				)
				(justify left bottom mirror)
			)
		)
		(fp_text user "${REFERENCE}"
			(at -0.95 -3.169 90)
			(layer "B.Fab")
			(effects
				(font
					(size 0.7 0.7)
					(thickness 0.15)
				)
				(justify left bottom mirror)
			)
		)
		(fp_text user "License: Apache-2.0"
			(at -0.95 -4.369 90)
			(layer "B.Fab")
			(effects
				(font
					(size 0.7 0.7)
					(thickness 0.15)
				)
				(justify left bottom mirror)
			)
		)
		(pad "1" smd roundrect
			(at -0.5 0 180)
			(size 0.6 0.6)
			(layers "B.Cu" "B.Mask" "B.Paste")
			(roundrect_rratio 0.25)
			(net 356 "/FPGA Config/MODE0")
			(pintype "passive")
		)
		(pad "2" smd roundrect
			(at 0.499 0 270)
			(size 0.6 0.6)
			(layers "B.Cu" "B.Mask" "B.Paste")
			(roundrect_rratio 0.25)
			(net 797 "+1V8")
			(pintype "passive")
		)
	)
	(footprint "antmicro-footprints:R_0402_1005Metric"
		(layer "B.Cu")
		(at 238.451999 165.225)
		(descr "Resistor SMD 0402")
		(tags "resistor SMD 0402")
		(property "Reference" "R136"
			(at 1.173001 0.475 0)
			(layer "B.SilkS")
			(effects
				(font
					(size 0.7 0.7)
					(thickness 0.15)
				)
				(justify right bottom mirror)
			)
		)
		(property "Value" "R_0R_0402"
			(at -1.011843 -1.772047 0)
			(layer "B.Fab")
			(effects
				(font
					(size 0.7 0.7)
					(thickness 0.15)
				)
				(justify right bottom mirror)
			)
		)
		(property "Datasheet" "https://industrial.panasonic.com/cdbs/www-data/pdf/RDA0000/AOA0000C301.pdf"
			(at 0 0 0)
			(layer "F.Fab")
			(hide yes)
			(effects
				(font
					(size 1.27 1.27)
					(thickness 0.15)
				)
			)
		)
		(property "MPN" "ERJ2GE0R00X"
			(at 0 0 0)
			(unlocked yes)
			(layer "B.Fab")
			(hide yes)
			(effects
				(font
					(size 1 1)
					(thickness 0.15)
				)
				(justify mirror)
			)
		)
		(property "Manufacturer" "Panasonic"
			(at 0 0 0)
			(unlocked yes)
			(layer "B.Fab")
			(hide yes)
			(effects
				(font
					(size 1 1)
					(thickness 0.15)
				)
				(justify mirror)
			)
		)
		(property "License" "Apache-2.0"
			(at 0 0 0)
			(unlocked yes)
			(layer "B.Fab")
			(hide yes)
			(effects
				(font
					(size 1 1)
					(thickness 0.15)
				)
				(justify mirror)
			)
		)
		(property "Author" "Antmicro"
			(at 0 0 0)
			(unlocked yes)
			(layer "B.Fab")
			(hide yes)
			(effects
				(font
					(size 1 1)
					(thickness 0.15)
				)
				(justify mirror)
			)
		)
		(property "Val" "0R"
			(at 0 0 0)
			(unlocked yes)
			(layer "B.Fab")
			(hide yes)
			(effects
				(font
					(size 1 1)
					(thickness 0.15)
				)
				(justify mirror)
			)
		)
		(property "Tolerance" "~"
			(at 0 0 0)
			(unlocked yes)
			(layer "B.Fab")
			(hide yes)
			(effects
				(font
					(size 1 1)
					(thickness 0.15)
				)
				(justify mirror)
			)
		)
		(property "Current" "1A"
			(at 0 0 0)
			(unlocked yes)
			(layer "B.Fab")
			(hide yes)
			(effects
				(font
					(size 1 1)
					(thickness 0.15)
				)
				(justify mirror)
			)
		)
		(sheetname "/Supply/")
		(sheetfile "supply.kicad_sch")
		(attr smd)
		(fp_rect
			(start -0.925 0.47)
			(end 0.925 -0.47)
			(stroke
				(width 0.05)
				(type default)
			)
			(fill no)
			(layer "B.CrtYd")
		)
		(fp_rect
			(start -0.5 0.25)
			(end 0.5 -0.25)
			(stroke
				(width 0.15)
				(type solid)
			)
			(fill no)
			(layer "B.Fab")
		)
		(fp_text user "Author: Antmicro"
			(at -0.95 -4.169 180)
			(layer "B.Fab")
			(effects
				(font
					(size 0.7 0.7)
					(thickness 0.15)
				)
				(justify left bottom mirror)
			)
		)
		(fp_text user "${REFERENCE}"
			(at -0.95 -3.168 180)
			(layer "B.Fab")
			(effects
				(font
					(size 0.7 0.7)
					(thickness 0.15)
				)
				(justify left bottom mirror)
			)
		)
		(fp_text user "License: Apache-2.0"
			(at -0.95 -5.169 180)
			(layer "B.Fab")
			(effects
				(font
					(size 0.7 0.7)
					(thickness 0.15)
				)
				(justify left bottom mirror)
			)
		)
		(pad "1" smd roundrect
			(at -0.48 0)
			(size 0.59 0.64)
			(layers "B.Cu" "B.Mask" "B.Paste")
			(roundrect_rratio 0.25)
			(net 183 "POWER")
			(pintype "passive")
		)
		(pad "2" smd roundrect
			(at 0.48 0)
			(size 0.59 0.64)
			(layers "B.Cu" "B.Mask" "B.Paste")
			(roundrect_rratio 0.25)
			(net 482 "PG1")
			(pintype "passive")
		)
	)
	(footprint "antmicro-footprints:C_0402_1005Metric_EIA"
		(layer "B.Cu")
		(at 190.5 160 180)
		(descr "Capacitor SMD 0402 (1005 Metric), square (rectangular) end terminal, IPC_7351 nominal, (Body size source: IPC-SM-782 page 76, https://www.pcb-3d.com/wordpress/wp-content/uploads/ipc-sm-782a_amendment_1_and_2.pdf)")
		(tags "capacitor 0402")
		(property "Reference" "C96"
			(at 30.125 9.775 0)
			(layer "B.SilkS")
			(effects
				(font
					(size 0.7 0.7)
					(thickness 0.15)
				)
				(justify left bottom mirror)
			)
		)
		(property "Value" "C_100n_0402"
			(at 0 -1.169 0)
			(layer "B.Fab")
			(effects
				(font
					(size 0.7 0.7)
					(thickness 0.15)
				)
				(justify left bottom mirror)
			)
		)
		(property "Datasheet" "https://www.murata.com/products/productdetail?partno=GRM155R61H104KE14%23"
			(at 0 0 180)
			(layer "F.Fab")
			(hide yes)
			(effects
				(font
					(size 1.27 1.27)
					(thickness 0.15)
				)
			)
		)
		(property "MPN" "GRM155R61H104KE14D"
			(at 0 0 180)
			(unlocked yes)
			(layer "B.Fab")
			(hide yes)
			(effects
				(font
					(size 1 1)
					(thickness 0.15)
				)
				(justify mirror)
			)
		)
		(property "Manufacturer" "Murata"
			(at 0 0 180)
			(unlocked yes)
			(layer "B.Fab")
			(hide yes)
			(effects
				(font
					(size 1 1)
					(thickness 0.15)
				)
				(justify mirror)
			)
		)
		(property "License" "Apache-2.0"
			(at 0 0 180)
			(unlocked yes)
			(layer "B.Fab")
			(hide yes)
			(effects
				(font
					(size 1 1)
					(thickness 0.15)
				)
				(justify mirror)
			)
		)
		(property "Author" "Antmicro"
			(at 0 0 180)
			(unlocked yes)
			(layer "B.Fab")
			(hide yes)
			(effects
				(font
					(size 1 1)
					(thickness 0.15)
				)
				(justify mirror)
			)
		)
		(property "Val" "100n"
			(at 0 0 180)
			(unlocked yes)
			(layer "B.Fab")
			(hide yes)
			(effects
				(font
					(size 1 1)
					(thickness 0.15)
				)
				(justify mirror)
			)
		)
		(property "Voltage" "50V"
			(at 0 0 180)
			(unlocked yes)
			(layer "B.Fab")
			(hide yes)
			(effects
				(font
					(size 1 1)
					(thickness 0.15)
				)
				(justify mirror)
			)
		)
		(property "Dielectric" "X5R"
			(at 0 0 180)
			(unlocked yes)
			(layer "B.Fab")
			(hide yes)
			(effects
				(font
					(size 1 1)
					(thickness 0.15)
				)
				(justify mirror)
			)
		)
		(sheetname "/FPGA power/")
		(sheetfile "fpga-power.kicad_sch")
		(attr smd)
		(fp_rect
			(start -0.95 0.45)
			(end 0.95 -0.45)
			(stroke
				(width 0.05)
				(type default)
			)
			(fill no)
			(layer "B.CrtYd")
		)
		(fp_line
			(start 0.498 0.25)
			(end 0.498 -0.248)
			(stroke
				(width 0.15)
				(type solid)
			)
			(layer "B.Fab")
		)
		(fp_line
			(start 0.498 -0.248)
			(end -0.5 -0.248)
			(stroke
				(width 0.15)
				(type solid)
			)
			(layer "B.Fab")
		)
		(fp_line
			(start -0.5 0.25)
			(end 0.498 0.25)
			(stroke
				(width 0.15)
				(type solid)
			)
			(layer "B.Fab")
		)
		(fp_line
			(start -0.5 -0.248)
			(end -0.5 0.25)
			(stroke
				(width 0.15)
				(type solid)
			)
			(layer "B.Fab")
		)
		(fp_text user "${REFERENCE}"
			(at -0.9656 -3.169 0)
			(layer "B.Fab")
			(effects
				(font
					(size 0.7 0.7)
					(thickness 0.15)
				)
				(justify left bottom mirror)
			)
		)
		(fp_text user "License: Apache-2.0"
			(at -0.9656 -4.369 0)
			(layer "B.Fab")
			(effects
				(font
					(size 0.7 0.7)
					(thickness 0.15)
				)
				(justify left bottom mirror)
			)
		)
		(fp_text user "Author: Antmicro"
			(at -0.9656 -5.569 0)
			(layer "B.Fab")
			(effects
				(font
					(size 0.7 0.7)
					(thickness 0.15)
				)
				(justify left bottom mirror)
			)
		)
		(pad "1" smd roundrect
			(at -0.5 0 90)
			(size 0.6 0.6)
			(layers "B.Cu" "B.Mask" "B.Paste")
			(roundrect_rratio 0.25)
			(net 1 "GND")
			(pintype "passive")
		)
		(pad "2" smd roundrect
			(at 0.498 0 180)
			(size 0.6 0.6)
			(layers "B.Cu" "B.Mask" "B.Paste")
			(roundrect_rratio 0.25)
			(net 573 "+1V8_MGTVCCAUX")
			(pintype "passive")
		)
	)
	(footprint "antmicro-footprints:R_0402_1005Metric"
		(layer "B.Cu")
		(at 238.424499 179.449 180)
		(descr "Resistor SMD 0402")
		(tags "resistor SMD 0402")
		(property "Reference" "R177"
			(at -3.95 -0.5 0)
			(layer "B.SilkS")
			(effects
				(font
					(size 0.7 0.7)
					(thickness 0.15)
				)
				(justify left bottom mirror)
			)
		)
		(property "Value" "R_0R_0402"
			(at -1.011843 -1.772047 0)
			(layer "B.Fab")
			(effects
				(font
					(size 0.7 0.7)
					(thickness 0.15)
				)
				(justify left bottom mirror)
			)
		)
		(property "Datasheet" "https://industrial.panasonic.com/cdbs/www-data/pdf/RDA0000/AOA0000C301.pdf"
			(at 0 0 180)
			(layer "F.Fab")
			(hide yes)
			(effects
				(font
					(size 1.27 1.27)
					(thickness 0.15)
				)
			)
		)
		(property "Manufacturer" "Panasonic"
			(at 0 0 180)
			(unlocked yes)
			(layer "B.Fab")
			(hide yes)
			(effects
				(font
					(size 1 1)
					(thickness 0.15)
				)
				(justify mirror)
			)
		)
		(property "MPN" "ERJ2GE0R00X"
			(at 0 0 180)
			(unlocked yes)
			(layer "B.Fab")
			(hide yes)
			(effects
				(font
					(size 1 1)
					(thickness 0.15)
				)
				(justify mirror)
			)
		)
		(property "Val" "0R"
			(at 0 0 180)
			(unlocked yes)
			(layer "B.Fab")
			(hide yes)
			(effects
				(font
					(size 1 1)
					(thickness 0.15)
				)
				(justify mirror)
			)
		)
		(property "License" "Apache-2.0"
			(at 0 0 180)
			(unlocked yes)
			(layer "B.Fab")
			(hide yes)
			(effects
				(font
					(size 1 1)
					(thickness 0.15)
				)
				(justify mirror)
			)
		)
		(property "Author" "Antmicro"
			(at 0 0 180)
			(unlocked yes)
			(layer "B.Fab")
			(hide yes)
			(effects
				(font
					(size 1 1)
					(thickness 0.15)
				)
				(justify mirror)
			)
		)
		(property "Tolerance" "~"
			(at 0 0 180)
			(unlocked yes)
			(layer "B.Fab")
			(hide yes)
			(effects
				(font
					(size 1 1)
					(thickness 0.15)
				)
				(justify mirror)
			)
		)
		(property "Current" "1A"
			(at 0 0 180)
			(unlocked yes)
			(layer "B.Fab")
			(hide yes)
			(effects
				(font
					(size 1 1)
					(thickness 0.15)
				)
				(justify mirror)
			)
		)
		(sheetname "/I^{2}C + I3C/")
		(sheetfile "i2c.kicad_sch")
		(attr smd exclude_from_bom dnp)
		(fp_rect
			(start -0.925 0.47)
			(end 0.925 -0.47)
			(stroke
				(width 0.05)
				(type default)
			)
			(fill no)
			(layer "B.CrtYd")
		)
		(fp_rect
			(start -0.5 0.25)
			(end 0.5 -0.25)
			(stroke
				(width 0.15)
				(type solid)
			)
			(fill no)
			(layer "B.Fab")
		)
		(fp_text user "License: Apache-2.0"
			(at -0.95 -5.169 0)
			(layer "B.Fab")
			(effects
				(font
					(size 0.7 0.7)
					(thickness 0.15)
				)
				(justify left bottom mirror)
			)
		)
		(fp_text user "${REFERENCE}"
			(at -0.95 -3.168 0)
			(layer "B.Fab")
			(effects
				(font
					(size 0.7 0.7)
					(thickness 0.15)
				)
				(justify left bottom mirror)
			)
		)
		(fp_text user "Author: Antmicro"
			(at -0.95 -4.169 0)
			(layer "B.Fab")
			(effects
				(font
					(size 0.7 0.7)
					(thickness 0.15)
				)
				(justify left bottom mirror)
			)
		)
		(pad "1" smd roundrect
			(at -0.48 0 180)
			(size 0.59 0.64)
			(layers "B.Cu" "B.Mask" "B.Paste")
			(roundrect_rratio 0.25)
			(net 749 "/I^{2}C + I3C/PWR.SCL")
			(pintype "passive")
		)
		(pad "2" smd roundrect
			(at 0.48 0 180)
			(size 0.59 0.64)
			(layers "B.Cu" "B.Mask" "B.Paste")
			(roundrect_rratio 0.25)
			(net 465 "/FPGA banks HD/FPGA_DDR.SCL")
			(pintype "passive")
		)
	)
	(footprint "antmicro-footprints:C_0603_1608Metric"
		(layer "B.Cu")
		(at 219.62 172.06 90)
		(descr "Capacitor SMD 0603")
		(tags "capacitor 0603")
		(property "Reference" "C261"
			(at -4.04 0.39 90)
			(layer "B.SilkS")
			(effects
				(font
					(size 0.7 0.7)
					(thickness 0.15)
				)
				(justify right bottom mirror)
			)
		)
		(property "Value" "C_22u_0603"
			(at -1.42757 -1.770288 90)
			(layer "B.Fab")
			(effects
				(font
					(size 0.7 0.7)
					(thickness 0.15)
				)
				(justify right bottom mirror)
			)
		)
		(property "Datasheet" "https://www.murata.com/products/productdetail?partno=GRM188R60J226MEA0%23"
			(at 0 0 90)
			(layer "F.Fab")
			(hide yes)
			(effects
				(font
					(size 1.27 1.27)
					(thickness 0.15)
				)
			)
		)
		(property "Manufacturer" "Murata"
			(at 0 0 90)
			(unlocked yes)
			(layer "B.Fab")
			(hide yes)
			(effects
				(font
					(size 1 1)
					(thickness 0.15)
				)
				(justify mirror)
			)
		)
		(property "MPN" "GRM188R60J226MEA0D"
			(at 0 0 90)
			(unlocked yes)
			(layer "B.Fab")
			(hide yes)
			(effects
				(font
					(size 1 1)
					(thickness 0.15)
				)
				(justify mirror)
			)
		)
		(property "Val" "22u"
			(at 0 0 90)
			(unlocked yes)
			(layer "B.Fab")
			(hide yes)
			(effects
				(font
					(size 1 1)
					(thickness 0.15)
				)
				(justify mirror)
			)
		)
		(property "License" "Apache-2.0"
			(at 0 0 90)
			(unlocked yes)
			(layer "B.Fab")
			(hide yes)
			(effects
				(font
					(size 1 1)
					(thickness 0.15)
				)
				(justify mirror)
			)
		)
		(property "Author" "Antmicro"
			(at 0 0 90)
			(unlocked yes)
			(layer "B.Fab")
			(hide yes)
			(effects
				(font
					(size 1 1)
					(thickness 0.15)
				)
				(justify mirror)
			)
		)
		(property "Voltage" ""
			(at 0 0 90)
			(unlocked yes)
			(layer "B.Fab")
			(hide yes)
			(effects
				(font
					(size 1 1)
					(thickness 0.15)
				)
				(justify mirror)
			)
		)
		(property "Dielectric" ""
			(at 0 0 90)
			(unlocked yes)
			(layer "B.Fab")
			(hide yes)
			(effects
				(font
					(size 1 1)
					(thickness 0.15)
				)
				(justify mirror)
			)
		)
		(sheetname "/Supply/DC-DC VCCINT/")
		(sheetfile "dc-dc-vccint.kicad_sch")
		(attr smd)
		(fp_line
			(start -0.15 -0.4)
			(end 0.15 -0.4)
			(stroke
				(width 0.15)
				(type solid)
			)
			(layer "B.SilkS")
		)
		(fp_line
			(start -0.15 0.4)
			(end 0.15 0.4)
			(stroke
				(width 0.15)
				(type solid)
			)
			(layer "B.SilkS")
		)
		(fp_rect
			(start -1.25 0.65)
			(end 1.25 -0.65)
			(stroke
				(width 0.05)
				(type solid)
			)
			(fill no)
			(layer "B.CrtYd")
		)
		(fp_rect
			(start -0.8 0.4)
			(end 0.8 -0.4)
			(stroke
				(width 0.15)
				(type solid)
			)
			(fill no)
			(layer "B.Fab")
		)
		(fp_text user "Author: Antmicro"
			(at -1.682 -4.894 270)
			(layer "B.Fab")
			(effects
				(font
					(size 0.7 0.7)
					(thickness 0.15)
				)
				(justify left bottom mirror)
			)
		)
		(fp_text user "${REFERENCE}"
			(at -1.682 -3.895 270)
			(layer "B.Fab")
			(effects
				(font
					(size 0.7 0.7)
					(thickness 0.15)
				)
				(justify left bottom mirror)
			)
		)
		(fp_text user "License: Apache-2.0"
			(at -1.682 -5.895 270)
			(layer "B.Fab")
			(effects
				(font
					(size 0.7 0.7)
					(thickness 0.15)
				)
				(justify left bottom mirror)
			)
		)
		(pad "1" smd roundrect
			(at -0.7 0 90)
			(size 0.8 1)
			(layers "B.Cu" "B.Mask" "B.Paste")
			(roundrect_rratio 0.2)
			(net 1 "GND")
			(pintype "passive")
		)
		(pad "2" smd roundrect
			(at 0.7 0 90)
			(size 0.8 1)
			(layers "B.Cu" "B.Mask" "B.Paste")
			(roundrect_rratio 0.2)
			(net 223 "/Supply/DC-DC VCCINT/0V85_REG0")
			(pintype "passive")
		)
	)
	(footprint "antmicro-footprints:R_0402_1005Metric_EIA"
		(layer "B.Cu")
		(at 195.5 154)
		(descr "Resistor SMD 0402 (1005 Metric), square (rectangular) end terminal, IPC_7351 nominal, (Body size source: IPC-SM-782 page 76, https://www.pcb-3d.com/wordpress/wp-content/uploads/ipc-sm-782a_amendment_1_and_2.pdf)")
		(tags "resistor 0402")
		(property "Reference" "R37"
			(at -29.925 -10.3 180)
			(layer "B.SilkS")
			(effects
				(font
					(size 0.7 0.7)
					(thickness 0.15)
				)
				(justify left bottom mirror)
			)
		)
		(property "Value" "R_100R_0402"
			(at 0 -1.169 180)
			(layer "B.Fab")
			(effects
				(font
					(size 0.7 0.7)
					(thickness 0.15)
				)
				(justify left bottom mirror)
			)
		)
		(property "Datasheet" "https://www.bourns.com/docs/product-datasheets/cr.pdf"
			(at 0 0 0)
			(layer "F.Fab")
			(hide yes)
			(effects
				(font
					(size 1.27 1.27)
					(thickness 0.15)
				)
			)
		)
		(property "Manufacturer" "Bourns"
			(at 0 0 0)
			(unlocked yes)
			(layer "B.Fab")
			(hide yes)
			(effects
				(font
					(size 1 1)
					(thickness 0.15)
				)
				(justify mirror)
			)
		)
		(property "MPN" "CR0402-FX-1000GLF"
			(at 0 0 0)
			(unlocked yes)
			(layer "B.Fab")
			(hide yes)
			(effects
				(font
					(size 1 1)
					(thickness 0.15)
				)
				(justify mirror)
			)
		)
		(property "Val" "100R"
			(at 0 0 0)
			(unlocked yes)
			(layer "B.Fab")
			(hide yes)
			(effects
				(font
					(size 1 1)
					(thickness 0.15)
				)
				(justify mirror)
			)
		)
		(property "License" "Apache-2.0"
			(at 0 0 0)
			(unlocked yes)
			(layer "B.Fab")
			(hide yes)
			(effects
				(font
					(size 1 1)
					(thickness 0.15)
				)
				(justify mirror)
			)
		)
		(property "Author" "Antmicro"
			(at 0 0 0)
			(unlocked yes)
			(layer "B.Fab")
			(hide yes)
			(effects
				(font
					(size 1 1)
					(thickness 0.15)
				)
				(justify mirror)
			)
		)
		(property "Tolerance" "1%"
			(at 0 0 0)
			(unlocked yes)
			(layer "B.Fab")
			(hide yes)
			(effects
				(font
					(size 1 1)
					(thickness 0.15)
				)
				(justify mirror)
			)
		)
		(sheetname "/FPGA Config/")
		(sheetfile "fpga-config.kicad_sch")
		(attr smd exclude_from_bom dnp)
		(fp_rect
			(start -0.95 0.45)
			(end 0.95 -0.45)
			(stroke
				(width 0.05)
				(type default)
			)
			(fill no)
			(layer "B.CrtYd")
		)
		(fp_line
			(start -0.5 -0.249)
			(end -0.5 0.25)
			(stroke
				(width 0.15)
				(type solid)
			)
			(layer "B.Fab")
		)
		(fp_line
			(start -0.5 0.25)
			(end 0.499 0.25)
			(stroke
				(width 0.15)
				(type solid)
			)
			(layer "B.Fab")
		)
		(fp_line
			(start 0.499 -0.249)
			(end -0.5 -0.249)
			(stroke
				(width 0.15)
				(type solid)
			)
			(layer "B.Fab")
		)
		(fp_line
			(start 0.499 0.25)
			(end 0.499 -0.249)
			(stroke
				(width 0.15)
				(type solid)
			)
			(layer "B.Fab")
		)
		(fp_text user "Author: Antmicro"
			(at -0.95 -5.569 180)
			(layer "B.Fab")
			(effects
				(font
					(size 0.7 0.7)
					(thickness 0.15)
				)
				(justify left bottom mirror)
			)
		)
		(fp_text user "License: Apache-2.0"
			(at -0.95 -4.369 180)
			(layer "B.Fab")
			(effects
				(font
					(size 0.7 0.7)
					(thickness 0.15)
				)
				(justify left bottom mirror)
			)
		)
		(fp_text user "${REFERENCE}"
			(at -0.95 -3.169 180)
			(layer "B.Fab")
			(effects
				(font
					(size 0.7 0.7)
					(thickness 0.15)
				)
				(justify left bottom mirror)
			)
		)
		(pad "1" smd roundrect
			(at -0.5 0 270)
			(size 0.6 0.6)
			(layers "B.Cu" "B.Mask" "B.Paste")
			(roundrect_rratio 0.25)
			(net 553 "+0V85")
			(pintype "passive")
		)
		(pad "2" smd roundrect
			(at 0.499 0)
			(size 0.6 0.6)
			(layers "B.Cu" "B.Mask" "B.Paste")
			(roundrect_rratio 0.25)
			(net 462 "/FPGA Config/POR_OVERRIDE")
			(pintype "passive")
		)
	)
	(footprint "antmicro-footprints:R_0402_1005Metric"
		(layer "B.Cu")
		(at 245.1 183.149 90)
		(descr "Resistor SMD 0402")
		(tags "resistor SMD 0402")
		(property "Reference" "R223"
			(at 1 0.35 90)
			(layer "B.SilkS")
			(effects
				(font
					(size 0.7 0.7)
					(thickness 0.15)
				)
				(justify right bottom mirror)
			)
		)
		(property "Value" "R_47k_0402"
			(at -1.011843 -1.772047 90)
			(layer "B.Fab")
			(effects
				(font
					(size 0.7 0.7)
					(thickness 0.15)
				)
				(justify right bottom mirror)
			)
		)
		(property "Datasheet" "https://www.bourns.com/docs/product-datasheets/cr.pdf"
			(at 0 0 90)
			(layer "F.Fab")
			(hide yes)
			(effects
				(font
					(size 1.27 1.27)
					(thickness 0.15)
				)
			)
		)
		(property "MPN" "CR0402-FX-4702GLF"
			(at 0 0 90)
			(unlocked yes)
			(layer "B.Fab")
			(hide yes)
			(effects
				(font
					(size 1 1)
					(thickness 0.15)
				)
				(justify mirror)
			)
		)
		(property "Manufacturer" "Bourns"
			(at 0 0 90)
			(unlocked yes)
			(layer "B.Fab")
			(hide yes)
			(effects
				(font
					(size 1 1)
					(thickness 0.15)
				)
				(justify mirror)
			)
		)
		(property "License" "Apache-2.0"
			(at 0 0 90)
			(unlocked yes)
			(layer "B.Fab")
			(hide yes)
			(effects
				(font
					(size 1 1)
					(thickness 0.15)
				)
				(justify mirror)
			)
		)
		(property "Author" "Antmicro"
			(at 0 0 90)
			(unlocked yes)
			(layer "B.Fab")
			(hide yes)
			(effects
				(font
					(size 1 1)
					(thickness 0.15)
				)
				(justify mirror)
			)
		)
		(property "Val" "47k"
			(at 0 0 90)
			(unlocked yes)
			(layer "B.Fab")
			(hide yes)
			(effects
				(font
					(size 1 1)
					(thickness 0.15)
				)
				(justify mirror)
			)
		)
		(property "Tolerance" "1%"
			(at 0 0 90)
			(unlocked yes)
			(layer "B.Fab")
			(hide yes)
			(effects
				(font
					(size 1 1)
					(thickness 0.15)
				)
				(justify mirror)
			)
		)
		(sheetname "/I^{2}C + I3C/")
		(sheetfile "i2c.kicad_sch")
		(attr smd)
		(fp_rect
			(start -0.925 0.47)
			(end 0.925 -0.47)
			(stroke
				(width 0.05)
				(type default)
			)
			(fill no)
			(layer "B.CrtYd")
		)
		(fp_rect
			(start -0.5 0.25)
			(end 0.5 -0.25)
			(stroke
				(width 0.15)
				(type solid)
			)
			(fill no)
			(layer "B.Fab")
		)
		(fp_text user "${REFERENCE}"
			(at -0.95 -3.168 270)
			(layer "B.Fab")
			(effects
				(font
					(size 0.7 0.7)
					(thickness 0.15)
				)
				(justify left bottom mirror)
			)
		)
		(fp_text user "Author: Antmicro"
			(at -0.95 -4.169 270)
			(layer "B.Fab")
			(effects
				(font
					(size 0.7 0.7)
					(thickness 0.15)
				)
				(justify left bottom mirror)
			)
		)
		(fp_text user "License: Apache-2.0"
			(at -0.95 -5.169 270)
			(layer "B.Fab")
			(effects
				(font
					(size 0.7 0.7)
					(thickness 0.15)
				)
				(justify left bottom mirror)
			)
		)
		(pad "1" smd roundrect
			(at -0.48 0 90)
			(size 0.59 0.64)
			(layers "B.Cu" "B.Mask" "B.Paste")
			(roundrect_rratio 0.25)
			(net 778 "~{FPGA_I3C_EXT_PU}")
			(pintype "passive")
		)
		(pad "2" smd roundrect
			(at 0.48 0 90)
			(size 0.59 0.64)
			(layers "B.Cu" "B.Mask" "B.Paste")
			(roundrect_rratio 0.25)
			(net 151 "+3V3")
			(pintype "passive")
		)
	)
	(footprint "antmicro-footprints:R_0402_1005Metric"
		(layer "B.Cu")
		(at 237.925 157.605 -90)
		(descr "Resistor SMD 0402")
		(tags "resistor SMD 0402")
		(property "Reference" "R212"
			(at 0.875 -0.485 90)
			(layer "B.SilkS")
			(effects
				(font
					(size 0.7 0.7)
					(thickness 0.15)
				)
				(justify left bottom mirror)
			)
		)
		(property "Value" "R_0R_0402"
			(at -1.011843 -1.772047 90)
			(layer "B.Fab")
			(effects
				(font
					(size 0.7 0.7)
					(thickness 0.15)
				)
				(justify left bottom mirror)
			)
		)
		(property "Datasheet" "https://industrial.panasonic.com/cdbs/www-data/pdf/RDA0000/AOA0000C301.pdf"
			(at 0 0 270)
			(layer "F.Fab")
			(hide yes)
			(effects
				(font
					(size 1.27 1.27)
					(thickness 0.15)
				)
			)
		)
		(property "MPN" "ERJ2GE0R00X"
			(at 0 0 270)
			(unlocked yes)
			(layer "B.Fab")
			(hide yes)
			(effects
				(font
					(size 1 1)
					(thickness 0.15)
				)
				(justify mirror)
			)
		)
		(property "Manufacturer" "Panasonic"
			(at 0 0 270)
			(unlocked yes)
			(layer "B.Fab")
			(hide yes)
			(effects
				(font
					(size 1 1)
					(thickness 0.15)
				)
				(justify mirror)
			)
		)
		(property "License" "Apache-2.0"
			(at 0 0 270)
			(unlocked yes)
			(layer "B.Fab")
			(hide yes)
			(effects
				(font
					(size 1 1)
					(thickness 0.15)
				)
				(justify mirror)
			)
		)
		(property "Author" "Antmicro"
			(at 0 0 270)
			(unlocked yes)
			(layer "B.Fab")
			(hide yes)
			(effects
				(font
					(size 1 1)
					(thickness 0.15)
				)
				(justify mirror)
			)
		)
		(property "Val" "0R"
			(at 0 0 270)
			(unlocked yes)
			(layer "B.Fab")
			(hide yes)
			(effects
				(font
					(size 1 1)
					(thickness 0.15)
				)
				(justify mirror)
			)
		)
		(property "Tolerance" "~"
			(at 0 0 270)
			(unlocked yes)
			(layer "B.Fab")
			(hide yes)
			(effects
				(font
					(size 1 1)
					(thickness 0.15)
				)
				(justify mirror)
			)
		)
		(property "Current" "1A"
			(at 0 0 270)
			(unlocked yes)
			(layer "B.Fab")
			(hide yes)
			(effects
				(font
					(size 1 1)
					(thickness 0.15)
				)
				(justify mirror)
			)
		)
		(sheetname "/Supply/DC-DC IO/")
		(sheetfile "dc-dc-io.kicad_sch")
		(attr smd)
		(fp_rect
			(start -0.925 0.47)
			(end 0.925 -0.47)
			(stroke
				(width 0.05)
				(type default)
			)
			(fill no)
			(layer "B.CrtYd")
		)
		(fp_rect
			(start -0.5 0.25)
			(end 0.5 -0.25)
			(stroke
				(width 0.15)
				(type solid)
			)
			(fill no)
			(layer "B.Fab")
		)
		(fp_text user "${REFERENCE}"
			(at -0.95 -3.168 90)
			(layer "B.Fab")
			(effects
				(font
					(size 0.7 0.7)
					(thickness 0.15)
				)
				(justify left bottom mirror)
			)
		)
		(fp_text user "License: Apache-2.0"
			(at -0.95 -5.169 90)
			(layer "B.Fab")
			(effects
				(font
					(size 0.7 0.7)
					(thickness 0.15)
				)
				(justify left bottom mirror)
			)
		)
		(fp_text user "Author: Antmicro"
			(at -0.95 -4.169 90)
			(layer "B.Fab")
			(effects
				(font
					(size 0.7 0.7)
					(thickness 0.15)
				)
				(justify left bottom mirror)
			)
		)
		(pad "1" smd roundrect
			(at -0.48 0 270)
			(size 0.59 0.64)
			(layers "B.Cu" "B.Mask" "B.Paste")
			(roundrect_rratio 0.25)
			(net 732 "Net-(U28-IN2+)")
			(pintype "passive")
		)
		(pad "2" smd roundrect
			(at 0.48 0 270)
			(size 0.59 0.64)
			(layers "B.Cu" "B.Mask" "B.Paste")
			(roundrect_rratio 0.25)
			(net 686 "/Supply/DC-DC IO/5V_SEN_+")
			(pintype "passive")
		)
	)
	(footprint "antmicro-footprints:C_0402_1005Metric"
		(layer "B.Cu")
		(at 169.385 158.45 180)
		(descr "Capacitor SMD 0402")
		(tags "capacitor SMD 0402")
		(property "Reference" "C164"
			(at 1.285 -0.45 0)
			(layer "B.SilkS")
			(effects
				(font
					(size 0.7 0.7)
					(thickness 0.15)
				)
				(justify left bottom mirror)
			)
		)
		(property "Value" "C_100n_0402"
			(at -1.022927 -2.155213 0)
			(layer "B.Fab")
			(effects
				(font
					(size 0.7 0.7)
					(thickness 0.15)
				)
				(justify left bottom mirror)
			)
		)
		(property "Datasheet" "https://www.murata.com/products/productdetail?partno=GRM155R61H104KE14%23"
			(at 0 0 180)
			(layer "F.Fab")
			(hide yes)
			(effects
				(font
					(size 1.27 1.27)
					(thickness 0.15)
				)
			)
		)
		(property "MPN" "GRM155R61H104KE14D"
			(at 0 0 180)
			(unlocked yes)
			(layer "B.Fab")
			(hide yes)
			(effects
				(font
					(size 1 1)
					(thickness 0.15)
				)
				(justify mirror)
			)
		)
		(property "Manufacturer" "Murata"
			(at 0 0 180)
			(unlocked yes)
			(layer "B.Fab")
			(hide yes)
			(effects
				(font
					(size 1 1)
					(thickness 0.15)
				)
				(justify mirror)
			)
		)
		(property "License" "Apache-2.0"
			(at 0 0 180)
			(unlocked yes)
			(layer "B.Fab")
			(hide yes)
			(effects
				(font
					(size 1 1)
					(thickness 0.15)
				)
				(justify mirror)
			)
		)
		(property "Author" "Antmicro"
			(at 0 0 180)
			(unlocked yes)
			(layer "B.Fab")
			(hide yes)
			(effects
				(font
					(size 1 1)
					(thickness 0.15)
				)
				(justify mirror)
			)
		)
		(property "Val" "100n"
			(at 0 0 180)
			(unlocked yes)
			(layer "B.Fab")
			(hide yes)
			(effects
				(font
					(size 1 1)
					(thickness 0.15)
				)
				(justify mirror)
			)
		)
		(property "Voltage" "50V"
			(at 0 0 180)
			(unlocked yes)
			(layer "B.Fab")
			(hide yes)
			(effects
				(font
					(size 1 1)
					(thickness 0.15)
				)
				(justify mirror)
			)
		)
		(property "Dielectric" "X5R"
			(at 0 0 180)
			(unlocked yes)
			(layer "B.Fab")
			(hide yes)
			(effects
				(font
					(size 1 1)
					(thickness 0.15)
				)
				(justify mirror)
			)
		)
		(sheetname "/FPGA banks HP/")
		(sheetfile "fpga-hp-banks.kicad_sch")
		(attr smd)
		(fp_rect
			(start -0.925 0.47)
			(end 0.925 -0.47)
			(stroke
				(width 0.05)
				(type default)
			)
			(fill no)
			(layer "B.CrtYd")
		)
		(fp_line
			(start 0.504 0.25)
			(end 0.504 -0.248)
			(stroke
				(width 0.15)
				(type solid)
			)
			(layer "B.Fab")
		)
		(fp_line
			(start 0.504 -0.248)
			(end -0.494 -0.248)
			(stroke
				(width 0.15)
				(type solid)
			)
			(layer "B.Fab")
		)
		(fp_line
			(start -0.494 0.25)
			(end 0.504 0.25)
			(stroke
				(width 0.15)
				(type solid)
			)
			(layer "B.Fab")
		)
		(fp_line
			(start -0.494 -0.248)
			(end -0.494 0.25)
			(stroke
				(width 0.15)
				(type solid)
			)
			(layer "B.Fab")
		)
		(fp_text user "License: Apache-2.0"
			(at -0.939 -5.799 0)
			(layer "B.Fab")
			(effects
				(font
					(size 0.7 0.7)
					(thickness 0.15)
				)
				(justify left bottom mirror)
			)
		)
		(fp_text user "${REFERENCE}"
			(at -0.939 -4.599 0)
			(layer "B.Fab")
			(effects
				(font
					(size 0.7 0.7)
					(thickness 0.15)
				)
				(justify left bottom mirror)
			)
		)
		(fp_text user "Author: Antmicro"
			(at -0.939 -3.399 0)
			(layer "B.Fab")
			(effects
				(font
					(size 0.7 0.7)
					(thickness 0.15)
				)
				(justify left bottom mirror)
			)
		)
		(pad "1" smd roundrect
			(at -0.48 0 180)
			(size 0.59 0.64)
			(layers "B.Cu" "B.Mask" "B.Paste")
			(roundrect_rratio 0.25)
			(net 1 "GND")
			(pintype "passive")
		)
		(pad "2" smd roundrect
			(at 0.48 0 180)
			(size 0.59 0.64)
			(layers "B.Cu" "B.Mask" "B.Paste")
			(roundrect_rratio 0.25)
			(net 151 "+3V3")
			(pintype "passive")
		)
	)
	(footprint "antmicro-footprints:C_0402_1005Metric_EIA"
		(layer "B.Cu")
		(at 182 159.5 -90)
		(descr "Capacitor SMD 0402 (1005 Metric), square (rectangular) end terminal, IPC_7351 nominal, (Body size source: IPC-SM-782 page 76, https://www.pcb-3d.com/wordpress/wp-content/uploads/ipc-sm-782a_amendment_1_and_2.pdf)")
		(tags "capacitor 0402")
		(property "Reference" "C70"
			(at 0 -1.5 90)
			(layer "B.SilkS")
			(effects
				(font
					(size 0.7 0.7)
					(thickness 0.15)
				)
				(justify left bottom mirror)
			)
		)
		(property "Value" "C_10u_10V_0402"
			(at 0 -1.169 90)
			(layer "B.Fab")
			(effects
				(font
					(size 0.7 0.7)
					(thickness 0.15)
				)
				(justify left bottom mirror)
			)
		)
		(property "Datasheet" "https://www.murata.com/products/productdetail?partno=GRM155R61A106ME11%23"
			(at 0 0 270)
			(layer "F.Fab")
			(hide yes)
			(effects
				(font
					(size 1.27 1.27)
					(thickness 0.15)
				)
			)
		)
		(property "MPN" "GRM155R61A106ME11D"
			(at 0 0 270)
			(unlocked yes)
			(layer "B.Fab")
			(hide yes)
			(effects
				(font
					(size 1 1)
					(thickness 0.15)
				)
				(justify mirror)
			)
		)
		(property "Manufacturer" "Murata"
			(at 0 0 270)
			(unlocked yes)
			(layer "B.Fab")
			(hide yes)
			(effects
				(font
					(size 1 1)
					(thickness 0.15)
				)
				(justify mirror)
			)
		)
		(property "License" "Apache-2.0"
			(at 0 0 270)
			(unlocked yes)
			(layer "B.Fab")
			(hide yes)
			(effects
				(font
					(size 1 1)
					(thickness 0.15)
				)
				(justify mirror)
			)
		)
		(property "Author" "Antmicro"
			(at 0 0 270)
			(unlocked yes)
			(layer "B.Fab")
			(hide yes)
			(effects
				(font
					(size 1 1)
					(thickness 0.15)
				)
				(justify mirror)
			)
		)
		(property "Val" "10u"
			(at 0 0 270)
			(unlocked yes)
			(layer "B.Fab")
			(hide yes)
			(effects
				(font
					(size 1 1)
					(thickness 0.15)
				)
				(justify mirror)
			)
		)
		(property "Voltage" "10V"
			(at 0 0 270)
			(unlocked yes)
			(layer "B.Fab")
			(hide yes)
			(effects
				(font
					(size 1 1)
					(thickness 0.15)
				)
				(justify mirror)
			)
		)
		(property "Dielectric" "X5R"
			(at 0 0 270)
			(unlocked yes)
			(layer "B.Fab")
			(hide yes)
			(effects
				(font
					(size 1 1)
					(thickness 0.15)
				)
				(justify mirror)
			)
		)
		(sheetname "/FPGA power/")
		(sheetfile "fpga-power.kicad_sch")
		(attr smd)
		(fp_rect
			(start -0.95 0.45)
			(end 0.95 -0.45)
			(stroke
				(width 0.05)
				(type default)
			)
			(fill no)
			(layer "B.CrtYd")
		)
		(fp_line
			(start -0.5 0.25)
			(end 0.498 0.25)
			(stroke
				(width 0.15)
				(type solid)
			)
			(layer "B.Fab")
		)
		(fp_line
			(start 0.498 0.25)
			(end 0.498 -0.248)
			(stroke
				(width 0.15)
				(type solid)
			)
			(layer "B.Fab")
		)
		(fp_line
			(start -0.5 -0.248)
			(end -0.5 0.25)
			(stroke
				(width 0.15)
				(type solid)
			)
			(layer "B.Fab")
		)
		(fp_line
			(start 0.498 -0.248)
			(end -0.5 -0.248)
			(stroke
				(width 0.15)
				(type solid)
			)
			(layer "B.Fab")
		)
		(fp_text user "Author: Antmicro"
			(at -0.9656 -5.569 90)
			(layer "B.Fab")
			(effects
				(font
					(size 0.7 0.7)
					(thickness 0.15)
				)
				(justify left bottom mirror)
			)
		)
		(fp_text user "License: Apache-2.0"
			(at -0.9656 -4.369 90)
			(layer "B.Fab")
			(effects
				(font
					(size 0.7 0.7)
					(thickness 0.15)
				)
				(justify left bottom mirror)
			)
		)
		(fp_text user "${REFERENCE}"
			(at -0.9656 -3.169 90)
			(layer "B.Fab")
			(effects
				(font
					(size 0.7 0.7)
					(thickness 0.15)
				)
				(justify left bottom mirror)
			)
		)
		(pad "1" smd roundrect
			(at -0.5 0 180)
			(size 0.6 0.6)
			(layers "B.Cu" "B.Mask" "B.Paste")
			(roundrect_rratio 0.25)
			(net 1 "GND")
			(pintype "passive")
		)
		(pad "2" smd roundrect
			(at 0.498 0 270)
			(size 0.6 0.6)
			(layers "B.Cu" "B.Mask" "B.Paste")
			(roundrect_rratio 0.25)
			(net 172 "+1V2_MGTAVTT")
			(pintype "passive")
		)
	)
	(footprint "antmicro-footprints:C_0402_1005Metric_EIA"
		(layer "B.Cu")
		(at 189 162.498 90)
		(descr "Capacitor SMD 0402 (1005 Metric), square (rectangular) end terminal, IPC_7351 nominal, (Body size source: IPC-SM-782 page 76, https://www.pcb-3d.com/wordpress/wp-content/uploads/ipc-sm-782a_amendment_1_and_2.pdf)")
		(tags "capacitor 0402")
		(property "Reference" "C167"
			(at -3.952 0.25 90)
			(layer "B.SilkS")
			(effects
				(font
					(size 0.7 0.7)
					(thickness 0.15)
				)
				(justify right bottom mirror)
			)
		)
		(property "Value" "C_10u_10V_0402"
			(at 0 -1.169 90)
			(layer "B.Fab")
			(effects
				(font
					(size 0.7 0.7)
					(thickness 0.15)
				)
				(justify right bottom mirror)
			)
		)
		(property "Datasheet" "https://www.murata.com/products/productdetail?partno=GRM155R61A106ME11%23"
			(at 0 0 90)
			(layer "F.Fab")
			(hide yes)
			(effects
				(font
					(size 1.27 1.27)
					(thickness 0.15)
				)
			)
		)
		(property "MPN" "GRM155R61A106ME11D"
			(at 0 0 90)
			(unlocked yes)
			(layer "B.Fab")
			(hide yes)
			(effects
				(font
					(size 1 1)
					(thickness 0.15)
				)
				(justify mirror)
			)
		)
		(property "Manufacturer" "Murata"
			(at 0 0 90)
			(unlocked yes)
			(layer "B.Fab")
			(hide yes)
			(effects
				(font
					(size 1 1)
					(thickness 0.15)
				)
				(justify mirror)
			)
		)
		(property "License" "Apache-2.0"
			(at 0 0 90)
			(unlocked yes)
			(layer "B.Fab")
			(hide yes)
			(effects
				(font
					(size 1 1)
					(thickness 0.15)
				)
				(justify mirror)
			)
		)
		(property "Author" "Antmicro"
			(at 0 0 90)
			(unlocked yes)
			(layer "B.Fab")
			(hide yes)
			(effects
				(font
					(size 1 1)
					(thickness 0.15)
				)
				(justify mirror)
			)
		)
		(property "Val" "10u"
			(at 0 0 90)
			(unlocked yes)
			(layer "B.Fab")
			(hide yes)
			(effects
				(font
					(size 1 1)
					(thickness 0.15)
				)
				(justify mirror)
			)
		)
		(property "Voltage" "10V"
			(at 0 0 90)
			(unlocked yes)
			(layer "B.Fab")
			(hide yes)
			(effects
				(font
					(size 1 1)
					(thickness 0.15)
				)
				(justify mirror)
			)
		)
		(property "Dielectric" "X5R"
			(at 0 0 90)
			(unlocked yes)
			(layer "B.Fab")
			(hide yes)
			(effects
				(font
					(size 1 1)
					(thickness 0.15)
				)
				(justify mirror)
			)
		)
		(sheetname "/FPGA power/")
		(sheetfile "fpga-power.kicad_sch")
		(attr smd)
		(fp_rect
			(start -0.95 0.45)
			(end 0.95 -0.45)
			(stroke
				(width 0.05)
				(type default)
			)
			(fill no)
			(layer "B.CrtYd")
		)
		(fp_line
			(start 0.498 -0.248)
			(end -0.5 -0.248)
			(stroke
				(width 0.15)
				(type solid)
			)
			(layer "B.Fab")
		)
		(fp_line
			(start -0.5 -0.248)
			(end -0.5 0.25)
			(stroke
				(width 0.15)
				(type solid)
			)
			(layer "B.Fab")
		)
		(fp_line
			(start 0.498 0.25)
			(end 0.498 -0.248)
			(stroke
				(width 0.15)
				(type solid)
			)
			(layer "B.Fab")
		)
		(fp_line
			(start -0.5 0.25)
			(end 0.498 0.25)
			(stroke
				(width 0.15)
				(type solid)
			)
			(layer "B.Fab")
		)
		(fp_text user "Author: Antmicro"
			(at -0.9656 -5.569 270)
			(layer "B.Fab")
			(effects
				(font
					(size 0.7 0.7)
					(thickness 0.15)
				)
				(justify left bottom mirror)
			)
		)
		(fp_text user "${REFERENCE}"
			(at -0.9656 -3.169 270)
			(layer "B.Fab")
			(effects
				(font
					(size 0.7 0.7)
					(thickness 0.15)
				)
				(justify left bottom mirror)
			)
		)
		(fp_text user "License: Apache-2.0"
			(at -0.9656 -4.369 270)
			(layer "B.Fab")
			(effects
				(font
					(size 0.7 0.7)
					(thickness 0.15)
				)
				(justify left bottom mirror)
			)
		)
		(pad "1" smd roundrect
			(at -0.5 0)
			(size 0.6 0.6)
			(layers "B.Cu" "B.Mask" "B.Paste")
			(roundrect_rratio 0.25)
			(net 1 "GND")
			(pintype "passive")
		)
		(pad "2" smd roundrect
			(at 0.498 0 90)
			(size 0.6 0.6)
			(layers "B.Cu" "B.Mask" "B.Paste")
			(roundrect_rratio 0.25)
			(net 172 "+1V2_MGTAVTT")
			(pintype "passive")
		)
	)
	(footprint "antmicro-footprints:R_0402_1005Metric"
		(layer "B.Cu")
		(at 234.06 134.76 -90)
		(descr "Resistor SMD 0402")
		(tags "resistor SMD 0402")
		(property "Reference" "R127"
			(at 0.99 -0.215 90)
			(layer "B.SilkS")
			(effects
				(font
					(size 0.7 0.7)
					(thickness 0.15)
				)
				(justify left bottom mirror)
			)
		)
		(property "Value" "R_0R_0402"
			(at -1.011843 -1.772047 90)
			(layer "B.Fab")
			(effects
				(font
					(size 0.7 0.7)
					(thickness 0.15)
				)
				(justify left bottom mirror)
			)
		)
		(property "Datasheet" "https://industrial.panasonic.com/cdbs/www-data/pdf/RDA0000/AOA0000C301.pdf"
			(at 0 0 270)
			(layer "F.Fab")
			(hide yes)
			(effects
				(font
					(size 1.27 1.27)
					(thickness 0.15)
				)
			)
		)
		(property "MPN" "ERJ2GE0R00X"
			(at 0 0 270)
			(unlocked yes)
			(layer "B.Fab")
			(hide yes)
			(effects
				(font
					(size 1 1)
					(thickness 0.15)
				)
				(justify mirror)
			)
		)
		(property "Manufacturer" "Panasonic"
			(at 0 0 270)
			(unlocked yes)
			(layer "B.Fab")
			(hide yes)
			(effects
				(font
					(size 1 1)
					(thickness 0.15)
				)
				(justify mirror)
			)
		)
		(property "License" "Apache-2.0"
			(at 0 0 270)
			(unlocked yes)
			(layer "B.Fab")
			(hide yes)
			(effects
				(font
					(size 1 1)
					(thickness 0.15)
				)
				(justify mirror)
			)
		)
		(property "Author" "Antmicro"
			(at 0 0 270)
			(unlocked yes)
			(layer "B.Fab")
			(hide yes)
			(effects
				(font
					(size 1 1)
					(thickness 0.15)
				)
				(justify mirror)
			)
		)
		(property "Val" "0R"
			(at 0 0 270)
			(unlocked yes)
			(layer "B.Fab")
			(hide yes)
			(effects
				(font
					(size 1 1)
					(thickness 0.15)
				)
				(justify mirror)
			)
		)
		(property "Tolerance" "~"
			(at 0 0 270)
			(unlocked yes)
			(layer "B.Fab")
			(hide yes)
			(effects
				(font
					(size 1 1)
					(thickness 0.15)
				)
				(justify mirror)
			)
		)
		(property "Current" "1A"
			(at 0 0 270)
			(unlocked yes)
			(layer "B.Fab")
			(hide yes)
			(effects
				(font
					(size 1 1)
					(thickness 0.15)
				)
				(justify mirror)
			)
		)
		(sheetname "/I^{2}C + I3C/")
		(sheetfile "i2c.kicad_sch")
		(attr smd)
		(fp_rect
			(start -0.925 0.47)
			(end 0.925 -0.47)
			(stroke
				(width 0.05)
				(type default)
			)
			(fill no)
			(layer "B.CrtYd")
		)
		(fp_rect
			(start -0.5 0.25)
			(end 0.5 -0.25)
			(stroke
				(width 0.15)
				(type solid)
			)
			(fill no)
			(layer "B.Fab")
		)
		(fp_text user "${REFERENCE}"
			(at -0.95 -3.168 90)
			(layer "B.Fab")
			(effects
				(font
					(size 0.7 0.7)
					(thickness 0.15)
				)
				(justify left bottom mirror)
			)
		)
		(fp_text user "License: Apache-2.0"
			(at -0.95 -5.169 90)
			(layer "B.Fab")
			(effects
				(font
					(size 0.7 0.7)
					(thickness 0.15)
				)
				(justify left bottom mirror)
			)
		)
		(fp_text user "Author: Antmicro"
			(at -0.95 -4.169 90)
			(layer "B.Fab")
			(effects
				(font
					(size 0.7 0.7)
					(thickness 0.15)
				)
				(justify left bottom mirror)
			)
		)
		(pad "1" smd roundrect
			(at -0.48 0 270)
			(size 0.59 0.64)
			(layers "B.Cu" "B.Mask" "B.Paste")
			(roundrect_rratio 0.25)
			(net 201 "VDDSPD")
			(pintype "passive")
		)
		(pad "2" smd roundrect
			(at 0.48 0 270)
			(size 0.59 0.64)
			(layers "B.Cu" "B.Mask" "B.Paste")
			(roundrect_rratio 0.25)
			(net 797 "+1V8")
			(pintype "passive")
		)
	)
	(footprint "antmicro-footprints:C_0402_1005Metric"
		(layer "B.Cu")
		(at 173.53 150.689999 -90)
		(descr "Capacitor SMD 0402")
		(tags "capacitor SMD 0402")
		(property "Reference" "C316"
			(at 1.010001 -0.37 90)
			(layer "B.SilkS")
			(effects
				(font
					(size 0.7 0.7)
					(thickness 0.15)
				)
				(justify left bottom mirror)
			)
		)
		(property "Value" "C_100n_0402"
			(at -1.022927 -2.155213 90)
			(layer "B.Fab")
			(effects
				(font
					(size 0.7 0.7)
					(thickness 0.15)
				)
				(justify left bottom mirror)
			)
		)
		(property "Datasheet" "https://www.murata.com/products/productdetail?partno=GRM155R61H104KE14%23"
			(at 0 0 270)
			(layer "F.Fab")
			(hide yes)
			(effects
				(font
					(size 1.27 1.27)
					(thickness 0.15)
				)
			)
		)
		(property "MPN" "GRM155R61H104KE14D"
			(at 0 0 270)
			(unlocked yes)
			(layer "B.Fab")
			(hide yes)
			(effects
				(font
					(size 1 1)
					(thickness 0.15)
				)
				(justify mirror)
			)
		)
		(property "Manufacturer" "Murata"
			(at 0 0 270)
			(unlocked yes)
			(layer "B.Fab")
			(hide yes)
			(effects
				(font
					(size 1 1)
					(thickness 0.15)
				)
				(justify mirror)
			)
		)
		(property "License" "Apache-2.0"
			(at 0 0 270)
			(unlocked yes)
			(layer "B.Fab")
			(hide yes)
			(effects
				(font
					(size 1 1)
					(thickness 0.15)
				)
				(justify mirror)
			)
		)
		(property "Author" "Antmicro"
			(at 0 0 270)
			(unlocked yes)
			(layer "B.Fab")
			(hide yes)
			(effects
				(font
					(size 1 1)
					(thickness 0.15)
				)
				(justify mirror)
			)
		)
		(property "Val" "100n"
			(at 0 0 270)
			(unlocked yes)
			(layer "B.Fab")
			(hide yes)
			(effects
				(font
					(size 1 1)
					(thickness 0.15)
				)
				(justify mirror)
			)
		)
		(property "Voltage" "50V"
			(at 0 0 270)
			(unlocked yes)
			(layer "B.Fab")
			(hide yes)
			(effects
				(font
					(size 1 1)
					(thickness 0.15)
				)
				(justify mirror)
			)
		)
		(property "Dielectric" "X5R"
			(at 0 0 270)
			(unlocked yes)
			(layer "B.Fab")
			(hide yes)
			(effects
				(font
					(size 1 1)
					(thickness 0.15)
				)
				(justify mirror)
			)
		)
		(sheetname "/FPGA MGT Interface/")
		(sheetfile "fpga-mgt.kicad_sch")
		(attr smd)
		(fp_rect
			(start -0.925 0.47)
			(end 0.925 -0.47)
			(stroke
				(width 0.05)
				(type default)
			)
			(fill no)
			(layer "B.CrtYd")
		)
		(fp_line
			(start -0.494 0.25)
			(end 0.504 0.25)
			(stroke
				(width 0.15)
				(type solid)
			)
			(layer "B.Fab")
		)
		(fp_line
			(start 0.504 0.25)
			(end 0.504 -0.248)
			(stroke
				(width 0.15)
				(type solid)
			)
			(layer "B.Fab")
		)
		(fp_line
			(start -0.494 -0.248)
			(end -0.494 0.25)
			(stroke
				(width 0.15)
				(type solid)
			)
			(layer "B.Fab")
		)
		(fp_line
			(start 0.504 -0.248)
			(end -0.494 -0.248)
			(stroke
				(width 0.15)
				(type solid)
			)
			(layer "B.Fab")
		)
		(fp_text user "Author: Antmicro"
			(at -0.939 -3.399 90)
			(layer "B.Fab")
			(effects
				(font
					(size 0.7 0.7)
					(thickness 0.15)
				)
				(justify left bottom mirror)
			)
		)
		(fp_text user "License: Apache-2.0"
			(at -0.939 -5.799 90)
			(layer "B.Fab")
			(effects
				(font
					(size 0.7 0.7)
					(thickness 0.15)
				)
				(justify left bottom mirror)
			)
		)
		(fp_text user "${REFERENCE}"
			(at -0.939 -4.599 90)
			(layer "B.Fab")
			(effects
				(font
					(size 0.7 0.7)
					(thickness 0.15)
				)
				(justify left bottom mirror)
			)
		)
		(pad "1" smd roundrect
			(at -0.48 0 270)
			(size 0.59 0.64)
			(layers "B.Cu" "B.Mask" "B.Paste")
			(roundrect_rratio 0.25)
			(net 458 "HDMI_REC_CLK_N")
			(pintype "passive")
		)
		(pad "2" smd roundrect
			(at 0.48 0 270)
			(size 0.59 0.64)
			(layers "B.Cu" "B.Mask" "B.Paste")
			(roundrect_rratio 0.25)
			(net 489 "/FPGA MGT Interface/HDMI_REC_CLK_C_N")
			(pintype "passive")
		)
	)
	(footprint "antmicro-footprints:R_0402_1005Metric"
		(layer "B.Cu")
		(at 219.91 154.389 180)
		(descr "Resistor SMD 0402")
		(tags "resistor SMD 0402")
		(property "Reference" "R3"
			(at -2.5 -0.421 0)
			(layer "B.SilkS")
			(effects
				(font
					(size 0.7 0.7)
					(thickness 0.15)
				)
				(justify left bottom mirror)
			)
		)
		(property "Value" "R_2k2_0402"
			(at 6.885407 -0.258797 0)
			(layer "B.Fab")
			(effects
				(font
					(size 0.7 0.7)
					(thickness 0.15)
				)
				(justify left bottom mirror)
			)
		)
		(property "Datasheet" "https://www.bourns.com/docs/product-datasheets/cr.pdf"
			(at 0 0 180)
			(layer "F.Fab")
			(hide yes)
			(effects
				(font
					(size 1.27 1.27)
					(thickness 0.15)
				)
			)
		)
		(property "Manufacturer" "Bourns"
			(at 0 0 180)
			(unlocked yes)
			(layer "B.Fab")
			(hide yes)
			(effects
				(font
					(size 1 1)
					(thickness 0.15)
				)
				(justify mirror)
			)
		)
		(property "MPN" "CR0402-FX-2201GLF"
			(at 0 0 180)
			(unlocked yes)
			(layer "B.Fab")
			(hide yes)
			(effects
				(font
					(size 1 1)
					(thickness 0.15)
				)
				(justify mirror)
			)
		)
		(property "Val" "2k2"
			(at 0 0 180)
			(unlocked yes)
			(layer "B.Fab")
			(hide yes)
			(effects
				(font
					(size 1 1)
					(thickness 0.15)
				)
				(justify mirror)
			)
		)
		(property "License" "Apache-2.0"
			(at 0 0 180)
			(unlocked yes)
			(layer "B.Fab")
			(hide yes)
			(effects
				(font
					(size 1 1)
					(thickness 0.15)
				)
				(justify mirror)
			)
		)
		(property "Author" "Antmicro"
			(at 0 0 180)
			(unlocked yes)
			(layer "B.Fab")
			(hide yes)
			(effects
				(font
					(size 1 1)
					(thickness 0.15)
				)
				(justify mirror)
			)
		)
		(property "Tolerance" "1%"
			(at 0 0 180)
			(unlocked yes)
			(layer "B.Fab")
			(hide yes)
			(effects
				(font
					(size 1 1)
					(thickness 0.15)
				)
				(justify mirror)
			)
		)
		(sheetname "/HyperRAM + QSPI Flash/")
		(sheetfile "hyperram-flash.kicad_sch")
		(attr smd)
		(fp_rect
			(start -0.925 0.47)
			(end 0.925 -0.47)
			(stroke
				(width 0.05)
				(type default)
			)
			(fill no)
			(layer "B.CrtYd")
		)
		(fp_rect
			(start -0.5 0.25)
			(end 0.5 -0.25)
			(stroke
				(width 0.15)
				(type solid)
			)
			(fill no)
			(layer "B.Fab")
		)
		(fp_text user "${REFERENCE}"
			(at -0.95 -3.168 0)
			(layer "B.Fab")
			(effects
				(font
					(size 0.7 0.7)
					(thickness 0.15)
				)
				(justify left bottom mirror)
			)
		)
		(fp_text user "License: Apache-2.0"
			(at -0.95 -5.169 0)
			(layer "B.Fab")
			(effects
				(font
					(size 0.7 0.7)
					(thickness 0.15)
				)
				(justify left bottom mirror)
			)
		)
		(fp_text user "Author: Antmicro"
			(at -0.95 -4.169 0)
			(layer "B.Fab")
			(effects
				(font
					(size 0.7 0.7)
					(thickness 0.15)
				)
				(justify left bottom mirror)
			)
		)
		(pad "1" smd roundrect
			(at -0.48 0 180)
			(size 0.59 0.64)
			(layers "B.Cu" "B.Mask" "B.Paste")
			(roundrect_rratio 0.25)
			(net 797 "+1V8")
			(pintype "passive")
		)
		(pad "2" smd roundrect
			(at 0.48 0 180)
			(size 0.59 0.64)
			(layers "B.Cu" "B.Mask" "B.Paste")
			(roundrect_rratio 0.25)
			(net 350 "/FPGA Config/FLASH.~{CS}")
			(pintype "passive")
		)
	)
	(footprint "antmicro-footprints:C_0402_1005Metric_EIA"
		(layer "B.Cu")
		(at 190 154.5 -90)
		(descr "Capacitor SMD 0402 (1005 Metric), square (rectangular) end terminal, IPC_7351 nominal, (Body size source: IPC-SM-782 page 76, https://www.pcb-3d.com/wordpress/wp-content/uploads/ipc-sm-782a_amendment_1_and_2.pdf)")
		(tags "capacitor 0402")
		(property "Reference" "C88"
			(at -11.875 30.725 90)
			(layer "B.SilkS")
			(effects
				(font
					(size 0.7 0.7)
					(thickness 0.15)
				)
				(justify left bottom mirror)
			)
		)
		(property "Value" "C_1u_25V_0402"
			(at 0 -1.169 90)
			(layer "B.Fab")
			(effects
				(font
					(size 0.7 0.7)
					(thickness 0.15)
				)
				(justify left bottom mirror)
			)
		)
		(property "Datasheet" "https://www.murata.com/products/productdetail?partno=GRM155R61E105KE11%23"
			(at 0 0 270)
			(layer "F.Fab")
			(hide yes)
			(effects
				(font
					(size 1.27 1.27)
					(thickness 0.15)
				)
			)
		)
		(property "MPN" "GRM155R61E105KE11J"
			(at 0 0 270)
			(unlocked yes)
			(layer "B.Fab")
			(hide yes)
			(effects
				(font
					(size 1 1)
					(thickness 0.15)
				)
				(justify mirror)
			)
		)
		(property "Manufacturer" "Murata"
			(at 0 0 270)
			(unlocked yes)
			(layer "B.Fab")
			(hide yes)
			(effects
				(font
					(size 1 1)
					(thickness 0.15)
				)
				(justify mirror)
			)
		)
		(property "License" "Apache-2.0"
			(at 0 0 270)
			(unlocked yes)
			(layer "B.Fab")
			(hide yes)
			(effects
				(font
					(size 1 1)
					(thickness 0.15)
				)
				(justify mirror)
			)
		)
		(property "Author" "Antmicro"
			(at 0 0 270)
			(unlocked yes)
			(layer "B.Fab")
			(hide yes)
			(effects
				(font
					(size 1 1)
					(thickness 0.15)
				)
				(justify mirror)
			)
		)
		(property "Val" "1u"
			(at 0 0 270)
			(unlocked yes)
			(layer "B.Fab")
			(hide yes)
			(effects
				(font
					(size 1 1)
					(thickness 0.15)
				)
				(justify mirror)
			)
		)
		(property "Voltage" "25V"
			(at 0 0 270)
			(unlocked yes)
			(layer "B.Fab")
			(hide yes)
			(effects
				(font
					(size 1 1)
					(thickness 0.15)
				)
				(justify mirror)
			)
		)
		(property "Dielectric" "X5R"
			(at 0 0 270)
			(unlocked yes)
			(layer "B.Fab")
			(hide yes)
			(effects
				(font
					(size 1 1)
					(thickness 0.15)
				)
				(justify mirror)
			)
		)
		(sheetname "/FPGA power/")
		(sheetfile "fpga-power.kicad_sch")
		(attr smd)
		(fp_rect
			(start -0.95 0.45)
			(end 0.95 -0.45)
			(stroke
				(width 0.05)
				(type default)
			)
			(fill no)
			(layer "B.CrtYd")
		)
		(fp_line
			(start -0.5 0.25)
			(end 0.498 0.25)
			(stroke
				(width 0.15)
				(type solid)
			)
			(layer "B.Fab")
		)
		(fp_line
			(start 0.498 0.25)
			(end 0.498 -0.248)
			(stroke
				(width 0.15)
				(type solid)
			)
			(layer "B.Fab")
		)
		(fp_line
			(start -0.5 -0.248)
			(end -0.5 0.25)
			(stroke
				(width 0.15)
				(type solid)
			)
			(layer "B.Fab")
		)
		(fp_line
			(start 0.498 -0.248)
			(end -0.5 -0.248)
			(stroke
				(width 0.15)
				(type solid)
			)
			(layer "B.Fab")
		)
		(fp_text user "Author: Antmicro"
			(at -0.9656 -5.569 90)
			(layer "B.Fab")
			(effects
				(font
					(size 0.7 0.7)
					(thickness 0.15)
				)
				(justify left bottom mirror)
			)
		)
		(fp_text user "${REFERENCE}"
			(at -0.9656 -3.169 90)
			(layer "B.Fab")
			(effects
				(font
					(size 0.7 0.7)
					(thickness 0.15)
				)
				(justify left bottom mirror)
			)
		)
		(fp_text user "License: Apache-2.0"
			(at -0.9656 -4.369 90)
			(layer "B.Fab")
			(effects
				(font
					(size 0.7 0.7)
					(thickness 0.15)
				)
				(justify left bottom mirror)
			)
		)
		(pad "1" smd roundrect
			(at -0.5 0 180)
			(size 0.6 0.6)
			(layers "B.Cu" "B.Mask" "B.Paste")
			(roundrect_rratio 0.25)
			(net 1 "GND")
			(pintype "passive")
		)
		(pad "2" smd roundrect
			(at 0.498 0 270)
			(size 0.6 0.6)
			(layers "B.Cu" "B.Mask" "B.Paste")
			(roundrect_rratio 0.25)
			(net 553 "+0V85")
			(pintype "passive")
		)
	)
	(footprint "antmicro-footprints:R_0402_1005Metric"
		(layer "B.Cu")
		(at 238.424499 180.449 180)
		(descr "Resistor SMD 0402")
		(tags "resistor SMD 0402")
		(property "Reference" "R179"
			(at -3.95 -0.5 0)
			(layer "B.SilkS")
			(effects
				(font
					(size 0.7 0.7)
					(thickness 0.15)
				)
				(justify left bottom mirror)
			)
		)
		(property "Value" "R_0R_0402"
			(at -1.011843 -1.772047 0)
			(layer "B.Fab")
			(effects
				(font
					(size 0.7 0.7)
					(thickness 0.15)
				)
				(justify left bottom mirror)
			)
		)
		(property "Datasheet" "https://industrial.panasonic.com/cdbs/www-data/pdf/RDA0000/AOA0000C301.pdf"
			(at 0 0 180)
			(layer "F.Fab")
			(hide yes)
			(effects
				(font
					(size 1.27 1.27)
					(thickness 0.15)
				)
			)
		)
		(property "Manufacturer" "Panasonic"
			(at 0 0 180)
			(unlocked yes)
			(layer "B.Fab")
			(hide yes)
			(effects
				(font
					(size 1 1)
					(thickness 0.15)
				)
				(justify mirror)
			)
		)
		(property "MPN" "ERJ2GE0R00X"
			(at 0 0 180)
			(unlocked yes)
			(layer "B.Fab")
			(hide yes)
			(effects
				(font
					(size 1 1)
					(thickness 0.15)
				)
				(justify mirror)
			)
		)
		(property "Val" "0R"
			(at 0 0 180)
			(unlocked yes)
			(layer "B.Fab")
			(hide yes)
			(effects
				(font
					(size 1 1)
					(thickness 0.15)
				)
				(justify mirror)
			)
		)
		(property "License" "Apache-2.0"
			(at 0 0 180)
			(unlocked yes)
			(layer "B.Fab")
			(hide yes)
			(effects
				(font
					(size 1 1)
					(thickness 0.15)
				)
				(justify mirror)
			)
		)
		(property "Author" "Antmicro"
			(at 0 0 180)
			(unlocked yes)
			(layer "B.Fab")
			(hide yes)
			(effects
				(font
					(size 1 1)
					(thickness 0.15)
				)
				(justify mirror)
			)
		)
		(property "Tolerance" "~"
			(at 0 0 180)
			(unlocked yes)
			(layer "B.Fab")
			(hide yes)
			(effects
				(font
					(size 1 1)
					(thickness 0.15)
				)
				(justify mirror)
			)
		)
		(property "Current" "1A"
			(at 0 0 180)
			(unlocked yes)
			(layer "B.Fab")
			(hide yes)
			(effects
				(font
					(size 1 1)
					(thickness 0.15)
				)
				(justify mirror)
			)
		)
		(sheetname "/I^{2}C + I3C/")
		(sheetfile "i2c.kicad_sch")
		(attr smd exclude_from_bom dnp)
		(fp_rect
			(start -0.925 0.47)
			(end 0.925 -0.47)
			(stroke
				(width 0.05)
				(type default)
			)
			(fill no)
			(layer "B.CrtYd")
		)
		(fp_rect
			(start -0.5 0.25)
			(end 0.5 -0.25)
			(stroke
				(width 0.15)
				(type solid)
			)
			(fill no)
			(layer "B.Fab")
		)
		(fp_text user "License: Apache-2.0"
			(at -0.95 -5.169 0)
			(layer "B.Fab")
			(effects
				(font
					(size 0.7 0.7)
					(thickness 0.15)
				)
				(justify left bottom mirror)
			)
		)
		(fp_text user "Author: Antmicro"
			(at -0.95 -4.169 0)
			(layer "B.Fab")
			(effects
				(font
					(size 0.7 0.7)
					(thickness 0.15)
				)
				(justify left bottom mirror)
			)
		)
		(fp_text user "${REFERENCE}"
			(at -0.95 -3.168 0)
			(layer "B.Fab")
			(effects
				(font
					(size 0.7 0.7)
					(thickness 0.15)
				)
				(justify left bottom mirror)
			)
		)
		(pad "1" smd roundrect
			(at -0.48 0 180)
			(size 0.59 0.64)
			(layers "B.Cu" "B.Mask" "B.Paste")
			(roundrect_rratio 0.25)
			(net 749 "/I^{2}C + I3C/PWR.SCL")
			(pintype "passive")
		)
		(pad "2" smd roundrect
			(at 0.48 0 180)
			(size 0.59 0.64)
			(layers "B.Cu" "B.Mask" "B.Paste")
			(roundrect_rratio 0.25)
			(net 526 "/Debug FTDI + VNA/FTDI.SCL")
			(pintype "passive")
		)
	)
	(footprint "antmicro-footprints:C_0402_1005Metric"
		(layer "B.Cu")
		(at 260.524499 156.349 -90)
		(descr "Capacitor SMD 0402")
		(tags "capacitor SMD 0402")
		(property "Reference" "C174"
			(at -1.849 -1.475501 90)
			(layer "B.SilkS")
			(effects
				(font
					(size 0.7 0.7)
					(thickness 0.15)
				)
				(justify left bottom mirror)
			)
		)
		(property "Value" "C_1u_0402"
			(at -1.022927 -2.155213 90)
			(layer "B.Fab")
			(effects
				(font
					(size 0.7 0.7)
					(thickness 0.15)
				)
				(justify left bottom mirror)
			)
		)
		(property "Datasheet" "https://product.tdk.com/en/search/capacitor/ceramic/mlcc/info?part_no=C1005X6S1A105K050BC"
			(at 0 0 270)
			(layer "F.Fab")
			(hide yes)
			(effects
				(font
					(size 1.27 1.27)
					(thickness 0.15)
				)
			)
		)
		(property "Manufacturer" "TDK"
			(at 0 0 270)
			(unlocked yes)
			(layer "B.Fab")
			(hide yes)
			(effects
				(font
					(size 1 1)
					(thickness 0.15)
				)
				(justify mirror)
			)
		)
		(property "MPN" "C1005X6S1A105K050BC"
			(at 0 0 270)
			(unlocked yes)
			(layer "B.Fab")
			(hide yes)
			(effects
				(font
					(size 1 1)
					(thickness 0.15)
				)
				(justify mirror)
			)
		)
		(property "Val" "1u"
			(at 0 0 270)
			(unlocked yes)
			(layer "B.Fab")
			(hide yes)
			(effects
				(font
					(size 1 1)
					(thickness 0.15)
				)
				(justify mirror)
			)
		)
		(property "License" "Apache-2.0"
			(at 0 0 270)
			(unlocked yes)
			(layer "B.Fab")
			(hide yes)
			(effects
				(font
					(size 1 1)
					(thickness 0.15)
				)
				(justify mirror)
			)
		)
		(property "Author" "Antmicro"
			(at 0 0 270)
			(unlocked yes)
			(layer "B.Fab")
			(hide yes)
			(effects
				(font
					(size 1 1)
					(thickness 0.15)
				)
				(justify mirror)
			)
		)
		(property "Voltage" ""
			(at 0 0 270)
			(unlocked yes)
			(layer "B.Fab")
			(hide yes)
			(effects
				(font
					(size 1 1)
					(thickness 0.15)
				)
				(justify mirror)
			)
		)
		(property "Dielectric" ""
			(at 0 0 270)
			(unlocked yes)
			(layer "B.Fab")
			(hide yes)
			(effects
				(font
					(size 1 1)
					(thickness 0.15)
				)
				(justify mirror)
			)
		)
		(sheetname "/Supply/DC-DC IO/")
		(sheetfile "dc-dc-io.kicad_sch")
		(attr smd)
		(fp_rect
			(start -0.925 0.47)
			(end 0.925 -0.47)
			(stroke
				(width 0.05)
				(type default)
			)
			(fill no)
			(layer "B.CrtYd")
		)
		(fp_line
			(start -0.494 0.25)
			(end 0.504 0.25)
			(stroke
				(width 0.15)
				(type solid)
			)
			(layer "B.Fab")
		)
		(fp_line
			(start 0.504 0.25)
			(end 0.504 -0.248)
			(stroke
				(width 0.15)
				(type solid)
			)
			(layer "B.Fab")
		)
		(fp_line
			(start -0.494 -0.248)
			(end -0.494 0.25)
			(stroke
				(width 0.15)
				(type solid)
			)
			(layer "B.Fab")
		)
		(fp_line
			(start 0.504 -0.248)
			(end -0.494 -0.248)
			(stroke
				(width 0.15)
				(type solid)
			)
			(layer "B.Fab")
		)
		(fp_text user "License: Apache-2.0"
			(at -0.939 -5.799 90)
			(layer "B.Fab")
			(effects
				(font
					(size 0.7 0.7)
					(thickness 0.15)
				)
				(justify left bottom mirror)
			)
		)
		(fp_text user "Author: Antmicro"
			(at -0.939 -3.399 90)
			(layer "B.Fab")
			(effects
				(font
					(size 0.7 0.7)
					(thickness 0.15)
				)
				(justify left bottom mirror)
			)
		)
		(fp_text user "${REFERENCE}"
			(at -0.939 -4.599 90)
			(layer "B.Fab")
			(effects
				(font
					(size 0.7 0.7)
					(thickness 0.15)
				)
				(justify left bottom mirror)
			)
		)
		(pad "1" smd roundrect
			(at -0.48 0 270)
			(size 0.59 0.64)
			(layers "B.Cu" "B.Mask" "B.Paste")
			(roundrect_rratio 0.25)
			(net 1 "GND")
			(pintype "passive")
		)
		(pad "2" smd roundrect
			(at 0.48 0 270)
			(size 0.59 0.64)
			(layers "B.Cu" "B.Mask" "B.Paste")
			(roundrect_rratio 0.25)
			(net 36 "/Supply/DC-DC IO/QDCDC2_VCC")
			(pintype "passive")
		)
	)
	(footprint "antmicro-footprints:C_0402_1005Metric"
		(layer "B.Cu")
		(at 163.65 193.299501 90)
		(descr "Capacitor SMD 0402")
		(tags "capacitor SMD 0402")
		(property "Reference" "C232"
			(at 0.994 0.403501 90)
			(layer "B.SilkS")
			(effects
				(font
					(size 0.7 0.7)
					(thickness 0.15)
				)
				(justify right bottom mirror)
			)
		)
		(property "Value" "C_100n_0402"
			(at -1.022927 -2.155213 90)
			(layer "B.Fab")
			(effects
				(font
					(size 0.7 0.7)
					(thickness 0.15)
				)
				(justify right bottom mirror)
			)
		)
		(property "Datasheet" "https://www.murata.com/products/productdetail?partno=GRM155R61H104KE14%23"
			(at 0 0 90)
			(layer "F.Fab")
			(hide yes)
			(effects
				(font
					(size 1.27 1.27)
					(thickness 0.15)
				)
			)
		)
		(property "Manufacturer" "Murata"
			(at 0 0 90)
			(unlocked yes)
			(layer "B.Fab")
			(hide yes)
			(effects
				(font
					(size 1 1)
					(thickness 0.15)
				)
				(justify mirror)
			)
		)
		(property "MPN" "GRM155R61H104KE14D"
			(at 0 0 90)
			(unlocked yes)
			(layer "B.Fab")
			(hide yes)
			(effects
				(font
					(size 1 1)
					(thickness 0.15)
				)
				(justify mirror)
			)
		)
		(property "Val" "100n"
			(at 0 0 90)
			(unlocked yes)
			(layer "B.Fab")
			(hide yes)
			(effects
				(font
					(size 1 1)
					(thickness 0.15)
				)
				(justify mirror)
			)
		)
		(property "License" "Apache-2.0"
			(at 0 0 90)
			(unlocked yes)
			(layer "B.Fab")
			(hide yes)
			(effects
				(font
					(size 1 1)
					(thickness 0.15)
				)
				(justify mirror)
			)
		)
		(property "Author" "Antmicro"
			(at 0 0 90)
			(unlocked yes)
			(layer "B.Fab")
			(hide yes)
			(effects
				(font
					(size 1 1)
					(thickness 0.15)
				)
				(justify mirror)
			)
		)
		(property "Voltage" "50V"
			(at 0 0 90)
			(unlocked yes)
			(layer "B.Fab")
			(hide yes)
			(effects
				(font
					(size 1 1)
					(thickness 0.15)
				)
				(justify mirror)
			)
		)
		(property "Dielectric" "X5R"
			(at 0 0 90)
			(unlocked yes)
			(layer "B.Fab")
			(hide yes)
			(effects
				(font
					(size 1 1)
					(thickness 0.15)
				)
				(justify mirror)
			)
		)
		(sheetname "/FPGA MGT Interface/")
		(sheetfile "fpga-mgt.kicad_sch")
		(attr smd)
		(fp_rect
			(start -0.925 0.47)
			(end 0.925 -0.47)
			(stroke
				(width 0.05)
				(type default)
			)
			(fill no)
			(layer "B.CrtYd")
		)
		(fp_line
			(start 0.504 -0.248)
			(end -0.494 -0.248)
			(stroke
				(width 0.15)
				(type solid)
			)
			(layer "B.Fab")
		)
		(fp_line
			(start -0.494 -0.248)
			(end -0.494 0.25)
			(stroke
				(width 0.15)
				(type solid)
			)
			(layer "B.Fab")
		)
		(fp_line
			(start 0.504 0.25)
			(end 0.504 -0.248)
			(stroke
				(width 0.15)
				(type solid)
			)
			(layer "B.Fab")
		)
		(fp_line
			(start -0.494 0.25)
			(end 0.504 0.25)
			(stroke
				(width 0.15)
				(type solid)
			)
			(layer "B.Fab")
		)
		(fp_text user "License: Apache-2.0"
			(at -0.939 -5.799 270)
			(layer "B.Fab")
			(effects
				(font
					(size 0.7 0.7)
					(thickness 0.15)
				)
				(justify left bottom mirror)
			)
		)
		(fp_text user "Author: Antmicro"
			(at -0.939 -3.399 270)
			(layer "B.Fab")
			(effects
				(font
					(size 0.7 0.7)
					(thickness 0.15)
				)
				(justify left bottom mirror)
			)
		)
		(fp_text user "${REFERENCE}"
			(at -0.939 -4.599 270)
			(layer "B.Fab")
			(effects
				(font
					(size 0.7 0.7)
					(thickness 0.15)
				)
				(justify left bottom mirror)
			)
		)
		(pad "1" smd roundrect
			(at -0.48 0 90)
			(size 0.59 0.64)
			(layers "B.Cu" "B.Mask" "B.Paste")
			(roundrect_rratio 0.25)
			(net 27 "/FPGA MGT Interface/PCIE.TXD0_N")
			(pintype "passive")
		)
		(pad "2" smd roundrect
			(at 0.48 0 90)
			(size 0.59 0.64)
			(layers "B.Cu" "B.Mask" "B.Paste")
			(roundrect_rratio 0.25)
			(net 28 "/FPGA MGT Interface/GTY_225_TX3_N")
			(pintype "passive")
		)
	)
	(footprint "antmicro-footprints:C_0402_1005Metric"
		(layer "B.Cu")
		(at 186.510001 167.45 90)
		(descr "Capacitor SMD 0402")
		(tags "capacitor SMD 0402")
		(property "Reference" "C275"
			(at -4 0.724 90)
			(layer "B.SilkS")
			(effects
				(font
					(size 0.7 0.7)
					(thickness 0.15)
				)
				(justify right bottom mirror)
			)
		)
		(property "Value" "C_100n_0402"
			(at -1.022927 -2.155213 90)
			(layer "B.Fab")
			(effects
				(font
					(size 0.7 0.7)
					(thickness 0.15)
				)
				(justify right bottom mirror)
			)
		)
		(property "Datasheet" "https://www.murata.com/products/productdetail?partno=GRM155R61H104KE14%23"
			(at 0 0 90)
			(layer "F.Fab")
			(hide yes)
			(effects
				(font
					(size 1.27 1.27)
					(thickness 0.15)
				)
			)
		)
		(property "Manufacturer" "Murata"
			(at 0 0 90)
			(unlocked yes)
			(layer "B.Fab")
			(hide yes)
			(effects
				(font
					(size 1 1)
					(thickness 0.15)
				)
				(justify mirror)
			)
		)
		(property "MPN" "GRM155R61H104KE14D"
			(at 0 0 90)
			(unlocked yes)
			(layer "B.Fab")
			(hide yes)
			(effects
				(font
					(size 1 1)
					(thickness 0.15)
				)
				(justify mirror)
			)
		)
		(property "Val" "100n"
			(at 0 0 90)
			(unlocked yes)
			(layer "B.Fab")
			(hide yes)
			(effects
				(font
					(size 1 1)
					(thickness 0.15)
				)
				(justify mirror)
			)
		)
		(property "License" "Apache-2.0"
			(at 0 0 90)
			(unlocked yes)
			(layer "B.Fab")
			(hide yes)
			(effects
				(font
					(size 1 1)
					(thickness 0.15)
				)
				(justify mirror)
			)
		)
		(property "Author" "Antmicro"
			(at 0 0 90)
			(unlocked yes)
			(layer "B.Fab")
			(hide yes)
			(effects
				(font
					(size 1 1)
					(thickness 0.15)
				)
				(justify mirror)
			)
		)
		(property "Voltage" "50V"
			(at 0 0 90)
			(unlocked yes)
			(layer "B.Fab")
			(hide yes)
			(effects
				(font
					(size 1 1)
					(thickness 0.15)
				)
				(justify mirror)
			)
		)
		(property "Dielectric" "X5R"
			(at 0 0 90)
			(unlocked yes)
			(layer "B.Fab")
			(hide yes)
			(effects
				(font
					(size 1 1)
					(thickness 0.15)
				)
				(justify mirror)
			)
		)
		(sheetname "/FPGA MGT Interface/")
		(sheetfile "fpga-mgt.kicad_sch")
		(attr smd)
		(fp_rect
			(start -0.925 0.47)
			(end 0.925 -0.47)
			(stroke
				(width 0.05)
				(type default)
			)
			(fill no)
			(layer "B.CrtYd")
		)
		(fp_line
			(start 0.504 -0.248)
			(end -0.494 -0.248)
			(stroke
				(width 0.15)
				(type solid)
			)
			(layer "B.Fab")
		)
		(fp_line
			(start -0.494 -0.248)
			(end -0.494 0.25)
			(stroke
				(width 0.15)
				(type solid)
			)
			(layer "B.Fab")
		)
		(fp_line
			(start 0.504 0.25)
			(end 0.504 -0.248)
			(stroke
				(width 0.15)
				(type solid)
			)
			(layer "B.Fab")
		)
		(fp_line
			(start -0.494 0.25)
			(end 0.504 0.25)
			(stroke
				(width 0.15)
				(type solid)
			)
			(layer "B.Fab")
		)
		(fp_text user "Author: Antmicro"
			(at -0.939 -3.399 270)
			(layer "B.Fab")
			(effects
				(font
					(size 0.7 0.7)
					(thickness 0.15)
				)
				(justify left bottom mirror)
			)
		)
		(fp_text user "License: Apache-2.0"
			(at -0.939 -5.799 270)
			(layer "B.Fab")
			(effects
				(font
					(size 0.7 0.7)
					(thickness 0.15)
				)
				(justify left bottom mirror)
			)
		)
		(fp_text user "${REFERENCE}"
			(at -0.939 -4.599 270)
			(layer "B.Fab")
			(effects
				(font
					(size 0.7 0.7)
					(thickness 0.15)
				)
				(justify left bottom mirror)
			)
		)
		(pad "1" smd roundrect
			(at -0.48 0 90)
			(size 0.59 0.64)
			(layers "B.Cu" "B.Mask" "B.Paste")
			(roundrect_rratio 0.25)
			(net 246 "/FPGA MGT Interface/HDMI_OUT.D0_P")
			(pintype "passive")
		)
		(pad "2" smd roundrect
			(at 0.48 0 90)
			(size 0.59 0.64)
			(layers "B.Cu" "B.Mask" "B.Paste")
			(roundrect_rratio 0.25)
			(net 632 "/FPGA MGT Interface/HDMI_FPGA.TX0_P")
			(pintype "passive")
		)
	)
	(footprint "antmicro-footprints:C_0402_1005Metric"
		(layer "B.Cu")
		(at 206.64 150.97 90)
		(descr "Capacitor SMD 0402")
		(tags "capacitor SMD 0402")
		(property "Reference" "C205"
			(at 1.05 0.33 90)
			(layer "B.SilkS")
			(effects
				(font
					(size 0.7 0.7)
					(thickness 0.15)
				)
				(justify right bottom mirror)
			)
		)
		(property "Value" "C_100n_0402"
			(at -1.022927 -2.155213 90)
			(layer "B.Fab")
			(effects
				(font
					(size 0.7 0.7)
					(thickness 0.15)
				)
				(justify right bottom mirror)
			)
		)
		(property "Datasheet" "https://www.murata.com/products/productdetail?partno=GRM155R61H104KE14%23"
			(at 0 0 90)
			(layer "F.Fab")
			(hide yes)
			(effects
				(font
					(size 1.27 1.27)
					(thickness 0.15)
				)
			)
		)
		(property "MPN" "GRM155R61H104KE14D"
			(at 0 0 90)
			(unlocked yes)
			(layer "B.Fab")
			(hide yes)
			(effects
				(font
					(size 1 1)
					(thickness 0.15)
				)
				(justify mirror)
			)
		)
		(property "Manufacturer" "Murata"
			(at 0 0 90)
			(unlocked yes)
			(layer "B.Fab")
			(hide yes)
			(effects
				(font
					(size 1 1)
					(thickness 0.15)
				)
				(justify mirror)
			)
		)
		(property "License" "Apache-2.0"
			(at 0 0 90)
			(unlocked yes)
			(layer "B.Fab")
			(hide yes)
			(effects
				(font
					(size 1 1)
					(thickness 0.15)
				)
				(justify mirror)
			)
		)
		(property "Author" "Antmicro"
			(at 0 0 90)
			(unlocked yes)
			(layer "B.Fab")
			(hide yes)
			(effects
				(font
					(size 1 1)
					(thickness 0.15)
				)
				(justify mirror)
			)
		)
		(property "Val" "100n"
			(at 0 0 90)
			(unlocked yes)
			(layer "B.Fab")
			(hide yes)
			(effects
				(font
					(size 1 1)
					(thickness 0.15)
				)
				(justify mirror)
			)
		)
		(property "Voltage" "50V"
			(at 0 0 90)
			(unlocked yes)
			(layer "B.Fab")
			(hide yes)
			(effects
				(font
					(size 1 1)
					(thickness 0.15)
				)
				(justify mirror)
			)
		)
		(property "Dielectric" "X5R"
			(at 0 0 90)
			(unlocked yes)
			(layer "B.Fab")
			(hide yes)
			(effects
				(font
					(size 1 1)
					(thickness 0.15)
				)
				(justify mirror)
			)
		)
		(sheetname "/FPGA Config/")
		(sheetfile "fpga-config.kicad_sch")
		(attr smd)
		(fp_rect
			(start -0.925 0.47)
			(end 0.925 -0.47)
			(stroke
				(width 0.05)
				(type default)
			)
			(fill no)
			(layer "B.CrtYd")
		)
		(fp_line
			(start 0.504 -0.248)
			(end -0.494 -0.248)
			(stroke
				(width 0.15)
				(type solid)
			)
			(layer "B.Fab")
		)
		(fp_line
			(start -0.494 -0.248)
			(end -0.494 0.25)
			(stroke
				(width 0.15)
				(type solid)
			)
			(layer "B.Fab")
		)
		(fp_line
			(start 0.504 0.25)
			(end 0.504 -0.248)
			(stroke
				(width 0.15)
				(type solid)
			)
			(layer "B.Fab")
		)
		(fp_line
			(start -0.494 0.25)
			(end 0.504 0.25)
			(stroke
				(width 0.15)
				(type solid)
			)
			(layer "B.Fab")
		)
		(fp_text user "Author: Antmicro"
			(at -0.939 -3.399 270)
			(layer "B.Fab")
			(effects
				(font
					(size 0.7 0.7)
					(thickness 0.15)
				)
				(justify left bottom mirror)
			)
		)
		(fp_text user "License: Apache-2.0"
			(at -0.939 -5.799 270)
			(layer "B.Fab")
			(effects
				(font
					(size 0.7 0.7)
					(thickness 0.15)
				)
				(justify left bottom mirror)
			)
		)
		(fp_text user "${REFERENCE}"
			(at -0.939 -4.599 270)
			(layer "B.Fab")
			(effects
				(font
					(size 0.7 0.7)
					(thickness 0.15)
				)
				(justify left bottom mirror)
			)
		)
		(pad "1" smd roundrect
			(at -0.48 0 90)
			(size 0.59 0.64)
			(layers "B.Cu" "B.Mask" "B.Paste")
			(roundrect_rratio 0.25)
			(net 1 "GND")
			(pintype "passive")
		)
		(pad "2" smd roundrect
			(at 0.48 0 90)
			(size 0.59 0.64)
			(layers "B.Cu" "B.Mask" "B.Paste")
			(roundrect_rratio 0.25)
			(net 160 "Net-(U30-OUT)")
			(pintype "passive")
		)
	)
	(footprint "antmicro-footprints:SOT-323"
		(layer "B.Cu")
		(at 252.15 183.499)
		(property "Reference" "Q24"
			(at -1.05 -1.7 0)
			(layer "B.SilkS")
			(effects
				(font
					(size 0.7 0.7)
					(thickness 0.15)
				)
				(justify right bottom mirror)
			)
		)
		(property "Value" "BSS84AKW"
			(at 0 -2.749 0)
			(layer "B.Fab")
			(effects
				(font
					(size 0.7 0.7)
					(thickness 0.15)
				)
				(justify right bottom mirror)
			)
		)
		(property "Datasheet" "https://assets.nexperia.com/documents/data-sheet/BSS84AKW.pdf"
			(at 0 0 0)
			(layer "F.Fab")
			(hide yes)
			(effects
				(font
					(size 1.27 1.27)
					(thickness 0.15)
				)
			)
		)
		(property "MPN" "BSS84AKW,115"
			(at 0 0 0)
			(unlocked yes)
			(layer "B.Fab")
			(hide yes)
			(effects
				(font
					(size 1 1)
					(thickness 0.15)
				)
				(justify mirror)
			)
		)
		(property "Manufacturer" "Nexperia"
			(at 0 0 0)
			(unlocked yes)
			(layer "B.Fab")
			(hide yes)
			(effects
				(font
					(size 1 1)
					(thickness 0.15)
				)
				(justify mirror)
			)
		)
		(property "Author" "Antmicro"
			(at 0 0 0)
			(unlocked yes)
			(layer "B.Fab")
			(hide yes)
			(effects
				(font
					(size 1 1)
					(thickness 0.15)
				)
				(justify mirror)
			)
		)
		(property "License" "Apache-2.0"
			(at 0 0 0)
			(unlocked yes)
			(layer "B.Fab")
			(hide yes)
			(effects
				(font
					(size 1 1)
					(thickness 0.15)
				)
				(justify mirror)
			)
		)
		(sheetname "/I^{2}C + I3C/")
		(sheetfile "i2c.kicad_sch")
		(attr smd)
		(fp_line
			(start -0.802 -1.199)
			(end -0.5 -1.199)
			(stroke
				(width 0.15)
				(type solid)
			)
			(layer "B.SilkS")
		)
		(fp_line
			(start -0.802 -1.05)
			(end -0.802 -1.199)
			(stroke
				(width 0.15)
				(type solid)
			)
			(layer "B.SilkS")
		)
		(fp_line
			(start -0.802 1.2)
			(end -0.802 1.05)
			(stroke
				(width 0.15)
				(type solid)
			)
			(layer "B.SilkS")
		)
		(fp_line
			(start -0.402 1.2)
			(end -0.802 1.2)
			(stroke
				(width 0.15)
				(type solid)
			)
			(layer "B.SilkS")
		)
		(fp_line
			(start 0.498 -1.199)
			(end 0.8 -1.199)
			(stroke
				(width 0.15)
				(type solid)
			)
			(layer "B.SilkS")
		)
		(fp_line
			(start 0.498 1.2)
			(end 0.8 1.2)
			(stroke
				(width 0.15)
				(type solid)
			)
			(layer "B.SilkS")
		)
		(fp_line
			(start 0.8 -1.199)
			(end 0.8 -0.9)
			(stroke
				(width 0.15)
				(type solid)
			)
			(layer "B.SilkS")
		)
		(fp_line
			(start 0.8 1.2)
			(end 0.8 0.902)
			(stroke
				(width 0.15)
				(type solid)
			)
			(layer "B.SilkS")
		)
		(fp_circle
			(center -1.05 1.156824)
			(end -1 1.129824)
			(stroke
				(width 0.15)
				(type solid)
			)
			(fill no)
			(layer "B.SilkS")
		)
		(fp_rect
			(start -1.35 1.35)
			(end 1.35 -1.35)
			(stroke
				(width 0.05)
				(type solid)
			)
			(fill no)
			(layer "B.CrtYd")
		)
		(fp_line
			(start -0.677 -1.1)
			(end 0.675 -1.1)
			(stroke
				(width 0.15)
				(type solid)
			)
			(layer "B.Fab")
		)
		(fp_line
			(start -0.677 1.101)
			(end -0.677 -1.1)
			(stroke
				(width 0.15)
				(type solid)
			)
			(layer "B.Fab")
		)
		(fp_line
			(start -0.677 1.101)
			(end 0.675 1.101)
			(stroke
				(width 0.15)
				(type solid)
			)
			(layer "B.Fab")
		)
		(fp_line
			(start 0.675 1.101)
			(end 0.675 -1.1)
			(stroke
				(width 0.15)
				(type solid)
			)
			(layer "B.Fab")
		)
		(fp_text user "${REFERENCE}"
			(at -1.35 -4.749 180)
			(layer "B.Fab")
			(effects
				(font
					(size 0.7 0.7)
					(thickness 0.15)
				)
				(justify left bottom mirror)
			)
		)
		(fp_text user "License: Apache-2.0"
			(at -1.35 -5.949 180)
			(layer "B.Fab")
			(effects
				(font
					(size 0.7 0.7)
					(thickness 0.15)
				)
				(justify left bottom mirror)
			)
		)
		(fp_text user "Author: Antmicro"
			(at -1.35 -7.149 180)
			(layer "B.Fab")
			(effects
				(font
					(size 0.7 0.7)
					(thickness 0.15)
				)
				(justify left bottom mirror)
			)
		)
		(pad "1" smd rect
			(at -0.927 0.652)
			(size 0.55 0.6)
			(layers "B.Cu" "B.Mask" "B.Paste")
			(net 779 "~{I3C_EXT_PU}")
			(pinfunction "G")
			(pintype "bidirectional")
		)
		(pad "2" smd rect
			(at -0.927 -0.65)
			(size 0.55 0.6)
			(layers "B.Cu" "B.Mask" "B.Paste")
			(net 775 "Net-(Q24-S)")
			(pinfunction "S")
			(pintype "bidirectional")
		)
		(pad "3" smd rect
			(at 0.925 0)
			(size 0.55 0.6)
			(layers "B.Cu" "B.Mask" "B.Paste")
			(net 782 "Net-(Q24-D)")
			(pinfunction "D")
			(pintype "bidirectional")
		)
	)
	(footprint "antmicro-footprints:R_0402_1005Metric"
		(layer "B.Cu")
		(at 238.424499 187.849 180)
		(descr "Resistor SMD 0402")
		(tags "resistor SMD 0402")
		(property "Reference" "R176"
			(at -3.95 -0.5 0)
			(layer "B.SilkS")
			(effects
				(font
					(size 0.7 0.7)
					(thickness 0.15)
				)
				(justify left bottom mirror)
			)
		)
		(property "Value" "R_0R_0402"
			(at -1.011843 -1.772047 0)
			(layer "B.Fab")
			(effects
				(font
					(size 0.7 0.7)
					(thickness 0.15)
				)
				(justify left bottom mirror)
			)
		)
		(property "Datasheet" "https://industrial.panasonic.com/cdbs/www-data/pdf/RDA0000/AOA0000C301.pdf"
			(at 0 0 180)
			(layer "F.Fab")
			(hide yes)
			(effects
				(font
					(size 1.27 1.27)
					(thickness 0.15)
				)
			)
		)
		(property "Manufacturer" "Panasonic"
			(at 0 0 180)
			(unlocked yes)
			(layer "B.Fab")
			(hide yes)
			(effects
				(font
					(size 1 1)
					(thickness 0.15)
				)
				(justify mirror)
			)
		)
		(property "MPN" "ERJ2GE0R00X"
			(at 0 0 180)
			(unlocked yes)
			(layer "B.Fab")
			(hide yes)
			(effects
				(font
					(size 1 1)
					(thickness 0.15)
				)
				(justify mirror)
			)
		)
		(property "Val" "0R"
			(at 0 0 180)
			(unlocked yes)
			(layer "B.Fab")
			(hide yes)
			(effects
				(font
					(size 1 1)
					(thickness 0.15)
				)
				(justify mirror)
			)
		)
		(property "License" "Apache-2.0"
			(at 0 0 180)
			(unlocked yes)
			(layer "B.Fab")
			(hide yes)
			(effects
				(font
					(size 1 1)
					(thickness 0.15)
				)
				(justify mirror)
			)
		)
		(property "Author" "Antmicro"
			(at 0 0 180)
			(unlocked yes)
			(layer "B.Fab")
			(hide yes)
			(effects
				(font
					(size 1 1)
					(thickness 0.15)
				)
				(justify mirror)
			)
		)
		(property "Tolerance" "~"
			(at 0 0 180)
			(unlocked yes)
			(layer "B.Fab")
			(hide yes)
			(effects
				(font
					(size 1 1)
					(thickness 0.15)
				)
				(justify mirror)
			)
		)
		(property "Current" "1A"
			(at 0 0 180)
			(unlocked yes)
			(layer "B.Fab")
			(hide yes)
			(effects
				(font
					(size 1 1)
					(thickness 0.15)
				)
				(justify mirror)
			)
		)
		(sheetname "/I^{2}C + I3C/")
		(sheetfile "i2c.kicad_sch")
		(attr smd exclude_from_bom dnp)
		(fp_rect
			(start -0.925 0.47)
			(end 0.925 -0.47)
			(stroke
				(width 0.05)
				(type default)
			)
			(fill no)
			(layer "B.CrtYd")
		)
		(fp_rect
			(start -0.5 0.25)
			(end 0.5 -0.25)
			(stroke
				(width 0.15)
				(type solid)
			)
			(fill no)
			(layer "B.Fab")
		)
		(fp_text user "License: Apache-2.0"
			(at -0.95 -5.169 0)
			(layer "B.Fab")
			(effects
				(font
					(size 0.7 0.7)
					(thickness 0.15)
				)
				(justify left bottom mirror)
			)
		)
		(fp_text user "Author: Antmicro"
			(at -0.95 -4.169 0)
			(layer "B.Fab")
			(effects
				(font
					(size 0.7 0.7)
					(thickness 0.15)
				)
				(justify left bottom mirror)
			)
		)
		(fp_text user "${REFERENCE}"
			(at -0.95 -3.168 0)
			(layer "B.Fab")
			(effects
				(font
					(size 0.7 0.7)
					(thickness 0.15)
				)
				(justify left bottom mirror)
			)
		)
		(pad "1" smd roundrect
			(at -0.48 0 180)
			(size 0.59 0.64)
			(layers "B.Cu" "B.Mask" "B.Paste")
			(roundrect_rratio 0.25)
			(net 533 "/I^{2}C + I3C/PWR.SDA")
			(pintype "passive")
		)
		(pad "2" smd roundrect
			(at 0.48 0 180)
			(size 0.59 0.64)
			(layers "B.Cu" "B.Mask" "B.Paste")
			(roundrect_rratio 0.25)
			(net 527 "/Debug FTDI + VNA/FTDI.SDA")
			(pintype "passive")
		)
	)
	(footprint "antmicro-footprints:R_0402_1005Metric"
		(layer "B.Cu")
		(at 203.25 136.0045)
		(descr "Resistor SMD 0402")
		(tags "resistor SMD 0402")
		(property "Reference" "R254"
			(at -2.35 0 0)
			(layer "B.SilkS")
			(effects
				(font
					(size 0.7 0.7)
					(thickness 0.15)
				)
				(justify mirror)
			)
		)
		(property "Value" "R_1k_0402"
			(at -1.011843 -1.772047 0)
			(layer "B.Fab")
			(effects
				(font
					(size 0.7 0.7)
					(thickness 0.15)
				)
				(justify right top mirror)
			)
		)
		(property "Datasheet" "https://www.bourns.com/docs/product-datasheets/cr.pdf"
			(at 0 0 0)
			(layer "B.Fab")
			(hide yes)
			(effects
				(font
					(size 1.27 1.27)
					(thickness 0.15)
				)
				(justify mirror)
			)
		)
		(property "MPN" "CR0402-FX-1001GLF"
			(at 0 0 180)
			(unlocked yes)
			(layer "B.Fab")
			(hide yes)
			(effects
				(font
					(size 1 1)
					(thickness 0.15)
				)
				(justify mirror)
			)
		)
		(property "Manufacturer" "Bourns"
			(at 0 0 180)
			(unlocked yes)
			(layer "B.Fab")
			(hide yes)
			(effects
				(font
					(size 1 1)
					(thickness 0.15)
				)
				(justify mirror)
			)
		)
		(property "License" "Apache-2.0"
			(at 0 0 180)
			(unlocked yes)
			(layer "B.Fab")
			(hide yes)
			(effects
				(font
					(size 1 1)
					(thickness 0.15)
				)
				(justify mirror)
			)
		)
		(property "Author" "Antmicro"
			(at 0 0 180)
			(unlocked yes)
			(layer "B.Fab")
			(hide yes)
			(effects
				(font
					(size 1 1)
					(thickness 0.15)
				)
				(justify mirror)
			)
		)
		(property "Val" "1k"
			(at 0 0 180)
			(unlocked yes)
			(layer "B.Fab")
			(hide yes)
			(effects
				(font
					(size 1 1)
					(thickness 0.15)
				)
				(justify mirror)
			)
		)
		(property "Tolerance" "1%"
			(at 0 0 180)
			(unlocked yes)
			(layer "B.Fab")
			(hide yes)
			(effects
				(font
					(size 1 1)
					(thickness 0.15)
				)
				(justify mirror)
			)
		)
		(sheetname "/FPGA banks HP/")
		(sheetfile "fpga-hp-banks.kicad_sch")
		(attr smd)
		(fp_rect
			(start -0.925 0.47)
			(end 0.925 -0.47)
			(stroke
				(width 0.05)
				(type default)
			)
			(fill no)
			(layer "B.CrtYd")
		)
		(fp_rect
			(start -0.5 0.25)
			(end 0.5 -0.25)
			(stroke
				(width 0.15)
				(type solid)
			)
			(fill no)
			(layer "B.Fab")
		)
		(fp_text user "${REFERENCE}"
			(at -0.95 -3.168 0)
			(layer "B.Fab")
			(effects
				(font
					(size 0.7 0.7)
					(thickness 0.15)
				)
				(justify right top mirror)
			)
		)
		(fp_text user "License: Apache-2.0"
			(at -0.95 -5.169 0)
			(layer "B.Fab")
			(effects
				(font
					(size 0.7 0.7)
					(thickness 0.15)
				)
				(justify right top mirror)
			)
		)
		(fp_text user "Author: Antmicro"
			(at -0.95 -4.169 0)
			(layer "B.Fab")
			(effects
				(font
					(size 0.7 0.7)
					(thickness 0.15)
				)
				(justify right top mirror)
			)
		)
		(pad "1" smd roundrect
			(at -0.48 0)
			(size 0.59 0.64)
			(layers "B.Cu" "B.Mask" "B.Paste")
			(roundrect_rratio 0.25)
			(net 1 "GND")
			(pintype "passive")
		)
		(pad "2" smd roundrect
			(at 0.48 0)
			(size 0.59 0.64)
			(layers "B.Cu" "B.Mask" "B.Paste")
			(roundrect_rratio 0.25)
			(net 827 "Net-(R253-Pad1)")
			(pintype "passive")
		)
	)
	(footprint "antmicro-footprints:C_0603_1608Metric"
		(layer "B.Cu")
		(at 188.5 145.75 -90)
		(descr "Capacitor SMD 0603")
		(tags "capacitor 0603")
		(property "Reference" "C44"
			(at -11.875 30.65 90)
			(layer "B.SilkS")
			(effects
				(font
					(size 0.7 0.7)
					(thickness 0.15)
				)
				(justify left bottom mirror)
			)
		)
		(property "Value" "C_47u_0603"
			(at -1.42757 -1.770288 90)
			(layer "B.Fab")
			(effects
				(font
					(size 0.7 0.7)
					(thickness 0.15)
				)
				(justify left bottom mirror)
			)
		)
		(property "Datasheet" "https://www.murata.com/products/productdetail?partno=GRM188R60J476ME15%23"
			(at 0 0 270)
			(layer "F.Fab")
			(hide yes)
			(effects
				(font
					(size 1.27 1.27)
					(thickness 0.15)
				)
			)
		)
		(property "Manufacturer" "Murata"
			(at 0 0 270)
			(unlocked yes)
			(layer "B.Fab")
			(hide yes)
			(effects
				(font
					(size 1 1)
					(thickness 0.15)
				)
				(justify mirror)
			)
		)
		(property "MPN" "GRM188R60J476ME15D"
			(at 0 0 270)
			(unlocked yes)
			(layer "B.Fab")
			(hide yes)
			(effects
				(font
					(size 1 1)
					(thickness 0.15)
				)
				(justify mirror)
			)
		)
		(property "Val" "47u"
			(at 0 0 270)
			(unlocked yes)
			(layer "B.Fab")
			(hide yes)
			(effects
				(font
					(size 1 1)
					(thickness 0.15)
				)
				(justify mirror)
			)
		)
		(property "License" "Apache-2.0"
			(at 0 0 270)
			(unlocked yes)
			(layer "B.Fab")
			(hide yes)
			(effects
				(font
					(size 1 1)
					(thickness 0.15)
				)
				(justify mirror)
			)
		)
		(property "Author" "Antmicro"
			(at 0 0 270)
			(unlocked yes)
			(layer "B.Fab")
			(hide yes)
			(effects
				(font
					(size 1 1)
					(thickness 0.15)
				)
				(justify mirror)
			)
		)
		(property "Voltage" ""
			(at 0 0 270)
			(unlocked yes)
			(layer "B.Fab")
			(hide yes)
			(effects
				(font
					(size 1 1)
					(thickness 0.15)
				)
				(justify mirror)
			)
		)
		(property "Dielectric" ""
			(at 0 0 270)
			(unlocked yes)
			(layer "B.Fab")
			(hide yes)
			(effects
				(font
					(size 1 1)
					(thickness 0.15)
				)
				(justify mirror)
			)
		)
		(sheetname "/FPGA power/")
		(sheetfile "fpga-power.kicad_sch")
		(attr smd)
		(fp_line
			(start -0.15 0.4)
			(end 0.15 0.4)
			(stroke
				(width 0.15)
				(type solid)
			)
			(layer "B.SilkS")
		)
		(fp_line
			(start -0.15 -0.4)
			(end 0.15 -0.4)
			(stroke
				(width 0.15)
				(type solid)
			)
			(layer "B.SilkS")
		)
		(fp_rect
			(start -1.25 0.65)
			(end 1.25 -0.65)
			(stroke
				(width 0.05)
				(type solid)
			)
			(fill no)
			(layer "B.CrtYd")
		)
		(fp_rect
			(start -0.8 0.4)
			(end 0.8 -0.4)
			(stroke
				(width 0.15)
				(type solid)
			)
			(fill no)
			(layer "B.Fab")
		)
		(fp_text user "${REFERENCE}"
			(at -1.682 -3.895 90)
			(layer "B.Fab")
			(effects
				(font
					(size 0.7 0.7)
					(thickness 0.15)
				)
				(justify left bottom mirror)
			)
		)
		(fp_text user "License: Apache-2.0"
			(at -1.682 -5.895 90)
			(layer "B.Fab")
			(effects
				(font
					(size 0.7 0.7)
					(thickness 0.15)
				)
				(justify left bottom mirror)
			)
		)
		(fp_text user "Author: Antmicro"
			(at -1.682 -4.894 90)
			(layer "B.Fab")
			(effects
				(font
					(size 0.7 0.7)
					(thickness 0.15)
				)
				(justify left bottom mirror)
			)
		)
		(pad "1" smd roundrect
			(at -0.7 0 270)
			(size 0.8 1)
			(layers "B.Cu" "B.Mask" "B.Paste")
			(roundrect_rratio 0.2)
			(net 687 "VDDQ")
			(pintype "passive")
		)
		(pad "2" smd roundrect
			(at 0.7 0 270)
			(size 0.8 1)
			(layers "B.Cu" "B.Mask" "B.Paste")
			(roundrect_rratio 0.2)
			(net 1 "GND")
			(pintype "passive")
		)
	)
	(footprint "antmicro-footprints:C_0402_1005Metric_EIA"
		(layer "B.Cu")
		(at 183 150.519 -90)
		(descr "Capacitor SMD 0402 (1005 Metric), square (rectangular) end terminal, IPC_7351 nominal, (Body size source: IPC-SM-782 page 76, https://www.pcb-3d.com/wordpress/wp-content/uploads/ipc-sm-782a_amendment_1_and_2.pdf)")
		(tags "capacitor 0402")
		(property "Reference" "C336"
			(at -12.219 30.6 90)
			(layer "B.SilkS")
			(effects
				(font
					(size 0.7 0.7)
					(thickness 0.15)
				)
				(justify left bottom mirror)
			)
		)
		(property "Value" "C_100n_0402"
			(at 0 -1.169 90)
			(layer "B.Fab")
			(effects
				(font
					(size 0.7 0.7)
					(thickness 0.15)
				)
				(justify left bottom mirror)
			)
		)
		(property "Manufacturer" "Murata"
			(at 0 0 270)
			(unlocked yes)
			(layer "B.Fab")
			(hide yes)
			(effects
				(font
					(size 1 1)
					(thickness 0.15)
				)
				(justify mirror)
			)
		)
		(property "MPN" "GRM155R61H104KE14D"
			(at 0 0 270)
			(unlocked yes)
			(layer "B.Fab")
			(hide yes)
			(effects
				(font
					(size 1 1)
					(thickness 0.15)
				)
				(justify mirror)
			)
		)
		(property "Val" "100n"
			(at 0 0 270)
			(unlocked yes)
			(layer "B.Fab")
			(hide yes)
			(effects
				(font
					(size 1 1)
					(thickness 0.15)
				)
				(justify mirror)
			)
		)
		(property "License" "Apache-2.0"
			(at 0 0 270)
			(unlocked yes)
			(layer "B.Fab")
			(hide yes)
			(effects
				(font
					(size 1 1)
					(thickness 0.15)
				)
				(justify mirror)
			)
		)
		(property "Author" "Antmicro"
			(at 0 0 270)
			(unlocked yes)
			(layer "B.Fab")
			(hide yes)
			(effects
				(font
					(size 1 1)
					(thickness 0.15)
				)
				(justify mirror)
			)
		)
		(property "Voltage" "50V"
			(at 0 0 270)
			(unlocked yes)
			(layer "B.Fab")
			(hide yes)
			(effects
				(font
					(size 1 1)
					(thickness 0.15)
				)
				(justify mirror)
			)
		)
		(property "Dielectric" "X5R"
			(at 0 0 270)
			(unlocked yes)
			(layer "B.Fab")
			(hide yes)
			(effects
				(font
					(size 1 1)
					(thickness 0.15)
				)
				(justify mirror)
			)
		)
		(sheetname "/FPGA banks HP/")
		(sheetfile "fpga-hp-banks.kicad_sch")
		(attr smd)
		(fp_rect
			(start -0.95 0.45)
			(end 0.95 -0.45)
			(stroke
				(width 0.05)
				(type default)
			)
			(fill no)
			(layer "B.CrtYd")
		)
		(fp_line
			(start -0.5 0.25)
			(end 0.498 0.25)
			(stroke
				(width 0.15)
				(type solid)
			)
			(layer "B.Fab")
		)
		(fp_line
			(start 0.498 0.25)
			(end 0.498 -0.248)
			(stroke
				(width 0.15)
				(type solid)
			)
			(layer "B.Fab")
		)
		(fp_line
			(start -0.5 -0.248)
			(end -0.5 0.25)
			(stroke
				(width 0.15)
				(type solid)
			)
			(layer "B.Fab")
		)
		(fp_line
			(start 0.498 -0.248)
			(end -0.5 -0.248)
			(stroke
				(width 0.15)
				(type solid)
			)
			(layer "B.Fab")
		)
		(fp_text user "${REFERENCE}"
			(at -0.9656 -3.169 90)
			(layer "B.Fab")
			(effects
				(font
					(size 0.7 0.7)
					(thickness 0.15)
				)
				(justify left bottom mirror)
			)
		)
		(fp_text user "License: Apache-2.0"
			(at -0.9656 -4.369 90)
			(layer "B.Fab")
			(effects
				(font
					(size 0.7 0.7)
					(thickness 0.15)
				)
				(justify left bottom mirror)
			)
		)
		(fp_text user "Author: Antmicro"
			(at -0.9656 -5.569 90)
			(layer "B.Fab")
			(effects
				(font
					(size 0.7 0.7)
					(thickness 0.15)
				)
				(justify left bottom mirror)
			)
		)
		(pad "1" smd roundrect
			(at -0.5 0 180)
			(size 0.6 0.6)
			(layers "B.Cu" "B.Mask" "B.Paste")
			(roundrect_rratio 0.25)
			(net 546 "/FPGA banks HP/VREF_67")
			(pintype "passive")
		)
		(pad "2" smd roundrect
			(at 0.498 0 270)
			(size 0.6 0.6)
			(layers "B.Cu" "B.Mask" "B.Paste")
			(roundrect_rratio 0.25)
			(net 1 "GND")
			(pintype "passive")
		)
	)
	(footprint "antmicro-footprints:C_0402_1005Metric_EIA"
		(layer "B.Cu")
		(at 194.499999 159)
		(descr "Capacitor SMD 0402 (1005 Metric), square (rectangular) end terminal, IPC_7351 nominal, (Body size source: IPC-SM-782 page 76, https://www.pcb-3d.com/wordpress/wp-content/uploads/ipc-sm-782a_amendment_1_and_2.pdf)")
		(tags "capacitor 0402")
		(property "Reference" "C99"
			(at -32.149999 -10.3 0)
			(layer "B.SilkS")
			(effects
				(font
					(size 0.7 0.7)
					(thickness 0.15)
				)
				(justify right bottom mirror)
			)
		)
		(property "Value" "C_100n_0402"
			(at 0 -1.169 0)
			(layer "B.Fab")
			(effects
				(font
					(size 0.7 0.7)
					(thickness 0.15)
				)
				(justify right bottom mirror)
			)
		)
		(property "Datasheet" "https://www.murata.com/products/productdetail?partno=GRM155R61H104KE14%23"
			(at 0 0 0)
			(layer "F.Fab")
			(hide yes)
			(effects
				(font
					(size 1.27 1.27)
					(thickness 0.15)
				)
			)
		)
		(property "MPN" "GRM155R61H104KE14D"
			(at 0 0 0)
			(unlocked yes)
			(layer "B.Fab")
			(hide yes)
			(effects
				(font
					(size 1 1)
					(thickness 0.15)
				)
				(justify mirror)
			)
		)
		(property "Manufacturer" "Murata"
			(at 0 0 0)
			(unlocked yes)
			(layer "B.Fab")
			(hide yes)
			(effects
				(font
					(size 1 1)
					(thickness 0.15)
				)
				(justify mirror)
			)
		)
		(property "License" "Apache-2.0"
			(at 0 0 0)
			(unlocked yes)
			(layer "B.Fab")
			(hide yes)
			(effects
				(font
					(size 1 1)
					(thickness 0.15)
				)
				(justify mirror)
			)
		)
		(property "Author" "Antmicro"
			(at 0 0 0)
			(unlocked yes)
			(layer "B.Fab")
			(hide yes)
			(effects
				(font
					(size 1 1)
					(thickness 0.15)
				)
				(justify mirror)
			)
		)
		(property "Val" "100n"
			(at 0 0 0)
			(unlocked yes)
			(layer "B.Fab")
			(hide yes)
			(effects
				(font
					(size 1 1)
					(thickness 0.15)
				)
				(justify mirror)
			)
		)
		(property "Voltage" "50V"
			(at 0 0 0)
			(unlocked yes)
			(layer "B.Fab")
			(hide yes)
			(effects
				(font
					(size 1 1)
					(thickness 0.15)
				)
				(justify mirror)
			)
		)
		(property "Dielectric" "X5R"
			(at 0 0 0)
			(unlocked yes)
			(layer "B.Fab")
			(hide yes)
			(effects
				(font
					(size 1 1)
					(thickness 0.15)
				)
				(justify mirror)
			)
		)
		(sheetname "/FPGA power/")
		(sheetfile "fpga-power.kicad_sch")
		(attr smd)
		(fp_rect
			(start -0.95 0.45)
			(end 0.95 -0.45)
			(stroke
				(width 0.05)
				(type default)
			)
			(fill no)
			(layer "B.CrtYd")
		)
		(fp_line
			(start -0.5 -0.248)
			(end -0.5 0.25)
			(stroke
				(width 0.15)
				(type solid)
			)
			(layer "B.Fab")
		)
		(fp_line
			(start -0.5 0.25)
			(end 0.498 0.25)
			(stroke
				(width 0.15)
				(type solid)
			)
			(layer "B.Fab")
		)
		(fp_line
			(start 0.498 -0.248)
			(end -0.5 -0.248)
			(stroke
				(width 0.15)
				(type solid)
			)
			(layer "B.Fab")
		)
		(fp_line
			(start 0.498 0.25)
			(end 0.498 -0.248)
			(stroke
				(width 0.15)
				(type solid)
			)
			(layer "B.Fab")
		)
		(fp_text user "License: Apache-2.0"
			(at -0.9656 -4.369 180)
			(layer "B.Fab")
			(effects
				(font
					(size 0.7 0.7)
					(thickness 0.15)
				)
				(justify left bottom mirror)
			)
		)
		(fp_text user "${REFERENCE}"
			(at -0.9656 -3.169 180)
			(layer "B.Fab")
			(effects
				(font
					(size 0.7 0.7)
					(thickness 0.15)
				)
				(justify left bottom mirror)
			)
		)
		(fp_text user "Author: Antmicro"
			(at -0.9656 -5.569 180)
			(layer "B.Fab")
			(effects
				(font
					(size 0.7 0.7)
					(thickness 0.15)
				)
				(justify left bottom mirror)
			)
		)
		(pad "1" smd roundrect
			(at -0.5 0 270)
			(size 0.6 0.6)
			(layers "B.Cu" "B.Mask" "B.Paste")
			(roundrect_rratio 0.25)
			(net 1 "GND")
			(pintype "passive")
		)
		(pad "2" smd roundrect
			(at 0.498 0)
			(size 0.6 0.6)
			(layers "B.Cu" "B.Mask" "B.Paste")
			(roundrect_rratio 0.25)
			(net 820 "+0V9_MGTAVCC")
			(pintype "passive")
		)
	)
	(footprint "antmicro-footprints:USON-10_2.5x1mm_P0.5mm"
		(layer "B.Cu")
		(at 107.804 160.119 180)
		(descr "USON-10 2.5x1mm_ Pitch 0.5mm")
		(tags "USON-10 2.5x1mm Pitch 0.5mm")
		(property "Reference" "U41"
			(at -1.946 -0.731 90)
			(layer "B.SilkS")
			(effects
				(font
					(size 0.7 0.7)
					(thickness 0.15)
				)
				(justify right bottom mirror)
			)
		)
		(property "Value" "TPD4E05U06QDQARQ1"
			(at 0.018 -2.499 0)
			(layer "B.Fab")
			(effects
				(font
					(size 0.7 0.7)
					(thickness 0.15)
				)
				(justify left bottom mirror)
			)
		)
		(property "Datasheet" "https://www.ti.com/lit/ds/symlink/tpd4e05u06-q1.pdf?HQS=dis-mous-null-mousermode-dsf-pf-null-wwe&ts=1663591265741&ref_url=https%253A%252F%252Fwww.mouser.com%252F"
			(at 0 0 180)
			(layer "F.Fab")
			(hide yes)
			(effects
				(font
					(size 1.27 1.27)
					(thickness 0.15)
				)
			)
		)
		(property "Manufacturer" "Texas Instruments"
			(at 0 0 180)
			(unlocked yes)
			(layer "B.Fab")
			(hide yes)
			(effects
				(font
					(size 1 1)
					(thickness 0.15)
				)
				(justify mirror)
			)
		)
		(property "MPN" "TPD4E05U06QDQARQ1"
			(at 0 0 180)
			(unlocked yes)
			(layer "B.Fab")
			(hide yes)
			(effects
				(font
					(size 1 1)
					(thickness 0.15)
				)
				(justify mirror)
			)
		)
		(property "Author" "Antmicro"
			(at 0 0 180)
			(unlocked yes)
			(layer "B.Fab")
			(hide yes)
			(effects
				(font
					(size 1 1)
					(thickness 0.15)
				)
				(justify mirror)
			)
		)
		(property "License" "Apache-2.0"
			(at 0 0 180)
			(unlocked yes)
			(layer "B.Fab")
			(hide yes)
			(effects
				(font
					(size 1 1)
					(thickness 0.15)
				)
				(justify mirror)
			)
		)
		(sheetname "/HDMI + SD Card/")
		(sheetfile "hdmi-sd-card.kicad_sch")
		(attr smd)
		(fp_line
			(start 0.498 1.401)
			(end -0.5 1.401)
			(stroke
				(width 0.15)
				(type solid)
			)
			(layer "B.SilkS")
		)
		(fp_line
			(start 0.498 -1.398)
			(end -0.5 -1.398)
			(stroke
				(width 0.15)
				(type solid)
			)
			(layer "B.SilkS")
		)
		(fp_circle
			(center -0.68 1.27)
			(end -0.63 1.27)
			(stroke
				(width 0.15)
				(type solid)
			)
			(fill yes)
			(layer "B.SilkS")
		)
		(fp_rect
			(start -0.8 1.5)
			(end 0.8 -1.499)
			(stroke
				(width 0.05)
				(type solid)
			)
			(fill no)
			(layer "B.CrtYd")
		)
		(fp_line
			(start 0.498 1.25)
			(end 0.498 -1.249)
			(stroke
				(width 0.15)
				(type solid)
			)
			(layer "B.Fab")
		)
		(fp_line
			(start 0.498 1.25)
			(end -0.25 1.25)
			(stroke
				(width 0.15)
				(type solid)
			)
			(layer "B.Fab")
		)
		(fp_line
			(start -0.25 1.25)
			(end -0.5 1)
			(stroke
				(width 0.15)
				(type solid)
			)
			(layer "B.Fab")
		)
		(fp_line
			(start -0.5 1)
			(end -0.5 -1.249)
			(stroke
				(width 0.15)
				(type solid)
			)
			(layer "B.Fab")
		)
		(fp_line
			(start -0.5 -1.249)
			(end 0.498 -1.249)
			(stroke
				(width 0.15)
				(type solid)
			)
			(layer "B.Fab")
		)
		(fp_text user "Author: Antmicro"
			(at -0.802 -5.7 0)
			(layer "B.Fab")
			(effects
				(font
					(size 0.7 0.7)
					(thickness 0.15)
				)
				(justify left bottom mirror)
			)
		)
		(fp_text user "License: Apache-2.0"
			(at -0.802 -6.9 0)
			(layer "B.Fab")
			(effects
				(font
					(size 0.7 0.7)
					(thickness 0.15)
				)
				(justify left bottom mirror)
			)
		)
		(fp_text user "${REFERENCE}"
			(at -0.802 -4.498 0)
			(layer "B.Fab")
			(effects
				(font
					(size 0.7 0.7)
					(thickness 0.15)
				)
				(justify left bottom mirror)
			)
		)
		(pad "1" smd roundrect
			(at -0.387 1 270)
			(size 0.25 0.55)
			(layers "B.Cu" "B.Mask" "B.Paste")
			(roundrect_rratio 0.25)
			(net 380 "/FPGA MGT Interface/HDMI_IN.D0_P")
			(pintype "passive")
		)
		(pad "2" smd roundrect
			(at -0.387 0.5 270)
			(size 0.25 0.55)
			(layers "B.Cu" "B.Mask" "B.Paste")
			(roundrect_rratio 0.25)
			(net 349 "/FPGA MGT Interface/HDMI_IN.D0_N")
			(pintype "passive")
		)
		(pad "3" smd roundrect
			(at -0.387 0 270)
			(size 0.4 0.55)
			(layers "B.Cu" "B.Mask" "B.Paste")
			(roundrect_rratio 0.25)
			(net 1 "GND")
			(pintype "power_in")
		)
		(pad "4" smd roundrect
			(at -0.387 -0.498 270)
			(size 0.25 0.55)
			(layers "B.Cu" "B.Mask" "B.Paste")
			(roundrect_rratio 0.25)
			(net 269 "/FPGA MGT Interface/HDMI_IN.CLK_P")
			(pintype "passive")
		)
		(pad "5" smd roundrect
			(at -0.387 -0.998 270)
			(size 0.25 0.55)
			(layers "B.Cu" "B.Mask" "B.Paste")
			(roundrect_rratio 0.25)
			(net 292 "/FPGA MGT Interface/HDMI_IN.CLK_N")
			(pintype "passive")
		)
		(pad "6" smd roundrect
			(at 0.385 -0.998 270)
			(size 0.25 0.55)
			(layers "B.Cu" "B.Mask" "B.Paste")
			(roundrect_rratio 0.25)
			(net 292 "/FPGA MGT Interface/HDMI_IN.CLK_N")
			(pintype "passive")
		)
		(pad "7" smd roundrect
			(at 0.385 -0.498 270)
			(size 0.25 0.55)
			(layers "B.Cu" "B.Mask" "B.Paste")
			(roundrect_rratio 0.25)
			(net 269 "/FPGA MGT Interface/HDMI_IN.CLK_P")
			(pintype "passive")
		)
		(pad "8" smd roundrect
			(at 0.385 0 270)
			(size 0.4 0.55)
			(layers "B.Cu" "B.Mask" "B.Paste")
			(roundrect_rratio 0.25)
			(net 1 "GND")
			(pintype "passive")
		)
		(pad "9" smd roundrect
			(at 0.385 0.5 270)
			(size 0.25 0.55)
			(layers "B.Cu" "B.Mask" "B.Paste")
			(roundrect_rratio 0.25)
			(net 349 "/FPGA MGT Interface/HDMI_IN.D0_N")
			(pintype "passive")
		)
		(pad "10" smd roundrect
			(at 0.385 1 270)
			(size 0.25 0.55)
			(layers "B.Cu" "B.Mask" "B.Paste")
			(roundrect_rratio 0.25)
			(net 380 "/FPGA MGT Interface/HDMI_IN.D0_P")
			(pintype "passive")
		)
	)
	(footprint "antmicro-footprints:R_0402_1005Metric"
		(layer "B.Cu")
		(at 225.32 182.765 180)
		(descr "Resistor SMD 0402")
		(tags "resistor SMD 0402")
		(property "Reference" "R185"
			(at -4.68 -0.535 0)
			(layer "B.SilkS")
			(effects
				(font
					(size 0.7 0.7)
					(thickness 0.15)
				)
				(justify left bottom mirror)
			)
		)
		(property "Value" "R_0R_0402"
			(at -1.011843 -1.772047 0)
			(layer "B.Fab")
			(effects
				(font
					(size 0.7 0.7)
					(thickness 0.15)
				)
				(justify left bottom mirror)
			)
		)
		(property "Datasheet" "https://industrial.panasonic.com/cdbs/www-data/pdf/RDA0000/AOA0000C301.pdf"
			(at 0 0 180)
			(layer "F.Fab")
			(hide yes)
			(effects
				(font
					(size 1.27 1.27)
					(thickness 0.15)
				)
			)
		)
		(property "MPN" "ERJ2GE0R00X"
			(at 0 0 180)
			(unlocked yes)
			(layer "B.Fab")
			(hide yes)
			(effects
				(font
					(size 1 1)
					(thickness 0.15)
				)
				(justify mirror)
			)
		)
		(property "Manufacturer" "Panasonic"
			(at 0 0 180)
			(unlocked yes)
			(layer "B.Fab")
			(hide yes)
			(effects
				(font
					(size 1 1)
					(thickness 0.15)
				)
				(justify mirror)
			)
		)
		(property "License" "Apache-2.0"
			(at 0 0 180)
			(unlocked yes)
			(layer "B.Fab")
			(hide yes)
			(effects
				(font
					(size 1 1)
					(thickness 0.15)
				)
				(justify mirror)
			)
		)
		(property "Author" "Antmicro"
			(at 0 0 180)
			(unlocked yes)
			(layer "B.Fab")
			(hide yes)
			(effects
				(font
					(size 1 1)
					(thickness 0.15)
				)
				(justify mirror)
			)
		)
		(property "Val" "0R"
			(at 0 0 180)
			(unlocked yes)
			(layer "B.Fab")
			(hide yes)
			(effects
				(font
					(size 1 1)
					(thickness 0.15)
				)
				(justify mirror)
			)
		)
		(property "Tolerance" "~"
			(at 0 0 180)
			(unlocked yes)
			(layer "B.Fab")
			(hide yes)
			(effects
				(font
					(size 1 1)
					(thickness 0.15)
				)
				(justify mirror)
			)
		)
		(property "Current" "1A"
			(at 0 0 180)
			(unlocked yes)
			(layer "B.Fab")
			(hide yes)
			(effects
				(font
					(size 1 1)
					(thickness 0.15)
				)
				(justify mirror)
			)
		)
		(sheetname "/Supply/DC-DC VCCINT/")
		(sheetfile "dc-dc-vccint.kicad_sch")
		(attr smd)
		(fp_rect
			(start -0.925 0.47)
			(end 0.925 -0.47)
			(stroke
				(width 0.05)
				(type default)
			)
			(fill no)
			(layer "B.CrtYd")
		)
		(fp_rect
			(start -0.5 0.25)
			(end 0.5 -0.25)
			(stroke
				(width 0.15)
				(type solid)
			)
			(fill no)
			(layer "B.Fab")
		)
		(fp_text user "License: Apache-2.0"
			(at -0.95 -5.169 0)
			(layer "B.Fab")
			(effects
				(font
					(size 0.7 0.7)
					(thickness 0.15)
				)
				(justify left bottom mirror)
			)
		)
		(fp_text user "Author: Antmicro"
			(at -0.95 -4.169 0)
			(layer "B.Fab")
			(effects
				(font
					(size 0.7 0.7)
					(thickness 0.15)
				)
				(justify left bottom mirror)
			)
		)
		(fp_text user "${REFERENCE}"
			(at -0.95 -3.168 0)
			(layer "B.Fab")
			(effects
				(font
					(size 0.7 0.7)
					(thickness 0.15)
				)
				(justify left bottom mirror)
			)
		)
		(pad "1" smd roundrect
			(at -0.48 0 180)
			(size 0.59 0.64)
			(layers "B.Cu" "B.Mask" "B.Paste")
			(roundrect_rratio 0.25)
			(net 723 "/Supply/DC-DC VCCINT/PASS1")
			(pintype "passive")
		)
		(pad "2" smd roundrect
			(at 0.48 0 180)
			(size 0.59 0.64)
			(layers "B.Cu" "B.Mask" "B.Paste")
			(roundrect_rratio 0.25)
			(net 724 "/Supply/DC-DC VCCINT/TAKE0")
			(pintype "passive")
		)
	)
	(footprint "antmicro-footprints:SC70-3"
		(layer "B.Cu")
		(at 114.27 163.97)
		(property "Reference" "Q21"
			(at -1.37 -1.42 0)
			(layer "B.SilkS")
			(effects
				(font
					(size 0.7 0.7)
					(thickness 0.15)
				)
				(justify right bottom mirror)
			)
		)
		(property "Value" "BSS138PW"
			(at 0 -2.3 0)
			(layer "B.Fab")
			(effects
				(font
					(size 0.7 0.7)
					(thickness 0.15)
				)
				(justify right bottom mirror)
			)
		)
		(property "Datasheet" "https://assets.nexperia.com/documents/data-sheet/BSS138PW.pdf"
			(at 0 0 0)
			(layer "F.Fab")
			(hide yes)
			(effects
				(font
					(size 1.27 1.27)
					(thickness 0.15)
				)
			)
		)
		(property "MPN" "BSS138PW"
			(at 0 0 0)
			(unlocked yes)
			(layer "B.Fab")
			(hide yes)
			(effects
				(font
					(size 1 1)
					(thickness 0.15)
				)
				(justify mirror)
			)
		)
		(property "Manufacturer" "Nexperia"
			(at 0 0 0)
			(unlocked yes)
			(layer "B.Fab")
			(hide yes)
			(effects
				(font
					(size 1 1)
					(thickness 0.15)
				)
				(justify mirror)
			)
		)
		(property "Author" "Antmicro"
			(at 0 0 0)
			(unlocked yes)
			(layer "B.Fab")
			(hide yes)
			(effects
				(font
					(size 1 1)
					(thickness 0.15)
				)
				(justify mirror)
			)
		)
		(property "License" "Apache-2.0"
			(at 0 0 0)
			(unlocked yes)
			(layer "B.Fab")
			(hide yes)
			(effects
				(font
					(size 1 1)
					(thickness 0.15)
				)
				(justify mirror)
			)
		)
		(sheetname "/HDMI + SD Card/")
		(sheetfile "hdmi-sd-card.kicad_sch")
		(attr smd)
		(fp_line
			(start -0.3 -1)
			(end 0.627 -1.001)
			(stroke
				(width 0.15)
				(type solid)
			)
			(layer "B.SilkS")
		)
		(fp_line
			(start -0.3 1)
			(end 0.627 0.999)
			(stroke
				(width 0.15)
				(type solid)
			)
			(layer "B.SilkS")
		)
		(fp_line
			(start 0.627 -0.6)
			(end 0.627 -1.001)
			(stroke
				(width 0.15)
				(type solid)
			)
			(layer "B.SilkS")
		)
		(fp_line
			(start 0.627 0.6)
			(end 0.627 0.999)
			(stroke
				(width 0.15)
				(type solid)
			)
			(layer "B.SilkS")
		)
		(fp_line
			(start -1.4 -1)
			(end -1.4 1)
			(stroke
				(width 0.05)
				(type solid)
			)
			(layer "B.CrtYd")
		)
		(fp_line
			(start -0.9 -1.3)
			(end -0.9 -1)
			(stroke
				(width 0.05)
				(type solid)
			)
			(layer "B.CrtYd")
		)
		(fp_line
			(start -0.9 -1)
			(end -1.4 -1)
			(stroke
				(width 0.05)
				(type solid)
			)
			(layer "B.CrtYd")
		)
		(fp_line
			(start -0.9 1)
			(end -1.4 1)
			(stroke
				(width 0.05)
				(type solid)
			)
			(layer "B.CrtYd")
		)
		(fp_line
			(start -0.9 1.3)
			(end -0.9 1)
			(stroke
				(width 0.05)
				(type solid)
			)
			(layer "B.CrtYd")
		)
		(fp_line
			(start -0.9 1.3)
			(end 0.9 1.3)
			(stroke
				(width 0.05)
				(type solid)
			)
			(layer "B.CrtYd")
		)
		(fp_line
			(start 0.9 -1.3)
			(end -0.9 -1.3)
			(stroke
				(width 0.05)
				(type solid)
			)
			(layer "B.CrtYd")
		)
		(fp_line
			(start 0.9 -0.4)
			(end 0.9 -1.3)
			(stroke
				(width 0.05)
				(type solid)
			)
			(layer "B.CrtYd")
		)
		(fp_line
			(start 0.9 0.4)
			(end 1.4 0.4)
			(stroke
				(width 0.05)
				(type solid)
			)
			(layer "B.CrtYd")
		)
		(fp_line
			(start 0.9 1.3)
			(end 0.9 0.4)
			(stroke
				(width 0.05)
				(type solid)
			)
			(layer "B.CrtYd")
		)
		(fp_line
			(start 1.4 -0.4)
			(end 0.9 -0.4)
			(stroke
				(width 0.05)
				(type solid)
			)
			(layer "B.CrtYd")
		)
		(fp_line
			(start 1.4 0.4)
			(end 1.4 -0.4)
			(stroke
				(width 0.05)
				(type solid)
			)
			(layer "B.CrtYd")
		)
		(fp_rect
			(start -0.623 0.999)
			(end 0.627 -1.001)
			(stroke
				(width 0.15)
				(type solid)
			)
			(fill no)
			(layer "B.Fab")
		)
		(fp_text user "License: Apache-2.0"
			(at -1.45 -6.782 180)
			(layer "B.Fab")
			(effects
				(font
					(size 0.7 0.7)
					(thickness 0.15)
				)
				(justify left bottom mirror)
			)
		)
		(fp_text user "${REFERENCE}"
			(at -1.45 -4.783 180)
			(layer "B.Fab")
			(effects
				(font
					(size 0.7 0.7)
					(thickness 0.15)
				)
				(justify left bottom mirror)
			)
		)
		(fp_text user "Author: Antmicro"
			(at -1.45 -5.782 180)
			(layer "B.Fab")
			(effects
				(font
					(size 0.7 0.7)
					(thickness 0.15)
				)
				(justify left bottom mirror)
			)
		)
		(pad "1" smd rect
			(at -1.051 0.65 270)
			(size 0.6 0.6)
			(layers "B.Cu" "B.Mask" "B.Paste")
			(net 297 "/HDMI + SD Card/HDMI_IN_5V")
			(pinfunction "G")
			(pintype "passive")
		)
		(pad "2" smd rect
			(at -1.051 -0.65 270)
			(size 0.6 0.6)
			(layers "B.Cu" "B.Mask" "B.Paste")
			(net 1 "GND")
			(pinfunction "S")
			(pintype "passive")
		)
		(pad "3" smd rect
			(at 1.05 0 270)
			(size 0.6 0.6)
			(layers "B.Cu" "B.Mask" "B.Paste")
			(net 507 "HDMI_IN_CD")
			(pinfunction "D")
			(pintype "passive")
		)
	)
	(footprint "antmicro-footprints:C_0603_1608Metric"
		(layer "B.Cu")
		(at 218.26 172.06 90)
		(descr "Capacitor SMD 0603")
		(tags "capacitor 0603")
		(property "Reference" "C270"
			(at -4.04 0.39 90)
			(layer "B.SilkS")
			(effects
				(font
					(size 0.7 0.7)
					(thickness 0.15)
				)
				(justify right bottom mirror)
			)
		)
		(property "Value" "C_22u_0603"
			(at -1.42757 -1.770288 90)
			(layer "B.Fab")
			(effects
				(font
					(size 0.7 0.7)
					(thickness 0.15)
				)
				(justify right bottom mirror)
			)
		)
		(property "Datasheet" "https://www.murata.com/products/productdetail?partno=GRM188R60J226MEA0%23"
			(at 0 0 90)
			(layer "F.Fab")
			(hide yes)
			(effects
				(font
					(size 1.27 1.27)
					(thickness 0.15)
				)
			)
		)
		(property "Manufacturer" "Murata"
			(at 0 0 90)
			(unlocked yes)
			(layer "B.Fab")
			(hide yes)
			(effects
				(font
					(size 1 1)
					(thickness 0.15)
				)
				(justify mirror)
			)
		)
		(property "MPN" "GRM188R60J226MEA0D"
			(at 0 0 90)
			(unlocked yes)
			(layer "B.Fab")
			(hide yes)
			(effects
				(font
					(size 1 1)
					(thickness 0.15)
				)
				(justify mirror)
			)
		)
		(property "Val" "22u"
			(at 0 0 90)
			(unlocked yes)
			(layer "B.Fab")
			(hide yes)
			(effects
				(font
					(size 1 1)
					(thickness 0.15)
				)
				(justify mirror)
			)
		)
		(property "License" "Apache-2.0"
			(at 0 0 90)
			(unlocked yes)
			(layer "B.Fab")
			(hide yes)
			(effects
				(font
					(size 1 1)
					(thickness 0.15)
				)
				(justify mirror)
			)
		)
		(property "Author" "Antmicro"
			(at 0 0 90)
			(unlocked yes)
			(layer "B.Fab")
			(hide yes)
			(effects
				(font
					(size 1 1)
					(thickness 0.15)
				)
				(justify mirror)
			)
		)
		(property "Voltage" ""
			(at 0 0 90)
			(unlocked yes)
			(layer "B.Fab")
			(hide yes)
			(effects
				(font
					(size 1 1)
					(thickness 0.15)
				)
				(justify mirror)
			)
		)
		(property "Dielectric" ""
			(at 0 0 90)
			(unlocked yes)
			(layer "B.Fab")
			(hide yes)
			(effects
				(font
					(size 1 1)
					(thickness 0.15)
				)
				(justify mirror)
			)
		)
		(sheetname "/Supply/DC-DC VCCINT/")
		(sheetfile "dc-dc-vccint.kicad_sch")
		(attr smd)
		(fp_line
			(start -0.15 -0.4)
			(end 0.15 -0.4)
			(stroke
				(width 0.15)
				(type solid)
			)
			(layer "B.SilkS")
		)
		(fp_line
			(start -0.15 0.4)
			(end 0.15 0.4)
			(stroke
				(width 0.15)
				(type solid)
			)
			(layer "B.SilkS")
		)
		(fp_rect
			(start -1.25 0.65)
			(end 1.25 -0.65)
			(stroke
				(width 0.05)
				(type solid)
			)
			(fill no)
			(layer "B.CrtYd")
		)
		(fp_rect
			(start -0.8 0.4)
			(end 0.8 -0.4)
			(stroke
				(width 0.15)
				(type solid)
			)
			(fill no)
			(layer "B.Fab")
		)
		(fp_text user "${REFERENCE}"
			(at -1.682 -3.895 270)
			(layer "B.Fab")
			(effects
				(font
					(size 0.7 0.7)
					(thickness 0.15)
				)
				(justify left bottom mirror)
			)
		)
		(fp_text user "Author: Antmicro"
			(at -1.682 -4.894 270)
			(layer "B.Fab")
			(effects
				(font
					(size 0.7 0.7)
					(thickness 0.15)
				)
				(justify left bottom mirror)
			)
		)
		(fp_text user "License: Apache-2.0"
			(at -1.682 -5.895 270)
			(layer "B.Fab")
			(effects
				(font
					(size 0.7 0.7)
					(thickness 0.15)
				)
				(justify left bottom mirror)
			)
		)
		(pad "1" smd roundrect
			(at -0.7 0 90)
			(size 0.8 1)
			(layers "B.Cu" "B.Mask" "B.Paste")
			(roundrect_rratio 0.2)
			(net 1 "GND")
			(pintype "passive")
		)
		(pad "2" smd roundrect
			(at 0.7 0 90)
			(size 0.8 1)
			(layers "B.Cu" "B.Mask" "B.Paste")
			(roundrect_rratio 0.2)
			(net 223 "/Supply/DC-DC VCCINT/0V85_REG0")
			(pintype "passive")
		)
	)
	(footprint "antmicro-footprints:C_0603_1608Metric"
		(layer "B.Cu")
		(at 227.435 172.06 90)
		(descr "Capacitor SMD 0603")
		(tags "capacitor 0603")
		(property "Reference" "C249"
			(at -4.069998 0.320001 90)
			(layer "B.SilkS")
			(effects
				(font
					(size 0.7 0.7)
					(thickness 0.15)
				)
				(justify right bottom mirror)
			)
		)
		(property "Value" "C_22u_0603"
			(at -1.42757 -1.770288 90)
			(layer "B.Fab")
			(effects
				(font
					(size 0.7 0.7)
					(thickness 0.15)
				)
				(justify right bottom mirror)
			)
		)
		(property "Datasheet" "https://www.murata.com/products/productdetail?partno=GRM188R60J226MEA0%23"
			(at 0 0 90)
			(layer "F.Fab")
			(hide yes)
			(effects
				(font
					(size 1.27 1.27)
					(thickness 0.15)
				)
			)
		)
		(property "Manufacturer" "Murata"
			(at 0 0 90)
			(unlocked yes)
			(layer "B.Fab")
			(hide yes)
			(effects
				(font
					(size 1 1)
					(thickness 0.15)
				)
				(justify mirror)
			)
		)
		(property "MPN" "GRM188R60J226MEA0D"
			(at 0 0 90)
			(unlocked yes)
			(layer "B.Fab")
			(hide yes)
			(effects
				(font
					(size 1 1)
					(thickness 0.15)
				)
				(justify mirror)
			)
		)
		(property "Val" "22u"
			(at 0 0 90)
			(unlocked yes)
			(layer "B.Fab")
			(hide yes)
			(effects
				(font
					(size 1 1)
					(thickness 0.15)
				)
				(justify mirror)
			)
		)
		(property "License" "Apache-2.0"
			(at 0 0 90)
			(unlocked yes)
			(layer "B.Fab")
			(hide yes)
			(effects
				(font
					(size 1 1)
					(thickness 0.15)
				)
				(justify mirror)
			)
		)
		(property "Author" "Antmicro"
			(at 0 0 90)
			(unlocked yes)
			(layer "B.Fab")
			(hide yes)
			(effects
				(font
					(size 1 1)
					(thickness 0.15)
				)
				(justify mirror)
			)
		)
		(property "Voltage" ""
			(at 0 0 90)
			(unlocked yes)
			(layer "B.Fab")
			(hide yes)
			(effects
				(font
					(size 1 1)
					(thickness 0.15)
				)
				(justify mirror)
			)
		)
		(property "Dielectric" ""
			(at 0 0 90)
			(unlocked yes)
			(layer "B.Fab")
			(hide yes)
			(effects
				(font
					(size 1 1)
					(thickness 0.15)
				)
				(justify mirror)
			)
		)
		(sheetname "/Supply/DC-DC VCCINT/")
		(sheetfile "dc-dc-vccint.kicad_sch")
		(attr smd)
		(fp_line
			(start -0.15 -0.4)
			(end 0.15 -0.4)
			(stroke
				(width 0.15)
				(type solid)
			)
			(layer "B.SilkS")
		)
		(fp_line
			(start -0.15 0.4)
			(end 0.15 0.4)
			(stroke
				(width 0.15)
				(type solid)
			)
			(layer "B.SilkS")
		)
		(fp_rect
			(start -1.25 0.65)
			(end 1.25 -0.65)
			(stroke
				(width 0.05)
				(type solid)
			)
			(fill no)
			(layer "B.CrtYd")
		)
		(fp_rect
			(start -0.8 0.4)
			(end 0.8 -0.4)
			(stroke
				(width 0.15)
				(type solid)
			)
			(fill no)
			(layer "B.Fab")
		)
		(fp_text user "Author: Antmicro"
			(at -1.682 -4.894 270)
			(layer "B.Fab")
			(effects
				(font
					(size 0.7 0.7)
					(thickness 0.15)
				)
				(justify left bottom mirror)
			)
		)
		(fp_text user "${REFERENCE}"
			(at -1.682 -3.895 270)
			(layer "B.Fab")
			(effects
				(font
					(size 0.7 0.7)
					(thickness 0.15)
				)
				(justify left bottom mirror)
			)
		)
		(fp_text user "License: Apache-2.0"
			(at -1.682 -5.895 270)
			(layer "B.Fab")
			(effects
				(font
					(size 0.7 0.7)
					(thickness 0.15)
				)
				(justify left bottom mirror)
			)
		)
		(pad "1" smd roundrect
			(at -0.7 0 90)
			(size 0.8 1)
			(layers "B.Cu" "B.Mask" "B.Paste")
			(roundrect_rratio 0.2)
			(net 1 "GND")
			(pintype "passive")
		)
		(pad "2" smd roundrect
			(at 0.7 0 90)
			(size 0.8 1)
			(layers "B.Cu" "B.Mask" "B.Paste")
			(roundrect_rratio 0.2)
			(net 224 "/Supply/DC-DC VCCINT/0V85_REG1")
			(pintype "passive")
		)
	)
	(footprint "antmicro-footprints:C_0402_1005Metric"
		(layer "B.Cu")
		(at 119.91 125.802383 90)
		(descr "Capacitor SMD 0402")
		(tags "capacitor SMD 0402")
		(property "Reference" "C135"
			(at 1.151513 -0.318604 90)
			(layer "B.SilkS")
			(effects
				(font
					(size 0.7 0.7)
					(thickness 0.15)
				)
				(justify right top mirror)
			)
		)
		(property "Value" "C_100n_0402"
			(at -1.022927 -2.155213 90)
			(layer "B.Fab")
			(effects
				(font
					(size 0.7 0.7)
					(thickness 0.15)
				)
				(justify right top mirror)
			)
		)
		(property "Datasheet" "https://www.murata.com/products/productdetail?partno=GRM155R61H104KE14%23"
			(at 0 0 90)
			(layer "F.Fab")
			(hide yes)
			(effects
				(font
					(size 1.27 1.27)
					(thickness 0.15)
				)
			)
		)
		(property "MPN" "GRM155R61H104KE14D"
			(at 0 0 90)
			(unlocked yes)
			(layer "B.Fab")
			(hide yes)
			(effects
				(font
					(size 1 1)
					(thickness 0.15)
				)
				(justify mirror)
			)
		)
		(property "Manufacturer" "Murata"
			(at 0 0 90)
			(unlocked yes)
			(layer "B.Fab")
			(hide yes)
			(effects
				(font
					(size 1 1)
					(thickness 0.15)
				)
				(justify mirror)
			)
		)
		(property "License" "Apache-2.0"
			(at 0 0 90)
			(unlocked yes)
			(layer "B.Fab")
			(hide yes)
			(effects
				(font
					(size 1 1)
					(thickness 0.15)
				)
				(justify mirror)
			)
		)
		(property "Author" "Antmicro"
			(at 0 0 90)
			(unlocked yes)
			(layer "B.Fab")
			(hide yes)
			(effects
				(font
					(size 1 1)
					(thickness 0.15)
				)
				(justify mirror)
			)
		)
		(property "Val" "100n"
			(at 0 0 90)
			(unlocked yes)
			(layer "B.Fab")
			(hide yes)
			(effects
				(font
					(size 1 1)
					(thickness 0.15)
				)
				(justify mirror)
			)
		)
		(property "Voltage" "50V"
			(at 0 0 90)
			(unlocked yes)
			(layer "B.Fab")
			(hide yes)
			(effects
				(font
					(size 1 1)
					(thickness 0.15)
				)
				(justify mirror)
			)
		)
		(property "Dielectric" "X5R"
			(at 0 0 90)
			(unlocked yes)
			(layer "B.Fab")
			(hide yes)
			(effects
				(font
					(size 1 1)
					(thickness 0.15)
				)
				(justify mirror)
			)
		)
		(sheetname "/Ethernet/")
		(sheetfile "ethernet.kicad_sch")
		(attr smd)
		(fp_rect
			(start -0.925 0.47)
			(end 0.925 -0.47)
			(stroke
				(width 0.05)
				(type default)
			)
			(fill no)
			(layer "B.CrtYd")
		)
		(fp_line
			(start 0.504 -0.248)
			(end -0.494 -0.248)
			(stroke
				(width 0.15)
				(type solid)
			)
			(layer "B.Fab")
		)
		(fp_line
			(start -0.494 -0.248)
			(end -0.494 0.25)
			(stroke
				(width 0.15)
				(type solid)
			)
			(layer "B.Fab")
		)
		(fp_line
			(start 0.504 0.25)
			(end 0.504 -0.248)
			(stroke
				(width 0.15)
				(type solid)
			)
			(layer "B.Fab")
		)
		(fp_line
			(start -0.494 0.25)
			(end 0.504 0.25)
			(stroke
				(width 0.15)
				(type solid)
			)
			(layer "B.Fab")
		)
		(fp_text user "Author: Antmicro"
			(at -0.939 -3.399 270)
			(layer "B.Fab")
			(effects
				(font
					(size 0.7 0.7)
					(thickness 0.15)
				)
				(justify left bottom mirror)
			)
		)
		(fp_text user "${REFERENCE}"
			(at -0.939 -4.599 270)
			(layer "B.Fab")
			(effects
				(font
					(size 0.7 0.7)
					(thickness 0.15)
				)
				(justify left bottom mirror)
			)
		)
		(fp_text user "License: Apache-2.0"
			(at -0.939 -5.799 270)
			(layer "B.Fab")
			(effects
				(font
					(size 0.7 0.7)
					(thickness 0.15)
				)
				(justify left bottom mirror)
			)
		)
		(pad "1" smd roundrect
			(at -0.48 0 90)
			(size 0.59 0.64)
			(layers "B.Cu" "B.Mask" "B.Paste")
			(roundrect_rratio 0.25)
			(net 1 "GND")
			(pintype "passive")
		)
		(pad "2" smd roundrect
			(at 0.48 0 90)
			(size 0.59 0.64)
			(layers "B.Cu" "B.Mask" "B.Paste")
			(roundrect_rratio 0.25)
			(net 821 "Net-(C135-Pad2)")
			(pintype "passive")
		)
	)
	(footprint "antmicro-footprints:R_0402_1005Metric_EIA"
		(layer "B.Cu")
		(at 181.499 149)
		(descr "Resistor SMD 0402 (1005 Metric), square (rectangular) end terminal, IPC_7351 nominal, (Body size source: IPC-SM-782 page 76, https://www.pcb-3d.com/wordpress/wp-content/uploads/ipc-sm-782a_amendment_1_and_2.pdf)")
		(tags "resistor 0402")
		(property "Reference" "R132"
			(at -1.899 -1.4 0)
			(layer "B.SilkS")
			(effects
				(font
					(size 0.7 0.7)
					(thickness 0.15)
				)
				(justify right top mirror)
			)
		)
		(property "Value" "R_1k_0402"
			(at 0 -1.169 0)
			(layer "B.Fab")
			(effects
				(font
					(size 0.7 0.7)
					(thickness 0.15)
				)
				(justify right top mirror)
			)
		)
		(property "Datasheet" "https://www.bourns.com/docs/product-datasheets/cr.pdf"
			(at 0 0 0)
			(layer "F.Fab")
			(hide yes)
			(effects
				(font
					(size 1.27 1.27)
					(thickness 0.15)
				)
			)
		)
		(property "MPN" "CR0402-FX-1001GLF"
			(at 0 0 0)
			(unlocked yes)
			(layer "B.Fab")
			(hide yes)
			(effects
				(font
					(size 1 1)
					(thickness 0.15)
				)
				(justify mirror)
			)
		)
		(property "Manufacturer" "Bourns"
			(at 0 0 0)
			(unlocked yes)
			(layer "B.Fab")
			(hide yes)
			(effects
				(font
					(size 1 1)
					(thickness 0.15)
				)
				(justify mirror)
			)
		)
		(property "License" "Apache-2.0"
			(at 0 0 0)
			(unlocked yes)
			(layer "B.Fab")
			(hide yes)
			(effects
				(font
					(size 1 1)
					(thickness 0.15)
				)
				(justify mirror)
			)
		)
		(property "Author" "Antmicro"
			(at 0 0 0)
			(unlocked yes)
			(layer "B.Fab")
			(hide yes)
			(effects
				(font
					(size 1 1)
					(thickness 0.15)
				)
				(justify mirror)
			)
		)
		(property "Val" "1k"
			(at 0 0 0)
			(unlocked yes)
			(layer "B.Fab")
			(hide yes)
			(effects
				(font
					(size 1 1)
					(thickness 0.15)
				)
				(justify mirror)
			)
		)
		(property "Tolerance" "1%"
			(at 0 0 0)
			(unlocked yes)
			(layer "B.Fab")
			(hide yes)
			(effects
				(font
					(size 1 1)
					(thickness 0.15)
				)
				(justify mirror)
			)
		)
		(sheetname "/FPGA banks HP/")
		(sheetfile "fpga-hp-banks.kicad_sch")
		(attr smd exclude_from_bom dnp)
		(fp_rect
			(start -0.95 0.45)
			(end 0.95 -0.45)
			(stroke
				(width 0.05)
				(type default)
			)
			(fill no)
			(layer "B.CrtYd")
		)
		(fp_line
			(start -0.5 -0.249)
			(end -0.5 0.25)
			(stroke
				(width 0.15)
				(type solid)
			)
			(layer "B.Fab")
		)
		(fp_line
			(start -0.5 0.25)
			(end 0.499 0.25)
			(stroke
				(width 0.15)
				(type solid)
			)
			(layer "B.Fab")
		)
		(fp_line
			(start 0.499 -0.249)
			(end -0.5 -0.249)
			(stroke
				(width 0.15)
				(type solid)
			)
			(layer "B.Fab")
		)
		(fp_line
			(start 0.499 0.25)
			(end 0.499 -0.249)
			(stroke
				(width 0.15)
				(type solid)
			)
			(layer "B.Fab")
		)
		(fp_text user "License: Apache-2.0"
			(at -0.95 -4.369 0)
			(layer "B.Fab")
			(effects
				(font
					(size 0.7 0.7)
					(thickness 0.15)
				)
				(justify right top mirror)
			)
		)
		(fp_text user "Author: Antmicro"
			(at -0.95 -5.569 0)
			(layer "B.Fab")
			(effects
				(font
					(size 0.7 0.7)
					(thickness 0.15)
				)
				(justify right top mirror)
			)
		)
		(fp_text user "${REFERENCE}"
			(at -0.95 -3.169 0)
			(layer "B.Fab")
			(effects
				(font
					(size 0.7 0.7)
					(thickness 0.15)
				)
				(justify right top mirror)
			)
		)
		(pad "1" smd roundrect
			(at -0.5 0 270)
			(size 0.6 0.6)
			(layers "B.Cu" "B.Mask" "B.Paste")
			(roundrect_rratio 0.25)
			(net 1 "GND")
			(pintype "passive")
		)
		(pad "2" smd roundrect
			(at 0.499 0)
			(size 0.6 0.6)
			(layers "B.Cu" "B.Mask" "B.Paste")
			(roundrect_rratio 0.25)
			(net 546 "/FPGA banks HP/VREF_67")
			(pintype "passive")
		)
	)
	(footprint "antmicro-footprints:R_0402_1005Metric"
		(layer "B.Cu")
		(at 236.22 154.262 90)
		(descr "Resistor SMD 0402")
		(tags "resistor SMD 0402")
		(property "Reference" "R214"
			(at 1.062 0.38 90)
			(layer "B.SilkS")
			(effects
				(font
					(size 0.7 0.7)
					(thickness 0.15)
				)
				(justify right bottom mirror)
			)
		)
		(property "Value" "R_0R_0402"
			(at -1.011843 -1.772047 90)
			(layer "B.Fab")
			(effects
				(font
					(size 0.7 0.7)
					(thickness 0.15)
				)
				(justify right bottom mirror)
			)
		)
		(property "Datasheet" "https://industrial.panasonic.com/cdbs/www-data/pdf/RDA0000/AOA0000C301.pdf"
			(at 0 0 90)
			(layer "F.Fab")
			(hide yes)
			(effects
				(font
					(size 1.27 1.27)
					(thickness 0.15)
				)
			)
		)
		(property "MPN" "ERJ2GE0R00X"
			(at 0 0 90)
			(unlocked yes)
			(layer "B.Fab")
			(hide yes)
			(effects
				(font
					(size 1 1)
					(thickness 0.15)
				)
				(justify mirror)
			)
		)
		(property "Manufacturer" "Panasonic"
			(at 0 0 90)
			(unlocked yes)
			(layer "B.Fab")
			(hide yes)
			(effects
				(font
					(size 1 1)
					(thickness 0.15)
				)
				(justify mirror)
			)
		)
		(property "License" "Apache-2.0"
			(at 0 0 90)
			(unlocked yes)
			(layer "B.Fab")
			(hide yes)
			(effects
				(font
					(size 1 1)
					(thickness 0.15)
				)
				(justify mirror)
			)
		)
		(property "Author" "Antmicro"
			(at 0 0 90)
			(unlocked yes)
			(layer "B.Fab")
			(hide yes)
			(effects
				(font
					(size 1 1)
					(thickness 0.15)
				)
				(justify mirror)
			)
		)
		(property "Val" "0R"
			(at 0 0 90)
			(unlocked yes)
			(layer "B.Fab")
			(hide yes)
			(effects
				(font
					(size 1 1)
					(thickness 0.15)
				)
				(justify mirror)
			)
		)
		(property "Tolerance" "~"
			(at 0 0 90)
			(unlocked yes)
			(layer "B.Fab")
			(hide yes)
			(effects
				(font
					(size 1 1)
					(thickness 0.15)
				)
				(justify mirror)
			)
		)
		(property "Current" "1A"
			(at 0 0 90)
			(unlocked yes)
			(layer "B.Fab")
			(hide yes)
			(effects
				(font
					(size 1 1)
					(thickness 0.15)
				)
				(justify mirror)
			)
		)
		(sheetname "/Supply/DC-DC IO/")
		(sheetfile "dc-dc-io.kicad_sch")
		(attr smd)
		(fp_rect
			(start -0.925 0.47)
			(end 0.925 -0.47)
			(stroke
				(width 0.05)
				(type default)
			)
			(fill no)
			(layer "B.CrtYd")
		)
		(fp_rect
			(start -0.5 0.25)
			(end 0.5 -0.25)
			(stroke
				(width 0.15)
				(type solid)
			)
			(fill no)
			(layer "B.Fab")
		)
		(fp_text user "License: Apache-2.0"
			(at -0.95 -5.169 270)
			(layer "B.Fab")
			(effects
				(font
					(size 0.7 0.7)
					(thickness 0.15)
				)
				(justify left bottom mirror)
			)
		)
		(fp_text user "Author: Antmicro"
			(at -0.95 -4.169 270)
			(layer "B.Fab")
			(effects
				(font
					(size 0.7 0.7)
					(thickness 0.15)
				)
				(justify left bottom mirror)
			)
		)
		(fp_text user "${REFERENCE}"
			(at -0.95 -3.168 270)
			(layer "B.Fab")
			(effects
				(font
					(size 0.7 0.7)
					(thickness 0.15)
				)
				(justify left bottom mirror)
			)
		)
		(pad "1" smd roundrect
			(at -0.48 0 90)
			(size 0.59 0.64)
			(layers "B.Cu" "B.Mask" "B.Paste")
			(roundrect_rratio 0.25)
			(net 734 "Net-(U28-IN4+)")
			(pintype "passive")
		)
		(pad "2" smd roundrect
			(at 0.48 0 90)
			(size 0.59 0.64)
			(layers "B.Cu" "B.Mask" "B.Paste")
			(roundrect_rratio 0.25)
			(net 688 "/Supply/DC-DC IO/1V2_SEN_+")
			(pintype "passive")
		)
	)
	(footprint "antmicro-footprints:SC70-3"
		(layer "B.Cu")
		(at 114.755 107.55 180)
		(property "Reference" "Q5"
			(at -3.355 -0.334 0)
			(layer "B.SilkS")
			(effects
				(font
					(size 0.7 0.7)
					(thickness 0.15)
				)
				(justify left bottom mirror)
			)
		)
		(property "Value" "BSS138PW"
			(at 0 -2.3 0)
			(layer "B.Fab")
			(effects
				(font
					(size 0.7 0.7)
					(thickness 0.15)
				)
				(justify left bottom mirror)
			)
		)
		(property "Datasheet" "https://assets.nexperia.com/documents/data-sheet/BSS138PW.pdf"
			(at 0 0 180)
			(layer "F.Fab")
			(hide yes)
			(effects
				(font
					(size 1.27 1.27)
					(thickness 0.15)
				)
			)
		)
		(property "MPN" "BSS138PW"
			(at 0 0 180)
			(unlocked yes)
			(layer "B.Fab")
			(hide yes)
			(effects
				(font
					(size 1 1)
					(thickness 0.15)
				)
				(justify mirror)
			)
		)
		(property "Manufacturer" "Nexperia"
			(at 0 0 180)
			(unlocked yes)
			(layer "B.Fab")
			(hide yes)
			(effects
				(font
					(size 1 1)
					(thickness 0.15)
				)
				(justify mirror)
			)
		)
		(property "Author" "Antmicro"
			(at 0 0 180)
			(unlocked yes)
			(layer "B.Fab")
			(hide yes)
			(effects
				(font
					(size 1 1)
					(thickness 0.15)
				)
				(justify mirror)
			)
		)
		(property "License" "Apache-2.0"
			(at 0 0 180)
			(unlocked yes)
			(layer "B.Fab")
			(hide yes)
			(effects
				(font
					(size 1 1)
					(thickness 0.15)
				)
				(justify mirror)
			)
		)
		(sheetname "/FPGA banks HD/")
		(sheetfile "fpga-hd-banks.kicad_sch")
		(attr smd)
		(fp_line
			(start 0.627 0.6)
			(end 0.627 0.999)
			(stroke
				(width 0.15)
				(type solid)
			)
			(layer "B.SilkS")
		)
		(fp_line
			(start 0.627 -0.6)
			(end 0.627 -1.001)
			(stroke
				(width 0.15)
				(type solid)
			)
			(layer "B.SilkS")
		)
		(fp_line
			(start -0.3 1)
			(end 0.627 0.999)
			(stroke
				(width 0.15)
				(type solid)
			)
			(layer "B.SilkS")
		)
		(fp_line
			(start -0.3 -1)
			(end 0.627 -1.001)
			(stroke
				(width 0.15)
				(type solid)
			)
			(layer "B.SilkS")
		)
		(fp_line
			(start 1.4 0.4)
			(end 1.4 -0.4)
			(stroke
				(width 0.05)
				(type solid)
			)
			(layer "B.CrtYd")
		)
		(fp_line
			(start 1.4 -0.4)
			(end 0.9 -0.4)
			(stroke
				(width 0.05)
				(type solid)
			)
			(layer "B.CrtYd")
		)
		(fp_line
			(start 0.9 1.3)
			(end 0.9 0.4)
			(stroke
				(width 0.05)
				(type solid)
			)
			(layer "B.CrtYd")
		)
		(fp_line
			(start 0.9 0.4)
			(end 1.4 0.4)
			(stroke
				(width 0.05)
				(type solid)
			)
			(layer "B.CrtYd")
		)
		(fp_line
			(start 0.9 -0.4)
			(end 0.9 -1.3)
			(stroke
				(width 0.05)
				(type solid)
			)
			(layer "B.CrtYd")
		)
		(fp_line
			(start 0.9 -1.3)
			(end -0.9 -1.3)
			(stroke
				(width 0.05)
				(type solid)
			)
			(layer "B.CrtYd")
		)
		(fp_line
			(start -0.9 1.3)
			(end 0.9 1.3)
			(stroke
				(width 0.05)
				(type solid)
			)
			(layer "B.CrtYd")
		)
		(fp_line
			(start -0.9 1.3)
			(end -0.9 1)
			(stroke
				(width 0.05)
				(type solid)
			)
			(layer "B.CrtYd")
		)
		(fp_line
			(start -0.9 1)
			(end -1.4 1)
			(stroke
				(width 0.05)
				(type solid)
			)
			(layer "B.CrtYd")
		)
		(fp_line
			(start -0.9 -1)
			(end -1.4 -1)
			(stroke
				(width 0.05)
				(type solid)
			)
			(layer "B.CrtYd")
		)
		(fp_line
			(start -0.9 -1.3)
			(end -0.9 -1)
			(stroke
				(width 0.05)
				(type solid)
			)
			(layer "B.CrtYd")
		)
		(fp_line
			(start -1.4 -1)
			(end -1.4 1)
			(stroke
				(width 0.05)
				(type solid)
			)
			(layer "B.CrtYd")
		)
		(fp_rect
			(start -0.623 0.999)
			(end 0.627 -1.001)
			(stroke
				(width 0.15)
				(type solid)
			)
			(fill no)
			(layer "B.Fab")
		)
		(fp_text user "License: Apache-2.0"
			(at -1.45 -6.782 0)
			(layer "B.Fab")
			(effects
				(font
					(size 0.7 0.7)
					(thickness 0.15)
				)
				(justify left bottom mirror)
			)
		)
		(fp_text user "Author: Antmicro"
			(at -1.45 -5.782 0)
			(layer "B.Fab")
			(effects
				(font
					(size 0.7 0.7)
					(thickness 0.15)
				)
				(justify left bottom mirror)
			)
		)
		(fp_text user "${REFERENCE}"
			(at -1.45 -4.783 0)
			(layer "B.Fab")
			(effects
				(font
					(size 0.7 0.7)
					(thickness 0.15)
				)
				(justify left bottom mirror)
			)
		)
		(pad "1" smd rect
			(at -1.051 0.65 90)
			(size 0.6 0.6)
			(layers "B.Cu" "B.Mask" "B.Paste")
			(net 700 "/FPGA banks HD/USR_LED4")
			(pinfunction "G")
			(pintype "passive")
		)
		(pad "2" smd rect
			(at -1.051 -0.65 90)
			(size 0.6 0.6)
			(layers "B.Cu" "B.Mask" "B.Paste")
			(net 1 "GND")
			(pinfunction "S")
			(pintype "passive")
		)
		(pad "3" smd rect
			(at 1.05 0 90)
			(size 0.6 0.6)
			(layers "B.Cu" "B.Mask" "B.Paste")
			(net 273 "Net-(Q5-D)")
			(pinfunction "D")
			(pintype "passive")
		)
	)
	(footprint "antmicro-footprints:C_0402_1005Metric_EIA"
		(layer "B.Cu")
		(at 184.500001 156 180)
		(descr "Capacitor SMD 0402 (1005 Metric), square (rectangular) end terminal, IPC_7351 nominal, (Body size source: IPC-SM-782 page 76, https://www.pcb-3d.com/wordpress/wp-content/uploads/ipc-sm-782a_amendment_1_and_2.pdf)")
		(tags "capacitor 0402")
		(property "Reference" "C46"
			(at 30.075001 10.5 0)
			(layer "B.SilkS")
			(effects
				(font
					(size 0.7 0.7)
					(thickness 0.15)
				)
				(justify left bottom mirror)
			)
		)
		(property "Value" "C_1u_25V_0402"
			(at 0 -1.169 0)
			(layer "B.Fab")
			(effects
				(font
					(size 0.7 0.7)
					(thickness 0.15)
				)
				(justify left bottom mirror)
			)
		)
		(property "Datasheet" "https://www.murata.com/products/productdetail?partno=GRM155R61E105KE11%23"
			(at 0 0 180)
			(layer "F.Fab")
			(hide yes)
			(effects
				(font
					(size 1.27 1.27)
					(thickness 0.15)
				)
			)
		)
		(property "MPN" "GRM155R61E105KE11J"
			(at 0 0 180)
			(unlocked yes)
			(layer "B.Fab")
			(hide yes)
			(effects
				(font
					(size 1 1)
					(thickness 0.15)
				)
				(justify mirror)
			)
		)
		(property "Manufacturer" "Murata"
			(at 0 0 180)
			(unlocked yes)
			(layer "B.Fab")
			(hide yes)
			(effects
				(font
					(size 1 1)
					(thickness 0.15)
				)
				(justify mirror)
			)
		)
		(property "License" "Apache-2.0"
			(at 0 0 180)
			(unlocked yes)
			(layer "B.Fab")
			(hide yes)
			(effects
				(font
					(size 1 1)
					(thickness 0.15)
				)
				(justify mirror)
			)
		)
		(property "Author" "Antmicro"
			(at 0 0 180)
			(unlocked yes)
			(layer "B.Fab")
			(hide yes)
			(effects
				(font
					(size 1 1)
					(thickness 0.15)
				)
				(justify mirror)
			)
		)
		(property "Val" "1u"
			(at 0 0 180)
			(unlocked yes)
			(layer "B.Fab")
			(hide yes)
			(effects
				(font
					(size 1 1)
					(thickness 0.15)
				)
				(justify mirror)
			)
		)
		(property "Voltage" "25V"
			(at 0 0 180)
			(unlocked yes)
			(layer "B.Fab")
			(hide yes)
			(effects
				(font
					(size 1 1)
					(thickness 0.15)
				)
				(justify mirror)
			)
		)
		(property "Dielectric" "X5R"
			(at 0 0 180)
			(unlocked yes)
			(layer "B.Fab")
			(hide yes)
			(effects
				(font
					(size 1 1)
					(thickness 0.15)
				)
				(justify mirror)
			)
		)
		(sheetname "/FPGA power/")
		(sheetfile "fpga-power.kicad_sch")
		(attr smd)
		(fp_rect
			(start -0.95 0.45)
			(end 0.95 -0.45)
			(stroke
				(width 0.05)
				(type default)
			)
			(fill no)
			(layer "B.CrtYd")
		)
		(fp_line
			(start 0.498 0.25)
			(end 0.498 -0.248)
			(stroke
				(width 0.15)
				(type solid)
			)
			(layer "B.Fab")
		)
		(fp_line
			(start 0.498 -0.248)
			(end -0.5 -0.248)
			(stroke
				(width 0.15)
				(type solid)
			)
			(layer "B.Fab")
		)
		(fp_line
			(start -0.5 0.25)
			(end 0.498 0.25)
			(stroke
				(width 0.15)
				(type solid)
			)
			(layer "B.Fab")
		)
		(fp_line
			(start -0.5 -0.248)
			(end -0.5 0.25)
			(stroke
				(width 0.15)
				(type solid)
			)
			(layer "B.Fab")
		)
		(fp_text user "License: Apache-2.0"
			(at -0.9656 -4.369 0)
			(layer "B.Fab")
			(effects
				(font
					(size 0.7 0.7)
					(thickness 0.15)
				)
				(justify left bottom mirror)
			)
		)
		(fp_text user "${REFERENCE}"
			(at -0.9656 -3.169 0)
			(layer "B.Fab")
			(effects
				(font
					(size 0.7 0.7)
					(thickness 0.15)
				)
				(justify left bottom mirror)
			)
		)
		(fp_text user "Author: Antmicro"
			(at -0.9656 -5.569 0)
			(layer "B.Fab")
			(effects
				(font
					(size 0.7 0.7)
					(thickness 0.15)
				)
				(justify left bottom mirror)
			)
		)
		(pad "1" smd roundrect
			(at -0.5 0 90)
			(size 0.6 0.6)
			(layers "B.Cu" "B.Mask" "B.Paste")
			(roundrect_rratio 0.25)
			(net 1 "GND")
			(pintype "passive")
		)
		(pad "2" smd roundrect
			(at 0.498 0 180)
			(size 0.6 0.6)
			(layers "B.Cu" "B.Mask" "B.Paste")
			(roundrect_rratio 0.25)
			(net 553 "+0V85")
			(pintype "passive")
		)
	)
	(footprint "antmicro-footprints:R_0402_1005Metric"
		(layer "B.Cu")
		(at 222.875 179.785 90)
		(descr "Resistor SMD 0402")
		(tags "resistor SMD 0402")
		(property "Reference" "R201"
			(at -2.165 1.75 90)
			(layer "B.SilkS")
			(effects
				(font
					(size 0.7 0.7)
					(thickness 0.15)
				)
				(justify right bottom mirror)
			)
		)
		(property "Value" "R_3k4_0402"
			(at -1.011843 -1.772047 90)
			(layer "B.Fab")
			(effects
				(font
					(size 0.7 0.7)
					(thickness 0.15)
				)
				(justify right bottom mirror)
			)
		)
		(property "Datasheet" "https://www.yageo.com/upload/media/product/app/datasheet/rchip/pyu-rt_1-to-0.01_rohs_l.pdf"
			(at 0 0 90)
			(layer "F.Fab")
			(hide yes)
			(effects
				(font
					(size 1.27 1.27)
					(thickness 0.15)
				)
			)
		)
		(property "MPN" "RT0402BRD073K4L"
			(at 0 0 90)
			(unlocked yes)
			(layer "B.Fab")
			(hide yes)
			(effects
				(font
					(size 1 1)
					(thickness 0.15)
				)
				(justify mirror)
			)
		)
		(property "Manufacturer" "YAGEO"
			(at 0 0 90)
			(unlocked yes)
			(layer "B.Fab")
			(hide yes)
			(effects
				(font
					(size 1 1)
					(thickness 0.15)
				)
				(justify mirror)
			)
		)
		(property "License" "Apache-2.0"
			(at 0 0 90)
			(unlocked yes)
			(layer "B.Fab")
			(hide yes)
			(effects
				(font
					(size 1 1)
					(thickness 0.15)
				)
				(justify mirror)
			)
		)
		(property "Author" "Antmicro"
			(at 0 0 90)
			(unlocked yes)
			(layer "B.Fab")
			(hide yes)
			(effects
				(font
					(size 1 1)
					(thickness 0.15)
				)
				(justify mirror)
			)
		)
		(property "Val" "3k4"
			(at 0 0 90)
			(unlocked yes)
			(layer "B.Fab")
			(hide yes)
			(effects
				(font
					(size 1 1)
					(thickness 0.15)
				)
				(justify mirror)
			)
		)
		(property "Tolerance" "0.1%"
			(at 0 0 90)
			(unlocked yes)
			(layer "B.Fab")
			(hide yes)
			(effects
				(font
					(size 1 1)
					(thickness 0.15)
				)
				(justify mirror)
			)
		)
		(sheetname "/Supply/DC-DC VCCINT/")
		(sheetfile "dc-dc-vccint.kicad_sch")
		(attr smd)
		(fp_rect
			(start -0.925 0.47)
			(end 0.925 -0.47)
			(stroke
				(width 0.05)
				(type default)
			)
			(fill no)
			(layer "B.CrtYd")
		)
		(fp_rect
			(start -0.5 0.25)
			(end 0.5 -0.25)
			(stroke
				(width 0.15)
				(type solid)
			)
			(fill no)
			(layer "B.Fab")
		)
		(fp_text user "License: Apache-2.0"
			(at -0.95 -5.169 270)
			(layer "B.Fab")
			(effects
				(font
					(size 0.7 0.7)
					(thickness 0.15)
				)
				(justify left bottom mirror)
			)
		)
		(fp_text user "Author: Antmicro"
			(at -0.95 -4.169 270)
			(layer "B.Fab")
			(effects
				(font
					(size 0.7 0.7)
					(thickness 0.15)
				)
				(justify left bottom mirror)
			)
		)
		(fp_text user "${REFERENCE}"
			(at -0.95 -3.168 270)
			(layer "B.Fab")
			(effects
				(font
					(size 0.7 0.7)
					(thickness 0.15)
				)
				(justify left bottom mirror)
			)
		)
		(pad "1" smd roundrect
			(at -0.48 0 90)
			(size 0.59 0.64)
			(layers "B.Cu" "B.Mask" "B.Paste")
			(roundrect_rratio 0.25)
			(net 226 "/Supply/DC-DC VCCINT/V_{0SNS+}")
			(pintype "passive")
		)
		(pad "2" smd roundrect
			(at 0.48 0 90)
			(size 0.59 0.64)
			(layers "B.Cu" "B.Mask" "B.Paste")
			(roundrect_rratio 0.25)
			(net 756 "Net-(C264-Pad2)")
			(pintype "passive")
		)
	)
	(footprint "antmicro-footprints:R_0402_1005Metric_EIA"
		(layer "B.Cu")
		(at 180 149.5 -90)
		(descr "Resistor SMD 0402 (1005 Metric), square (rectangular) end terminal, IPC_7351 nominal, (Body size source: IPC-SM-782 page 76, https://www.pcb-3d.com/wordpress/wp-content/uploads/ipc-sm-782a_amendment_1_and_2.pdf)")
		(tags "resistor 0402")
		(property "Reference" "R182"
			(at -1.425 0.575 90)
			(layer "B.SilkS")
			(effects
				(font
					(size 0.7 0.7)
					(thickness 0.15)
				)
				(justify left bottom mirror)
			)
		)
		(property "Value" "R_240R_0402"
			(at 0 -1.169 90)
			(layer "B.Fab")
			(effects
				(font
					(size 0.7 0.7)
					(thickness 0.15)
				)
				(justify left bottom mirror)
			)
		)
		(property "Datasheet" "https://www.bourns.com/docs/product-datasheets/cr.pdf"
			(at 0 0 270)
			(layer "F.Fab")
			(hide yes)
			(effects
				(font
					(size 1.27 1.27)
					(thickness 0.15)
				)
			)
		)
		(property "MPN" "CR0402-FX-2400GLF"
			(at 0 0 270)
			(unlocked yes)
			(layer "B.Fab")
			(hide yes)
			(effects
				(font
					(size 1 1)
					(thickness 0.15)
				)
				(justify mirror)
			)
		)
		(property "Manufacturer" "Bourns"
			(at 0 0 270)
			(unlocked yes)
			(layer "B.Fab")
			(hide yes)
			(effects
				(font
					(size 1 1)
					(thickness 0.15)
				)
				(justify mirror)
			)
		)
		(property "License" "Apache-2.0"
			(at 0 0 270)
			(unlocked yes)
			(layer "B.Fab")
			(hide yes)
			(effects
				(font
					(size 1 1)
					(thickness 0.15)
				)
				(justify mirror)
			)
		)
		(property "Author" "Antmicro"
			(at 0 0 270)
			(unlocked yes)
			(layer "B.Fab")
			(hide yes)
			(effects
				(font
					(size 1 1)
					(thickness 0.15)
				)
				(justify mirror)
			)
		)
		(property "Val" "240R"
			(at 0 0 270)
			(unlocked yes)
			(layer "B.Fab")
			(hide yes)
			(effects
				(font
					(size 1 1)
					(thickness 0.15)
				)
				(justify mirror)
			)
		)
		(property "Tolerance" "1%"
			(at 0 0 270)
			(unlocked yes)
			(layer "B.Fab")
			(hide yes)
			(effects
				(font
					(size 1 1)
					(thickness 0.15)
				)
				(justify mirror)
			)
		)
		(sheetname "/FPGA banks HP/")
		(sheetfile "fpga-hp-banks.kicad_sch")
		(attr smd)
		(fp_rect
			(start -0.95 0.45)
			(end 0.95 -0.45)
			(stroke
				(width 0.05)
				(type default)
			)
			(fill no)
			(layer "B.CrtYd")
		)
		(fp_line
			(start -0.5 0.25)
			(end 0.499 0.25)
			(stroke
				(width 0.15)
				(type solid)
			)
			(layer "B.Fab")
		)
		(fp_line
			(start 0.499 0.25)
			(end 0.499 -0.249)
			(stroke
				(width 0.15)
				(type solid)
			)
			(layer "B.Fab")
		)
		(fp_line
			(start -0.5 -0.249)
			(end -0.5 0.25)
			(stroke
				(width 0.15)
				(type solid)
			)
			(layer "B.Fab")
		)
		(fp_line
			(start 0.499 -0.249)
			(end -0.5 -0.249)
			(stroke
				(width 0.15)
				(type solid)
			)
			(layer "B.Fab")
		)
		(fp_text user "${REFERENCE}"
			(at -0.95 -3.169 90)
			(layer "B.Fab")
			(effects
				(font
					(size 0.7 0.7)
					(thickness 0.15)
				)
				(justify left bottom mirror)
			)
		)
		(fp_text user "License: Apache-2.0"
			(at -0.95 -4.369 90)
			(layer "B.Fab")
			(effects
				(font
					(size 0.7 0.7)
					(thickness 0.15)
				)
				(justify left bottom mirror)
			)
		)
		(fp_text user "Author: Antmicro"
			(at -0.95 -5.569 90)
			(layer "B.Fab")
			(effects
				(font
					(size 0.7 0.7)
					(thickness 0.15)
				)
				(justify left bottom mirror)
			)
		)
		(pad "1" smd roundrect
			(at -0.5 0 180)
			(size 0.6 0.6)
			(layers "B.Cu" "B.Mask" "B.Paste")
			(roundrect_rratio 0.25)
			(net 601 "/FPGA banks HP/VRP_67")
			(pintype "passive")
		)
		(pad "2" smd roundrect
			(at 0.499 0 270)
			(size 0.6 0.6)
			(layers "B.Cu" "B.Mask" "B.Paste")
			(roundrect_rratio 0.25)
			(net 1 "GND")
			(pintype "passive")
		)
	)
	(footprint "antmicro-footprints:C_0402_1005Metric"
		(layer "B.Cu")
		(at 122.95 147.61)
		(descr "Capacitor SMD 0402")
		(tags "capacitor SMD 0402")
		(property "Reference" "C303"
			(at 2.32 0.932 0)
			(layer "B.SilkS")
			(effects
				(font
					(size 0.7 0.7)
					(thickness 0.15)
				)
				(justify right bottom mirror)
			)
		)
		(property "Value" "C_100n_0402"
			(at -1.022927 -2.155213 0)
			(layer "B.Fab")
			(effects
				(font
					(size 0.7 0.7)
					(thickness 0.15)
				)
				(justify right bottom mirror)
			)
		)
		(property "Datasheet" "https://www.murata.com/products/productdetail?partno=GRM155R61H104KE14%23"
			(at 0 0 0)
			(layer "F.Fab")
			(hide yes)
			(effects
				(font
					(size 1.27 1.27)
					(thickness 0.15)
				)
			)
		)
		(property "Manufacturer" "Murata"
			(at 0 0 0)
			(unlocked yes)
			(layer "B.Fab")
			(hide yes)
			(effects
				(font
					(size 1 1)
					(thickness 0.15)
				)
				(justify mirror)
			)
		)
		(property "MPN" "GRM155R61H104KE14D"
			(at 0 0 0)
			(unlocked yes)
			(layer "B.Fab")
			(hide yes)
			(effects
				(font
					(size 1 1)
					(thickness 0.15)
				)
				(justify mirror)
			)
		)
		(property "Val" "100n"
			(at 0 0 0)
			(unlocked yes)
			(layer "B.Fab")
			(hide yes)
			(effects
				(font
					(size 1 1)
					(thickness 0.15)
				)
				(justify mirror)
			)
		)
		(property "License" "Apache-2.0"
			(at 0 0 0)
			(unlocked yes)
			(layer "B.Fab")
			(hide yes)
			(effects
				(font
					(size 1 1)
					(thickness 0.15)
				)
				(justify mirror)
			)
		)
		(property "Author" "Antmicro"
			(at 0 0 0)
			(unlocked yes)
			(layer "B.Fab")
			(hide yes)
			(effects
				(font
					(size 1 1)
					(thickness 0.15)
				)
				(justify mirror)
			)
		)
		(property "Voltage" "50V"
			(at 0 0 0)
			(unlocked yes)
			(layer "B.Fab")
			(hide yes)
			(effects
				(font
					(size 1 1)
					(thickness 0.15)
				)
				(justify mirror)
			)
		)
		(property "Dielectric" "X5R"
			(at 0 0 0)
			(unlocked yes)
			(layer "B.Fab")
			(hide yes)
			(effects
				(font
					(size 1 1)
					(thickness 0.15)
				)
				(justify mirror)
			)
		)
		(sheetname "/FPGA MGT Interface/")
		(sheetfile "fpga-mgt.kicad_sch")
		(attr smd)
		(fp_rect
			(start -0.925 0.47)
			(end 0.925 -0.47)
			(stroke
				(width 0.05)
				(type default)
			)
			(fill no)
			(layer "B.CrtYd")
		)
		(fp_line
			(start -0.494 -0.248)
			(end -0.494 0.25)
			(stroke
				(width 0.15)
				(type solid)
			)
			(layer "B.Fab")
		)
		(fp_line
			(start -0.494 0.25)
			(end 0.504 0.25)
			(stroke
				(width 0.15)
				(type solid)
			)
			(layer "B.Fab")
		)
		(fp_line
			(start 0.504 -0.248)
			(end -0.494 -0.248)
			(stroke
				(width 0.15)
				(type solid)
			)
			(layer "B.Fab")
		)
		(fp_line
			(start 0.504 0.25)
			(end 0.504 -0.248)
			(stroke
				(width 0.15)
				(type solid)
			)
			(layer "B.Fab")
		)
		(fp_text user "Author: Antmicro"
			(at -0.939 -3.399 180)
			(layer "B.Fab")
			(effects
				(font
					(size 0.7 0.7)
					(thickness 0.15)
				)
				(justify left bottom mirror)
			)
		)
		(fp_text user "${REFERENCE}"
			(at -0.939 -4.599 180)
			(layer "B.Fab")
			(effects
				(font
					(size 0.7 0.7)
					(thickness 0.15)
				)
				(justify left bottom mirror)
			)
		)
		(fp_text user "License: Apache-2.0"
			(at -0.939 -5.799 180)
			(layer "B.Fab")
			(effects
				(font
					(size 0.7 0.7)
					(thickness 0.15)
				)
				(justify left bottom mirror)
			)
		)
		(pad "1" smd roundrect
			(at -0.48 0)
			(size 0.59 0.64)
			(layers "B.Cu" "B.Mask" "B.Paste")
			(roundrect_rratio 0.25)
			(net 344 "/FPGA MGT Interface/HDMI_IN.D2_P")
			(pintype "passive")
		)
		(pad "2" smd roundrect
			(at 0.48 0)
			(size 0.59 0.64)
			(layers "B.Cu" "B.Mask" "B.Paste")
			(roundrect_rratio 0.25)
			(net 649 "/FPGA MGT Interface/HDMI_FPGA.RX2_P")
			(pintype "passive")
		)
	)
	(footprint "antmicro-footprints:C_0402_1005Metric_EIA"
		(layer "B.Cu")
		(at 190 146.5 -90)
		(descr "Capacitor SMD 0402 (1005 Metric), square (rectangular) end terminal, IPC_7351 nominal, (Body size source: IPC-SM-782 page 76, https://www.pcb-3d.com/wordpress/wp-content/uploads/ipc-sm-782a_amendment_1_and_2.pdf)")
		(tags "capacitor 0402")
		(property "Reference" "C68"
			(at -12.15 30.65 90)
			(layer "B.SilkS")
			(effects
				(font
					(size 0.7 0.7)
					(thickness 0.15)
				)
				(justify left bottom mirror)
			)
		)
		(property "Value" "C_100n_0402"
			(at 0 -1.169 90)
			(layer "B.Fab")
			(effects
				(font
					(size 0.7 0.7)
					(thickness 0.15)
				)
				(justify left bottom mirror)
			)
		)
		(property "Datasheet" "https://www.murata.com/products/productdetail?partno=GRM155R61H104KE14%23"
			(at 0 0 270)
			(layer "F.Fab")
			(hide yes)
			(effects
				(font
					(size 1.27 1.27)
					(thickness 0.15)
				)
			)
		)
		(property "MPN" "GRM155R61H104KE14D"
			(at 0 0 270)
			(unlocked yes)
			(layer "B.Fab")
			(hide yes)
			(effects
				(font
					(size 1 1)
					(thickness 0.15)
				)
				(justify mirror)
			)
		)
		(property "Manufacturer" "Murata"
			(at 0 0 270)
			(unlocked yes)
			(layer "B.Fab")
			(hide yes)
			(effects
				(font
					(size 1 1)
					(thickness 0.15)
				)
				(justify mirror)
			)
		)
		(property "License" "Apache-2.0"
			(at 0 0 270)
			(unlocked yes)
			(layer "B.Fab")
			(hide yes)
			(effects
				(font
					(size 1 1)
					(thickness 0.15)
				)
				(justify mirror)
			)
		)
		(property "Author" "Antmicro"
			(at 0 0 270)
			(unlocked yes)
			(layer "B.Fab")
			(hide yes)
			(effects
				(font
					(size 1 1)
					(thickness 0.15)
				)
				(justify mirror)
			)
		)
		(property "Val" "100n"
			(at 0 0 270)
			(unlocked yes)
			(layer "B.Fab")
			(hide yes)
			(effects
				(font
					(size 1 1)
					(thickness 0.15)
				)
				(justify mirror)
			)
		)
		(property "Voltage" "50V"
			(at 0 0 270)
			(unlocked yes)
			(layer "B.Fab")
			(hide yes)
			(effects
				(font
					(size 1 1)
					(thickness 0.15)
				)
				(justify mirror)
			)
		)
		(property "Dielectric" "X5R"
			(at 0 0 270)
			(unlocked yes)
			(layer "B.Fab")
			(hide yes)
			(effects
				(font
					(size 1 1)
					(thickness 0.15)
				)
				(justify mirror)
			)
		)
		(sheetname "/FPGA power/")
		(sheetfile "fpga-power.kicad_sch")
		(attr smd)
		(fp_rect
			(start -0.95 0.45)
			(end 0.95 -0.45)
			(stroke
				(width 0.05)
				(type default)
			)
			(fill no)
			(layer "B.CrtYd")
		)
		(fp_line
			(start -0.5 0.25)
			(end 0.498 0.25)
			(stroke
				(width 0.15)
				(type solid)
			)
			(layer "B.Fab")
		)
		(fp_line
			(start 0.498 0.25)
			(end 0.498 -0.248)
			(stroke
				(width 0.15)
				(type solid)
			)
			(layer "B.Fab")
		)
		(fp_line
			(start -0.5 -0.248)
			(end -0.5 0.25)
			(stroke
				(width 0.15)
				(type solid)
			)
			(layer "B.Fab")
		)
		(fp_line
			(start 0.498 -0.248)
			(end -0.5 -0.248)
			(stroke
				(width 0.15)
				(type solid)
			)
			(layer "B.Fab")
		)
		(fp_text user "License: Apache-2.0"
			(at -0.9656 -4.369 90)
			(layer "B.Fab")
			(effects
				(font
					(size 0.7 0.7)
					(thickness 0.15)
				)
				(justify left bottom mirror)
			)
		)
		(fp_text user "Author: Antmicro"
			(at -0.9656 -5.569 90)
			(layer "B.Fab")
			(effects
				(font
					(size 0.7 0.7)
					(thickness 0.15)
				)
				(justify left bottom mirror)
			)
		)
		(fp_text user "${REFERENCE}"
			(at -0.9656 -3.169 90)
			(layer "B.Fab")
			(effects
				(font
					(size 0.7 0.7)
					(thickness 0.15)
				)
				(justify left bottom mirror)
			)
		)
		(pad "1" smd roundrect
			(at -0.5 0 180)
			(size 0.6 0.6)
			(layers "B.Cu" "B.Mask" "B.Paste")
			(roundrect_rratio 0.25)
			(net 1 "GND")
			(pintype "passive")
		)
		(pad "2" smd roundrect
			(at 0.498 0 270)
			(size 0.6 0.6)
			(layers "B.Cu" "B.Mask" "B.Paste")
			(roundrect_rratio 0.25)
			(net 797 "+1V8")
			(pintype "passive")
		)
	)
	(footprint "antmicro-footprints:R_0402_1005Metric"
		(layer "B.Cu")
		(at 196.5 136.8 90)
		(descr "Resistor SMD 0402")
		(tags "resistor SMD 0402")
		(property "Reference" "R257"
			(at 2.3 0 270)
			(layer "B.SilkS")
			(effects
				(font
					(size 0.7 0.7)
					(thickness 0.15)
				)
				(justify mirror)
			)
		)
		(property "Value" "R_0R_0402"
			(at -1.011843 -1.772047 270)
			(layer "B.Fab")
			(effects
				(font
					(size 0.7 0.7)
					(thickness 0.15)
				)
				(justify left bottom mirror)
			)
		)
		(property "Datasheet" "https://industrial.panasonic.com/cdbs/www-data/pdf/RDA0000/AOA0000C301.pdf"
			(at 0 0 270)
			(layer "B.Fab")
			(hide yes)
			(effects
				(font
					(size 1.27 1.27)
					(thickness 0.15)
				)
				(justify mirror)
			)
		)
		(property "MPN" "ERJ2GE0R00X"
			(at 0 0 90)
			(unlocked yes)
			(layer "B.Fab")
			(hide yes)
			(effects
				(font
					(size 1 1)
					(thickness 0.15)
				)
				(justify mirror)
			)
		)
		(property "Manufacturer" "Panasonic"
			(at 0 0 90)
			(unlocked yes)
			(layer "B.Fab")
			(hide yes)
			(effects
				(font
					(size 1 1)
					(thickness 0.15)
				)
				(justify mirror)
			)
		)
		(property "License" "Apache-2.0"
			(at 0 0 90)
			(unlocked yes)
			(layer "B.Fab")
			(hide yes)
			(effects
				(font
					(size 1 1)
					(thickness 0.15)
				)
				(justify mirror)
			)
		)
		(property "Author" "Antmicro"
			(at 0 0 90)
			(unlocked yes)
			(layer "B.Fab")
			(hide yes)
			(effects
				(font
					(size 1 1)
					(thickness 0.15)
				)
				(justify mirror)
			)
		)
		(property "Val" "0R"
			(at 0 0 90)
			(unlocked yes)
			(layer "B.Fab")
			(hide yes)
			(effects
				(font
					(size 1 1)
					(thickness 0.15)
				)
				(justify mirror)
			)
		)
		(property "Tolerance" "~"
			(at 0 0 90)
			(unlocked yes)
			(layer "B.Fab")
			(hide yes)
			(effects
				(font
					(size 1 1)
					(thickness 0.15)
				)
				(justify mirror)
			)
		)
		(property "Current" "1A"
			(at 0 0 90)
			(unlocked yes)
			(layer "B.Fab")
			(hide yes)
			(effects
				(font
					(size 1 1)
					(thickness 0.15)
				)
				(justify mirror)
			)
		)
		(sheetname "/FPGA banks HP/")
		(sheetfile "fpga-hp-banks.kicad_sch")
		(attr smd)
		(fp_rect
			(start -0.925 0.47)
			(end 0.925 -0.47)
			(stroke
				(width 0.05)
				(type default)
			)
			(fill no)
			(layer "B.CrtYd")
		)
		(fp_rect
			(start -0.5 0.25)
			(end 0.5 -0.25)
			(stroke
				(width 0.15)
				(type solid)
			)
			(fill no)
			(layer "B.Fab")
		)
		(fp_text user "License: Apache-2.0"
			(at -0.95 -5.169 270)
			(layer "B.Fab")
			(effects
				(font
					(size 0.7 0.7)
					(thickness 0.15)
				)
				(justify left bottom mirror)
			)
		)
		(fp_text user "Author: Antmicro"
			(at -0.95 -4.169 270)
			(layer "B.Fab")
			(effects
				(font
					(size 0.7 0.7)
					(thickness 0.15)
				)
				(justify left bottom mirror)
			)
		)
		(fp_text user "${REFERENCE}"
			(at -0.95 -3.168 270)
			(layer "B.Fab")
			(effects
				(font
					(size 0.7 0.7)
					(thickness 0.15)
				)
				(justify left bottom mirror)
			)
		)
		(pad "1" smd roundrect
			(at -0.48 0 90)
			(size 0.59 0.64)
			(layers "B.Cu" "B.Mask" "B.Paste")
			(roundrect_rratio 0.25)
			(net 535 "/FPGA banks HP/VREF_64")
			(pintype "passive")
		)
		(pad "2" smd roundrect
			(at 0.48 0 90)
			(size 0.59 0.64)
			(layers "B.Cu" "B.Mask" "B.Paste")
			(roundrect_rratio 0.25)
			(net 826 "/FPGA banks HP/VREF")
			(pintype "passive")
		)
	)
	(footprint "antmicro-footprints:C_0402_1005Metric_EIA"
		(layer "B.Cu")
		(at 183 144.5 90)
		(descr "Capacitor SMD 0402 (1005 Metric), square (rectangular) end terminal, IPC_7351 nominal, (Body size source: IPC-SM-782 page 76, https://www.pcb-3d.com/wordpress/wp-content/uploads/ipc-sm-782a_amendment_1_and_2.pdf)")
		(tags "capacitor 0402")
		(property "Reference" "C78"
			(at -1.05 1.475 90)
			(layer "B.SilkS")
			(effects
				(font
					(size 0.7 0.7)
					(thickness 0.15)
				)
				(justify right bottom mirror)
			)
		)
		(property "Value" "C_100n_0402"
			(at 0 -1.169 90)
			(layer "B.Fab")
			(effects
				(font
					(size 0.7 0.7)
					(thickness 0.15)
				)
				(justify right bottom mirror)
			)
		)
		(property "Datasheet" "https://www.murata.com/products/productdetail?partno=GRM155R61H104KE14%23"
			(at 0 0 90)
			(layer "F.Fab")
			(hide yes)
			(effects
				(font
					(size 1.27 1.27)
					(thickness 0.15)
				)
			)
		)
		(property "MPN" "GRM155R61H104KE14D"
			(at 0 0 90)
			(unlocked yes)
			(layer "B.Fab")
			(hide yes)
			(effects
				(font
					(size 1 1)
					(thickness 0.15)
				)
				(justify mirror)
			)
		)
		(property "Manufacturer" "Murata"
			(at 0 0 90)
			(unlocked yes)
			(layer "B.Fab")
			(hide yes)
			(effects
				(font
					(size 1 1)
					(thickness 0.15)
				)
				(justify mirror)
			)
		)
		(property "License" "Apache-2.0"
			(at 0 0 90)
			(unlocked yes)
			(layer "B.Fab")
			(hide yes)
			(effects
				(font
					(size 1 1)
					(thickness 0.15)
				)
				(justify mirror)
			)
		)
		(property "Author" "Antmicro"
			(at 0 0 90)
			(unlocked yes)
			(layer "B.Fab")
			(hide yes)
			(effects
				(font
					(size 1 1)
					(thickness 0.15)
				)
				(justify mirror)
			)
		)
		(property "Val" "100n"
			(at 0 0 90)
			(unlocked yes)
			(layer "B.Fab")
			(hide yes)
			(effects
				(font
					(size 1 1)
					(thickness 0.15)
				)
				(justify mirror)
			)
		)
		(property "Voltage" "50V"
			(at 0 0 90)
			(unlocked yes)
			(layer "B.Fab")
			(hide yes)
			(effects
				(font
					(size 1 1)
					(thickness 0.15)
				)
				(justify mirror)
			)
		)
		(property "Dielectric" "X5R"
			(at 0 0 90)
			(unlocked yes)
			(layer "B.Fab")
			(hide yes)
			(effects
				(font
					(size 1 1)
					(thickness 0.15)
				)
				(justify mirror)
			)
		)
		(sheetname "/FPGA power/")
		(sheetfile "fpga-power.kicad_sch")
		(attr smd)
		(fp_rect
			(start -0.95 0.45)
			(end 0.95 -0.45)
			(stroke
				(width 0.05)
				(type default)
			)
			(fill no)
			(layer "B.CrtYd")
		)
		(fp_line
			(start 0.498 -0.248)
			(end -0.5 -0.248)
			(stroke
				(width 0.15)
				(type solid)
			)
			(layer "B.Fab")
		)
		(fp_line
			(start -0.5 -0.248)
			(end -0.5 0.25)
			(stroke
				(width 0.15)
				(type solid)
			)
			(layer "B.Fab")
		)
		(fp_line
			(start 0.498 0.25)
			(end 0.498 -0.248)
			(stroke
				(width 0.15)
				(type solid)
			)
			(layer "B.Fab")
		)
		(fp_line
			(start -0.5 0.25)
			(end 0.498 0.25)
			(stroke
				(width 0.15)
				(type solid)
			)
			(layer "B.Fab")
		)
		(fp_text user "Author: Antmicro"
			(at -0.9656 -5.569 270)
			(layer "B.Fab")
			(effects
				(font
					(size 0.7 0.7)
					(thickness 0.15)
				)
				(justify left bottom mirror)
			)
		)
		(fp_text user "${REFERENCE}"
			(at -0.9656 -3.169 270)
			(layer "B.Fab")
			(effects
				(font
					(size 0.7 0.7)
					(thickness 0.15)
				)
				(justify left bottom mirror)
			)
		)
		(fp_text user "License: Apache-2.0"
			(at -0.9656 -4.369 270)
			(layer "B.Fab")
			(effects
				(font
					(size 0.7 0.7)
					(thickness 0.15)
				)
				(justify left bottom mirror)
			)
		)
		(pad "1" smd roundrect
			(at -0.5 0)
			(size 0.6 0.6)
			(layers "B.Cu" "B.Mask" "B.Paste")
			(roundrect_rratio 0.25)
			(net 1 "GND")
			(pintype "passive")
		)
		(pad "2" smd roundrect
			(at 0.498 0 90)
			(size 0.6 0.6)
			(layers "B.Cu" "B.Mask" "B.Paste")
			(roundrect_rratio 0.25)
			(net 687 "VDDQ")
			(pintype "passive")
		)
	)
	(footprint "antmicro-footprints:C_0402_1005Metric"
		(layer "B.Cu")
		(at 190.672499 193.2285 90)
		(descr "Capacitor SMD 0402")
		(tags "capacitor SMD 0402")
		(property "Reference" "C254"
			(at 0.994 0.403501 90)
			(layer "B.SilkS")
			(effects
				(font
					(size 0.7 0.7)
					(thickness 0.15)
				)
				(justify right bottom mirror)
			)
		)
		(property "Value" "C_100n_0402"
			(at -1.022927 -2.155213 90)
			(layer "B.Fab")
			(effects
				(font
					(size 0.7 0.7)
					(thickness 0.15)
				)
				(justify right bottom mirror)
			)
		)
		(property "Datasheet" "https://www.murata.com/products/productdetail?partno=GRM155R61H104KE14%23"
			(at 0 0 90)
			(layer "F.Fab")
			(hide yes)
			(effects
				(font
					(size 1.27 1.27)
					(thickness 0.15)
				)
			)
		)
		(property "Manufacturer" "Murata"
			(at 0 0 90)
			(unlocked yes)
			(layer "B.Fab")
			(hide yes)
			(effects
				(font
					(size 1 1)
					(thickness 0.15)
				)
				(justify mirror)
			)
		)
		(property "MPN" "GRM155R61H104KE14D"
			(at 0 0 90)
			(unlocked yes)
			(layer "B.Fab")
			(hide yes)
			(effects
				(font
					(size 1 1)
					(thickness 0.15)
				)
				(justify mirror)
			)
		)
		(property "Val" "100n"
			(at 0 0 90)
			(unlocked yes)
			(layer "B.Fab")
			(hide yes)
			(effects
				(font
					(size 1 1)
					(thickness 0.15)
				)
				(justify mirror)
			)
		)
		(property "License" "Apache-2.0"
			(at 0 0 90)
			(unlocked yes)
			(layer "B.Fab")
			(hide yes)
			(effects
				(font
					(size 1 1)
					(thickness 0.15)
				)
				(justify mirror)
			)
		)
		(property "Author" "Antmicro"
			(at 0 0 90)
			(unlocked yes)
			(layer "B.Fab")
			(hide yes)
			(effects
				(font
					(size 1 1)
					(thickness 0.15)
				)
				(justify mirror)
			)
		)
		(property "Voltage" "50V"
			(at 0 0 90)
			(unlocked yes)
			(layer "B.Fab")
			(hide yes)
			(effects
				(font
					(size 1 1)
					(thickness 0.15)
				)
				(justify mirror)
			)
		)
		(property "Dielectric" "X5R"
			(at 0 0 90)
			(unlocked yes)
			(layer "B.Fab")
			(hide yes)
			(effects
				(font
					(size 1 1)
					(thickness 0.15)
				)
				(justify mirror)
			)
		)
		(sheetname "/FPGA MGT Interface/")
		(sheetfile "fpga-mgt.kicad_sch")
		(attr smd)
		(fp_rect
			(start -0.925 0.47)
			(end 0.925 -0.47)
			(stroke
				(width 0.05)
				(type default)
			)
			(fill no)
			(layer "B.CrtYd")
		)
		(fp_line
			(start 0.504 -0.248)
			(end -0.494 -0.248)
			(stroke
				(width 0.15)
				(type solid)
			)
			(layer "B.Fab")
		)
		(fp_line
			(start -0.494 -0.248)
			(end -0.494 0.25)
			(stroke
				(width 0.15)
				(type solid)
			)
			(layer "B.Fab")
		)
		(fp_line
			(start 0.504 0.25)
			(end 0.504 -0.248)
			(stroke
				(width 0.15)
				(type solid)
			)
			(layer "B.Fab")
		)
		(fp_line
			(start -0.494 0.25)
			(end 0.504 0.25)
			(stroke
				(width 0.15)
				(type solid)
			)
			(layer "B.Fab")
		)
		(fp_text user "License: Apache-2.0"
			(at -0.939 -5.799 270)
			(layer "B.Fab")
			(effects
				(font
					(size 0.7 0.7)
					(thickness 0.15)
				)
				(justify left bottom mirror)
			)
		)
		(fp_text user "Author: Antmicro"
			(at -0.939 -3.399 270)
			(layer "B.Fab")
			(effects
				(font
					(size 0.7 0.7)
					(thickness 0.15)
				)
				(justify left bottom mirror)
			)
		)
		(fp_text user "${REFERENCE}"
			(at -0.939 -4.599 270)
			(layer "B.Fab")
			(effects
				(font
					(size 0.7 0.7)
					(thickness 0.15)
				)
				(justify left bottom mirror)
			)
		)
		(pad "1" smd roundrect
			(at -0.48 0 90)
			(size 0.59 0.64)
			(layers "B.Cu" "B.Mask" "B.Paste")
			(roundrect_rratio 0.25)
			(net 256 "/FPGA MGT Interface/PCIE.TXD6_N")
			(pintype "passive")
		)
		(pad "2" smd roundrect
			(at 0.48 0 90)
			(size 0.59 0.64)
			(layers "B.Cu" "B.Mask" "B.Paste")
			(roundrect_rratio 0.25)
			(net 562 "/FPGA MGT Interface/GTY_224_TX1_N")
			(pintype "passive")
		)
	)
	(footprint "antmicro-footprints:C_0402_1005Metric"
		(layer "B.Cu")
		(at 124.2 162.5 180)
		(descr "Capacitor SMD 0402")
		(tags "capacitor SMD 0402")
		(property "Reference" "C297"
			(at -4.05 -0.35 0)
			(layer "B.SilkS")
			(effects
				(font
					(size 0.7 0.7)
					(thickness 0.15)
				)
				(justify left bottom mirror)
			)
		)
		(property "Value" "C_100n_0402"
			(at -1.022927 -2.155213 0)
			(layer "B.Fab")
			(effects
				(font
					(size 0.7 0.7)
					(thickness 0.15)
				)
				(justify left bottom mirror)
			)
		)
		(property "Datasheet" "https://www.murata.com/products/productdetail?partno=GRM155R61H104KE14%23"
			(at 0 0 180)
			(layer "F.Fab")
			(hide yes)
			(effects
				(font
					(size 1.27 1.27)
					(thickness 0.15)
				)
			)
		)
		(property "MPN" "GRM155R61H104KE14D"
			(at 0 0 180)
			(unlocked yes)
			(layer "B.Fab")
			(hide yes)
			(effects
				(font
					(size 1 1)
					(thickness 0.15)
				)
				(justify mirror)
			)
		)
		(property "Manufacturer" "Murata"
			(at 0 0 180)
			(unlocked yes)
			(layer "B.Fab")
			(hide yes)
			(effects
				(font
					(size 1 1)
					(thickness 0.15)
				)
				(justify mirror)
			)
		)
		(property "License" "Apache-2.0"
			(at 0 0 180)
			(unlocked yes)
			(layer "B.Fab")
			(hide yes)
			(effects
				(font
					(size 1 1)
					(thickness 0.15)
				)
				(justify mirror)
			)
		)
		(property "Author" "Antmicro"
			(at 0 0 180)
			(unlocked yes)
			(layer "B.Fab")
			(hide yes)
			(effects
				(font
					(size 1 1)
					(thickness 0.15)
				)
				(justify mirror)
			)
		)
		(property "Val" "100n"
			(at 0 0 180)
			(unlocked yes)
			(layer "B.Fab")
			(hide yes)
			(effects
				(font
					(size 1 1)
					(thickness 0.15)
				)
				(justify mirror)
			)
		)
		(property "Voltage" "50V"
			(at 0 0 180)
			(unlocked yes)
			(layer "B.Fab")
			(hide yes)
			(effects
				(font
					(size 1 1)
					(thickness 0.15)
				)
				(justify mirror)
			)
		)
		(property "Dielectric" "X5R"
			(at 0 0 180)
			(unlocked yes)
			(layer "B.Fab")
			(hide yes)
			(effects
				(font
					(size 1 1)
					(thickness 0.15)
				)
				(justify mirror)
			)
		)
		(sheetname "/HDMI + SD Card/")
		(sheetfile "hdmi-sd-card.kicad_sch")
		(attr smd)
		(fp_rect
			(start -0.925 0.47)
			(end 0.925 -0.47)
			(stroke
				(width 0.05)
				(type default)
			)
			(fill no)
			(layer "B.CrtYd")
		)
		(fp_line
			(start 0.504 0.25)
			(end 0.504 -0.248)
			(stroke
				(width 0.15)
				(type solid)
			)
			(layer "B.Fab")
		)
		(fp_line
			(start 0.504 -0.248)
			(end -0.494 -0.248)
			(stroke
				(width 0.15)
				(type solid)
			)
			(layer "B.Fab")
		)
		(fp_line
			(start -0.494 0.25)
			(end 0.504 0.25)
			(stroke
				(width 0.15)
				(type solid)
			)
			(layer "B.Fab")
		)
		(fp_line
			(start -0.494 -0.248)
			(end -0.494 0.25)
			(stroke
				(width 0.15)
				(type solid)
			)
			(layer "B.Fab")
		)
		(fp_text user "${REFERENCE}"
			(at -0.939 -4.599 0)
			(layer "B.Fab")
			(effects
				(font
					(size 0.7 0.7)
					(thickness 0.15)
				)
				(justify left bottom mirror)
			)
		)
		(fp_text user "Author: Antmicro"
			(at -0.939 -3.399 0)
			(layer "B.Fab")
			(effects
				(font
					(size 0.7 0.7)
					(thickness 0.15)
				)
				(justify left bottom mirror)
			)
		)
		(fp_text user "License: Apache-2.0"
			(at -0.939 -5.799 0)
			(layer "B.Fab")
			(effects
				(font
					(size 0.7 0.7)
					(thickness 0.15)
				)
				(justify left bottom mirror)
			)
		)
		(pad "1" smd roundrect
			(at -0.48 0 180)
			(size 0.59 0.64)
			(layers "B.Cu" "B.Mask" "B.Paste")
			(roundrect_rratio 0.25)
			(net 1 "GND")
			(pintype "passive")
		)
		(pad "2" smd roundrect
			(at 0.48 0 180)
			(size 0.59 0.64)
			(layers "B.Cu" "B.Mask" "B.Paste")
			(roundrect_rratio 0.25)
			(net 151 "+3V3")
			(pintype "passive")
		)
	)
	(footprint "antmicro-footprints:C_0402_1005Metric_EIA"
		(layer "B.Cu")
		(at 191 148.5 -90)
		(descr "Capacitor SMD 0402 (1005 Metric), square (rectangular) end terminal, IPC_7351 nominal, (Body size source: IPC-SM-782 page 76, https://www.pcb-3d.com/wordpress/wp-content/uploads/ipc-sm-782a_amendment_1_and_2.pdf)")
		(tags "capacitor 0402")
		(property "Reference" "C65"
			(at -12.125 30.675 90)
			(layer "B.SilkS")
			(effects
				(font
					(size 0.7 0.7)
					(thickness 0.15)
				)
				(justify left bottom mirror)
			)
		)
		(property "Value" "C_100n_0402"
			(at 0 -1.169 90)
			(layer "B.Fab")
			(effects
				(font
					(size 0.7 0.7)
					(thickness 0.15)
				)
				(justify left bottom mirror)
			)
		)
		(property "Datasheet" "https://www.murata.com/products/productdetail?partno=GRM155R61H104KE14%23"
			(at 0 0 270)
			(layer "F.Fab")
			(hide yes)
			(effects
				(font
					(size 1.27 1.27)
					(thickness 0.15)
				)
			)
		)
		(property "MPN" "GRM155R61H104KE14D"
			(at 0 0 270)
			(unlocked yes)
			(layer "B.Fab")
			(hide yes)
			(effects
				(font
					(size 1 1)
					(thickness 0.15)
				)
				(justify mirror)
			)
		)
		(property "Manufacturer" "Murata"
			(at 0 0 270)
			(unlocked yes)
			(layer "B.Fab")
			(hide yes)
			(effects
				(font
					(size 1 1)
					(thickness 0.15)
				)
				(justify mirror)
			)
		)
		(property "License" "Apache-2.0"
			(at 0 0 270)
			(unlocked yes)
			(layer "B.Fab")
			(hide yes)
			(effects
				(font
					(size 1 1)
					(thickness 0.15)
				)
				(justify mirror)
			)
		)
		(property "Author" "Antmicro"
			(at 0 0 270)
			(unlocked yes)
			(layer "B.Fab")
			(hide yes)
			(effects
				(font
					(size 1 1)
					(thickness 0.15)
				)
				(justify mirror)
			)
		)
		(property "Val" "100n"
			(at 0 0 270)
			(unlocked yes)
			(layer "B.Fab")
			(hide yes)
			(effects
				(font
					(size 1 1)
					(thickness 0.15)
				)
				(justify mirror)
			)
		)
		(property "Voltage" "50V"
			(at 0 0 270)
			(unlocked yes)
			(layer "B.Fab")
			(hide yes)
			(effects
				(font
					(size 1 1)
					(thickness 0.15)
				)
				(justify mirror)
			)
		)
		(property "Dielectric" "X5R"
			(at 0 0 270)
			(unlocked yes)
			(layer "B.Fab")
			(hide yes)
			(effects
				(font
					(size 1 1)
					(thickness 0.15)
				)
				(justify mirror)
			)
		)
		(sheetname "/FPGA power/")
		(sheetfile "fpga-power.kicad_sch")
		(attr smd)
		(fp_rect
			(start -0.95 0.45)
			(end 0.95 -0.45)
			(stroke
				(width 0.05)
				(type default)
			)
			(fill no)
			(layer "B.CrtYd")
		)
		(fp_line
			(start -0.5 0.25)
			(end 0.498 0.25)
			(stroke
				(width 0.15)
				(type solid)
			)
			(layer "B.Fab")
		)
		(fp_line
			(start 0.498 0.25)
			(end 0.498 -0.248)
			(stroke
				(width 0.15)
				(type solid)
			)
			(layer "B.Fab")
		)
		(fp_line
			(start -0.5 -0.248)
			(end -0.5 0.25)
			(stroke
				(width 0.15)
				(type solid)
			)
			(layer "B.Fab")
		)
		(fp_line
			(start 0.498 -0.248)
			(end -0.5 -0.248)
			(stroke
				(width 0.15)
				(type solid)
			)
			(layer "B.Fab")
		)
		(fp_text user "License: Apache-2.0"
			(at -0.9656 -4.369 90)
			(layer "B.Fab")
			(effects
				(font
					(size 0.7 0.7)
					(thickness 0.15)
				)
				(justify left bottom mirror)
			)
		)
		(fp_text user "${REFERENCE}"
			(at -0.9656 -3.169 90)
			(layer "B.Fab")
			(effects
				(font
					(size 0.7 0.7)
					(thickness 0.15)
				)
				(justify left bottom mirror)
			)
		)
		(fp_text user "Author: Antmicro"
			(at -0.9656 -5.569 90)
			(layer "B.Fab")
			(effects
				(font
					(size 0.7 0.7)
					(thickness 0.15)
				)
				(justify left bottom mirror)
			)
		)
		(pad "1" smd roundrect
			(at -0.5 0 180)
			(size 0.6 0.6)
			(layers "B.Cu" "B.Mask" "B.Paste")
			(roundrect_rratio 0.25)
			(net 1 "GND")
			(pintype "passive")
		)
		(pad "2" smd roundrect
			(at 0.498 0 270)
			(size 0.6 0.6)
			(layers "B.Cu" "B.Mask" "B.Paste")
			(roundrect_rratio 0.25)
			(net 553 "+0V85")
			(pintype "passive")
		)
	)
	(footprint "antmicro-footprints:Fiducial_1mm_Mask2mm"
		(layer "B.Cu")
		(at 259.37 102.04)
		(descr "Circular Fiducial, 1mm bare copper, 3mm soldermask opening")
		(tags "fiducial")
		(property "Reference" "FID1003"
			(at 0 1.4 0)
			(layer "B.SilkS")
			(hide yes)
			(effects
				(font
					(size 0.7 0.7)
					(thickness 0.15)
				)
				(justify right bottom mirror)
			)
		)
		(property "Value" "Fiducial_1mm_Mask2mm"
			(at 0 -2.2 0)
			(layer "B.Fab")
			(effects
				(font
					(size 0.7 0.7)
					(thickness 0.15)
				)
				(justify right bottom mirror)
			)
		)
		(sheetfile "data-center-rdimm-ddr5-tester.kicad_sch")
		(attr board_only exclude_from_pos_files exclude_from_bom)
		(fp_circle
			(center 0 0)
			(end 1.24 0)
			(stroke
				(width 0.05)
				(type solid)
			)
			(fill no)
			(layer "B.CrtYd")
		)
		(fp_circle
			(center 0 0)
			(end 0.999 0)
			(stroke
				(width 0.15)
				(type solid)
			)
			(fill no)
			(layer "B.Fab")
		)
		(fp_text user "${REFERENCE}"
			(at -1.25 -4.603 180)
			(layer "B.Fab")
			(effects
				(font
					(size 0.7 0.7)
					(thickness 0.15)
				)
				(justify left bottom mirror)
			)
		)
		(fp_text user "Author: Antmicro"
			(at -1.25 -5.803 180)
			(layer "B.Fab")
			(effects
				(font
					(size 0.7 0.7)
					(thickness 0.15)
				)
				(justify left bottom mirror)
			)
		)
		(fp_text user "License: Apache-2.0"
			(at -1.25 -7.003 180)
			(layer "B.Fab")
			(effects
				(font
					(size 0.7 0.7)
					(thickness 0.15)
				)
				(justify left bottom mirror)
			)
		)
		(pad "" smd circle
			(at 0 0)
			(size 1 1)
			(layers "B.Cu" "B.Mask")
			(solder_mask_margin 0.5)
			(clearance 0.5)
		)
	)
	(footprint "antmicro-footprints:C_0805_2012Metric"
		(layer "B.Cu")
		(at 230.005 185.800001)
		(descr "Capacitor SMD 0805")
		(tags "capacitor SMD 0805")
		(property "Reference" "C200"
			(at 1.945 0.799999 0)
			(layer "B.SilkS")
			(effects
				(font
					(size 0.7 0.7)
					(thickness 0.15)
				)
				(justify right bottom mirror)
			)
		)
		(property "Value" "C_22u_25V_0805"
			(at -2.055717 -1.963152 0)
			(layer "B.Fab")
			(effects
				(font
					(size 0.7 0.7)
					(thickness 0.15)
				)
				(justify right bottom mirror)
			)
		)
		(property "Datasheet" "https://product.samsungsem.com/mlcc/CL21A226MAYNNN.do"
			(at 0 0 0)
			(layer "F.Fab")
			(hide yes)
			(effects
				(font
					(size 1.27 1.27)
					(thickness 0.15)
				)
			)
		)
		(property "MPN" "CL21A226MAYNNNE"
			(at 0 0 0)
			(unlocked yes)
			(layer "B.Fab")
			(hide yes)
			(effects
				(font
					(size 1 1)
					(thickness 0.15)
				)
				(justify mirror)
			)
		)
		(property "Manufacturer" "Samsung Electro-Mechanics"
			(at 0 0 0)
			(unlocked yes)
			(layer "B.Fab")
			(hide yes)
			(effects
				(font
					(size 1 1)
					(thickness 0.15)
				)
				(justify mirror)
			)
		)
		(property "License" "Apache-2.0"
			(at 0 0 0)
			(unlocked yes)
			(layer "B.Fab")
			(hide yes)
			(effects
				(font
					(size 1 1)
					(thickness 0.15)
				)
				(justify mirror)
			)
		)
		(property "Author" "Antmicro"
			(at 0 0 0)
			(unlocked yes)
			(layer "B.Fab")
			(hide yes)
			(effects
				(font
					(size 1 1)
					(thickness 0.15)
				)
				(justify mirror)
			)
		)
		(property "Val" "22u"
			(at 0 0 0)
			(unlocked yes)
			(layer "B.Fab")
			(hide yes)
			(effects
				(font
					(size 1 1)
					(thickness 0.15)
				)
				(justify mirror)
			)
		)
		(property "Voltage" "25V"
			(at 0 0 0)
			(unlocked yes)
			(layer "B.Fab")
			(hide yes)
			(effects
				(font
					(size 1 1)
					(thickness 0.15)
				)
				(justify mirror)
			)
		)
		(property "Dielectric" "X5R"
			(at 0 0 0)
			(unlocked yes)
			(layer "B.Fab")
			(hide yes)
			(effects
				(font
					(size 1 1)
					(thickness 0.15)
				)
				(justify mirror)
			)
		)
		(property "Public" "False"
			(at 0 0 0)
			(unlocked yes)
			(layer "B.Fab")
			(hide yes)
			(effects
				(font
					(size 1 1)
					(thickness 0.15)
				)
				(justify mirror)
			)
		)
		(sheetname "/Supply/DC-DC VCCINT/")
		(sheetfile "dc-dc-vccint.kicad_sch")
		(attr smd)
		(fp_line
			(start -0.3 -0.7)
			(end 0.3 -0.7)
			(stroke
				(width 0.15)
				(type solid)
			)
			(layer "B.SilkS")
		)
		(fp_line
			(start -0.3 0.7)
			(end 0.3 0.7)
			(stroke
				(width 0.15)
				(type solid)
			)
			(layer "B.SilkS")
		)
		(fp_rect
			(start 1.95 0.9)
			(end -1.95 -0.9)
			(stroke
				(width 0.05)
				(type default)
			)
			(fill no)
			(layer "B.CrtYd")
		)
		(fp_rect
			(start -0.95 0.675)
			(end 0.95 -0.675)
			(stroke
				(width 0.15)
				(type solid)
			)
			(fill no)
			(layer "B.Fab")
		)
		(fp_text user "License: Apache-2.0"
			(at -1.9 -4.947 180)
			(layer "B.Fab")
			(effects
				(font
					(size 0.7 0.7)
					(thickness 0.15)
				)
				(justify left bottom mirror)
			)
		)
		(fp_text user "Author: Antmicro"
			(at -1.9 -5.947 180)
			(layer "B.Fab")
			(effects
				(font
					(size 0.7 0.7)
					(thickness 0.15)
				)
				(justify left bottom mirror)
			)
		)
		(fp_text user "${REFERENCE}"
			(at -1.9 -3.947 180)
			(layer "B.Fab")
			(effects
				(font
					(size 0.7 0.7)
					(thickness 0.15)
				)
				(justify left bottom mirror)
			)
		)
		(pad "1" smd roundrect
			(at -1.1 0)
			(size 1.2 1.3)
			(layers "B.Cu" "B.Mask" "B.Paste")
			(roundrect_rratio 0.25)
			(net 1 "GND")
			(pintype "passive")
		)
		(pad "2" smd roundrect
			(at 1.1 0)
			(size 1.2 1.3)
			(layers "B.Cu" "B.Mask" "B.Paste")
			(roundrect_rratio 0.25)
			(net 35 "VDC")
			(pintype "passive")
		)
	)
	(footprint "antmicro-footprints:R_0402_1005Metric"
		(layer "B.Cu")
		(at 209.89 150.6095 180)
		(descr "Resistor SMD 0402")
		(tags "resistor SMD 0402")
		(property "Reference" "R6"
			(at -2.64 -0.5005 0)
			(layer "B.SilkS")
			(effects
				(font
					(size 0.7 0.7)
					(thickness 0.15)
				)
				(justify left bottom mirror)
			)
		)
		(property "Value" "R_22R_0402"
			(at -1.011843 -1.772047 0)
			(layer "B.Fab")
			(effects
				(font
					(size 0.7 0.7)
					(thickness 0.15)
				)
				(justify left bottom mirror)
			)
		)
		(property "Datasheet" "https://www.bourns.com/docs/product-datasheets/cr.pdf"
			(at 0 0 180)
			(layer "F.Fab")
			(hide yes)
			(effects
				(font
					(size 1.27 1.27)
					(thickness 0.15)
				)
			)
		)
		(property "Manufacturer" "Bourns"
			(at 0 0 180)
			(unlocked yes)
			(layer "B.Fab")
			(hide yes)
			(effects
				(font
					(size 1 1)
					(thickness 0.15)
				)
				(justify mirror)
			)
		)
		(property "MPN" "CR0402-FX-22R0GLF"
			(at 0 0 180)
			(unlocked yes)
			(layer "B.Fab")
			(hide yes)
			(effects
				(font
					(size 1 1)
					(thickness 0.15)
				)
				(justify mirror)
			)
		)
		(property "Val" "22R"
			(at 0 0 180)
			(unlocked yes)
			(layer "B.Fab")
			(hide yes)
			(effects
				(font
					(size 1 1)
					(thickness 0.15)
				)
				(justify mirror)
			)
		)
		(property "License" "Apache-2.0"
			(at 0 0 180)
			(unlocked yes)
			(layer "B.Fab")
			(hide yes)
			(effects
				(font
					(size 1 1)
					(thickness 0.15)
				)
				(justify mirror)
			)
		)
		(property "Author" "Antmicro"
			(at 0 0 180)
			(unlocked yes)
			(layer "B.Fab")
			(hide yes)
			(effects
				(font
					(size 1 1)
					(thickness 0.15)
				)
				(justify mirror)
			)
		)
		(property "Tolerance" "1%"
			(at 0 0 180)
			(unlocked yes)
			(layer "B.Fab")
			(hide yes)
			(effects
				(font
					(size 1 1)
					(thickness 0.15)
				)
				(justify mirror)
			)
		)
		(sheetname "/HyperRAM + QSPI Flash/")
		(sheetfile "hyperram-flash.kicad_sch")
		(attr smd)
		(fp_rect
			(start -0.925 0.47)
			(end 0.925 -0.47)
			(stroke
				(width 0.05)
				(type default)
			)
			(fill no)
			(layer "B.CrtYd")
		)
		(fp_rect
			(start -0.5 0.25)
			(end 0.5 -0.25)
			(stroke
				(width 0.15)
				(type solid)
			)
			(fill no)
			(layer "B.Fab")
		)
		(fp_text user "License: Apache-2.0"
			(at -0.95 -5.169 0)
			(layer "B.Fab")
			(effects
				(font
					(size 0.7 0.7)
					(thickness 0.15)
				)
				(justify left bottom mirror)
			)
		)
		(fp_text user "${REFERENCE}"
			(at -0.95 -3.168 0)
			(layer "B.Fab")
			(effects
				(font
					(size 0.7 0.7)
					(thickness 0.15)
				)
				(justify left bottom mirror)
			)
		)
		(fp_text user "Author: Antmicro"
			(at -0.95 -4.169 0)
			(layer "B.Fab")
			(effects
				(font
					(size 0.7 0.7)
					(thickness 0.15)
				)
				(justify left bottom mirror)
			)
		)
		(pad "1" smd roundrect
			(at -0.48 0 180)
			(size 0.59 0.64)
			(layers "B.Cu" "B.Mask" "B.Paste")
			(roundrect_rratio 0.25)
			(net 281 "/HyperRAM + QSPI Flash/IO0")
			(pintype "passive")
		)
		(pad "2" smd roundrect
			(at 0.48 0 180)
			(size 0.59 0.64)
			(layers "B.Cu" "B.Mask" "B.Paste")
			(roundrect_rratio 0.25)
			(net 351 "/FPGA Config/FLASH.IO0")
			(pintype "passive")
		)
	)
	(footprint "antmicro-footprints:C_0402_1005Metric_EIA"
		(layer "B.Cu")
		(at 182 162.5 90)
		(descr "Capacitor SMD 0402 (1005 Metric), square (rectangular) end terminal, IPC_7351 nominal, (Body size source: IPC-SM-782 page 76, https://www.pcb-3d.com/wordpress/wp-content/uploads/ipc-sm-782a_amendment_1_and_2.pdf)")
		(tags "capacitor 0402")
		(property "Reference" "C80"
			(at -3.3 0.25 90)
			(layer "B.SilkS")
			(effects
				(font
					(size 0.7 0.7)
					(thickness 0.15)
				)
				(justify right bottom mirror)
			)
		)
		(property "Value" "C_100n_0402"
			(at 0 -1.169 90)
			(layer "B.Fab")
			(effects
				(font
					(size 0.7 0.7)
					(thickness 0.15)
				)
				(justify right bottom mirror)
			)
		)
		(property "Datasheet" "https://www.murata.com/products/productdetail?partno=GRM155R61H104KE14%23"
			(at 0 0 90)
			(layer "F.Fab")
			(hide yes)
			(effects
				(font
					(size 1.27 1.27)
					(thickness 0.15)
				)
			)
		)
		(property "MPN" "GRM155R61H104KE14D"
			(at 0 0 90)
			(unlocked yes)
			(layer "B.Fab")
			(hide yes)
			(effects
				(font
					(size 1 1)
					(thickness 0.15)
				)
				(justify mirror)
			)
		)
		(property "Manufacturer" "Murata"
			(at 0 0 90)
			(unlocked yes)
			(layer "B.Fab")
			(hide yes)
			(effects
				(font
					(size 1 1)
					(thickness 0.15)
				)
				(justify mirror)
			)
		)
		(property "License" "Apache-2.0"
			(at 0 0 90)
			(unlocked yes)
			(layer "B.Fab")
			(hide yes)
			(effects
				(font
					(size 1 1)
					(thickness 0.15)
				)
				(justify mirror)
			)
		)
		(property "Author" "Antmicro"
			(at 0 0 90)
			(unlocked yes)
			(layer "B.Fab")
			(hide yes)
			(effects
				(font
					(size 1 1)
					(thickness 0.15)
				)
				(justify mirror)
			)
		)
		(property "Val" "100n"
			(at 0 0 90)
			(unlocked yes)
			(layer "B.Fab")
			(hide yes)
			(effects
				(font
					(size 1 1)
					(thickness 0.15)
				)
				(justify mirror)
			)
		)
		(property "Voltage" "50V"
			(at 0 0 90)
			(unlocked yes)
			(layer "B.Fab")
			(hide yes)
			(effects
				(font
					(size 1 1)
					(thickness 0.15)
				)
				(justify mirror)
			)
		)
		(property "Dielectric" "X5R"
			(at 0 0 90)
			(unlocked yes)
			(layer "B.Fab")
			(hide yes)
			(effects
				(font
					(size 1 1)
					(thickness 0.15)
				)
				(justify mirror)
			)
		)
		(sheetname "/FPGA power/")
		(sheetfile "fpga-power.kicad_sch")
		(attr smd)
		(fp_rect
			(start -0.95 0.45)
			(end 0.95 -0.45)
			(stroke
				(width 0.05)
				(type default)
			)
			(fill no)
			(layer "B.CrtYd")
		)
		(fp_line
			(start 0.498 -0.248)
			(end -0.5 -0.248)
			(stroke
				(width 0.15)
				(type solid)
			)
			(layer "B.Fab")
		)
		(fp_line
			(start -0.5 -0.248)
			(end -0.5 0.25)
			(stroke
				(width 0.15)
				(type solid)
			)
			(layer "B.Fab")
		)
		(fp_line
			(start 0.498 0.25)
			(end 0.498 -0.248)
			(stroke
				(width 0.15)
				(type solid)
			)
			(layer "B.Fab")
		)
		(fp_line
			(start -0.5 0.25)
			(end 0.498 0.25)
			(stroke
				(width 0.15)
				(type solid)
			)
			(layer "B.Fab")
		)
		(fp_text user "License: Apache-2.0"
			(at -0.9656 -4.369 270)
			(layer "B.Fab")
			(effects
				(font
					(size 0.7 0.7)
					(thickness 0.15)
				)
				(justify left bottom mirror)
			)
		)
		(fp_text user "${REFERENCE}"
			(at -0.9656 -3.169 270)
			(layer "B.Fab")
			(effects
				(font
					(size 0.7 0.7)
					(thickness 0.15)
				)
				(justify left bottom mirror)
			)
		)
		(fp_text user "Author: Antmicro"
			(at -0.9656 -5.569 270)
			(layer "B.Fab")
			(effects
				(font
					(size 0.7 0.7)
					(thickness 0.15)
				)
				(justify left bottom mirror)
			)
		)
		(pad "1" smd roundrect
			(at -0.5 0)
			(size 0.6 0.6)
			(layers "B.Cu" "B.Mask" "B.Paste")
			(roundrect_rratio 0.25)
			(net 1 "GND")
			(pintype "passive")
		)
		(pad "2" smd roundrect
			(at 0.498 0 90)
			(size 0.6 0.6)
			(layers "B.Cu" "B.Mask" "B.Paste")
			(roundrect_rratio 0.25)
			(net 172 "+1V2_MGTAVTT")
			(pintype "passive")
		)
	)
	(footprint "antmicro-footprints:SC70-3"
		(layer "B.Cu")
		(at 114.755 110.25 180)
		(property "Reference" "Q6"
			(at -3.355 -0.334 0)
			(layer "B.SilkS")
			(effects
				(font
					(size 0.7 0.7)
					(thickness 0.15)
				)
				(justify left bottom mirror)
			)
		)
		(property "Value" "BSS138PW"
			(at 0 -2.3 0)
			(layer "B.Fab")
			(effects
				(font
					(size 0.7 0.7)
					(thickness 0.15)
				)
				(justify left bottom mirror)
			)
		)
		(property "Datasheet" "https://assets.nexperia.com/documents/data-sheet/BSS138PW.pdf"
			(at 0 0 180)
			(layer "F.Fab")
			(hide yes)
			(effects
				(font
					(size 1.27 1.27)
					(thickness 0.15)
				)
			)
		)
		(property "MPN" "BSS138PW"
			(at 0 0 180)
			(unlocked yes)
			(layer "B.Fab")
			(hide yes)
			(effects
				(font
					(size 1 1)
					(thickness 0.15)
				)
				(justify mirror)
			)
		)
		(property "Manufacturer" "Nexperia"
			(at 0 0 180)
			(unlocked yes)
			(layer "B.Fab")
			(hide yes)
			(effects
				(font
					(size 1 1)
					(thickness 0.15)
				)
				(justify mirror)
			)
		)
		(property "Author" "Antmicro"
			(at 0 0 180)
			(unlocked yes)
			(layer "B.Fab")
			(hide yes)
			(effects
				(font
					(size 1 1)
					(thickness 0.15)
				)
				(justify mirror)
			)
		)
		(property "License" "Apache-2.0"
			(at 0 0 180)
			(unlocked yes)
			(layer "B.Fab")
			(hide yes)
			(effects
				(font
					(size 1 1)
					(thickness 0.15)
				)
				(justify mirror)
			)
		)
		(sheetname "/FPGA banks HD/")
		(sheetfile "fpga-hd-banks.kicad_sch")
		(attr smd)
		(fp_line
			(start 0.627 0.6)
			(end 0.627 0.999)
			(stroke
				(width 0.15)
				(type solid)
			)
			(layer "B.SilkS")
		)
		(fp_line
			(start 0.627 -0.6)
			(end 0.627 -1.001)
			(stroke
				(width 0.15)
				(type solid)
			)
			(layer "B.SilkS")
		)
		(fp_line
			(start -0.3 1)
			(end 0.627 0.999)
			(stroke
				(width 0.15)
				(type solid)
			)
			(layer "B.SilkS")
		)
		(fp_line
			(start -0.3 -1)
			(end 0.627 -1.001)
			(stroke
				(width 0.15)
				(type solid)
			)
			(layer "B.SilkS")
		)
		(fp_line
			(start 1.4 0.4)
			(end 1.4 -0.4)
			(stroke
				(width 0.05)
				(type solid)
			)
			(layer "B.CrtYd")
		)
		(fp_line
			(start 1.4 -0.4)
			(end 0.9 -0.4)
			(stroke
				(width 0.05)
				(type solid)
			)
			(layer "B.CrtYd")
		)
		(fp_line
			(start 0.9 1.3)
			(end 0.9 0.4)
			(stroke
				(width 0.05)
				(type solid)
			)
			(layer "B.CrtYd")
		)
		(fp_line
			(start 0.9 0.4)
			(end 1.4 0.4)
			(stroke
				(width 0.05)
				(type solid)
			)
			(layer "B.CrtYd")
		)
		(fp_line
			(start 0.9 -0.4)
			(end 0.9 -1.3)
			(stroke
				(width 0.05)
				(type solid)
			)
			(layer "B.CrtYd")
		)
		(fp_line
			(start 0.9 -1.3)
			(end -0.9 -1.3)
			(stroke
				(width 0.05)
				(type solid)
			)
			(layer "B.CrtYd")
		)
		(fp_line
			(start -0.9 1.3)
			(end 0.9 1.3)
			(stroke
				(width 0.05)
				(type solid)
			)
			(layer "B.CrtYd")
		)
		(fp_line
			(start -0.9 1.3)
			(end -0.9 1)
			(stroke
				(width 0.05)
				(type solid)
			)
			(layer "B.CrtYd")
		)
		(fp_line
			(start -0.9 1)
			(end -1.4 1)
			(stroke
				(width 0.05)
				(type solid)
			)
			(layer "B.CrtYd")
		)
		(fp_line
			(start -0.9 -1)
			(end -1.4 -1)
			(stroke
				(width 0.05)
				(type solid)
			)
			(layer "B.CrtYd")
		)
		(fp_line
			(start -0.9 -1.3)
			(end -0.9 -1)
			(stroke
				(width 0.05)
				(type solid)
			)
			(layer "B.CrtYd")
		)
		(fp_line
			(start -1.4 -1)
			(end -1.4 1)
			(stroke
				(width 0.05)
				(type solid)
			)
			(layer "B.CrtYd")
		)
		(fp_rect
			(start -0.623 0.999)
			(end 0.627 -1.001)
			(stroke
				(width 0.15)
				(type solid)
			)
			(fill no)
			(layer "B.Fab")
		)
		(fp_text user "${REFERENCE}"
			(at -1.45 -4.783 0)
			(layer "B.Fab")
			(effects
				(font
					(size 0.7 0.7)
					(thickness 0.15)
				)
				(justify left bottom mirror)
			)
		)
		(fp_text user "Author: Antmicro"
			(at -1.45 -5.782 0)
			(layer "B.Fab")
			(effects
				(font
					(size 0.7 0.7)
					(thickness 0.15)
				)
				(justify left bottom mirror)
			)
		)
		(fp_text user "License: Apache-2.0"
			(at -1.45 -6.782 0)
			(layer "B.Fab")
			(effects
				(font
					(size 0.7 0.7)
					(thickness 0.15)
				)
				(justify left bottom mirror)
			)
		)
		(pad "1" smd rect
			(at -1.051 0.65 90)
			(size 0.6 0.6)
			(layers "B.Cu" "B.Mask" "B.Paste")
			(net 699 "/FPGA banks HD/USR_LED3")
			(pinfunction "G")
			(pintype "passive")
		)
		(pad "2" smd rect
			(at -1.051 -0.65 90)
			(size 0.6 0.6)
			(layers "B.Cu" "B.Mask" "B.Paste")
			(net 1 "GND")
			(pinfunction "S")
			(pintype "passive")
		)
		(pad "3" smd rect
			(at 1.05 0 90)
			(size 0.6 0.6)
			(layers "B.Cu" "B.Mask" "B.Paste")
			(net 274 "Net-(Q6-D)")
			(pinfunction "D")
			(pintype "passive")
		)
	)
	(footprint "antmicro-footprints:C_0402_1005Metric_EIA"
		(layer "B.Cu")
		(at 186 148.5 90)
		(descr "Capacitor SMD 0402 (1005 Metric), square (rectangular) end terminal, IPC_7351 nominal, (Body size source: IPC-SM-782 page 76, https://www.pcb-3d.com/wordpress/wp-content/uploads/ipc-sm-782a_amendment_1_and_2.pdf)")
		(tags "capacitor 0402")
		(property "Reference" "C19"
			(at 9.525 -30.575 90)
			(layer "B.SilkS")
			(effects
				(font
					(size 0.7 0.7)
					(thickness 0.15)
				)
				(justify right bottom mirror)
			)
		)
		(property "Value" "C_100n_0402"
			(at 0 -1.169 90)
			(layer "B.Fab")
			(effects
				(font
					(size 0.7 0.7)
					(thickness 0.15)
				)
				(justify right bottom mirror)
			)
		)
		(property "Datasheet" "https://www.murata.com/products/productdetail?partno=GRM155R61H104KE14%23"
			(at 0 0 90)
			(layer "F.Fab")
			(hide yes)
			(effects
				(font
					(size 1.27 1.27)
					(thickness 0.15)
				)
			)
		)
		(property "MPN" "GRM155R61H104KE14D"
			(at 0 0 90)
			(unlocked yes)
			(layer "B.Fab")
			(hide yes)
			(effects
				(font
					(size 1 1)
					(thickness 0.15)
				)
				(justify mirror)
			)
		)
		(property "Manufacturer" "Murata"
			(at 0 0 90)
			(unlocked yes)
			(layer "B.Fab")
			(hide yes)
			(effects
				(font
					(size 1 1)
					(thickness 0.15)
				)
				(justify mirror)
			)
		)
		(property "License" "Apache-2.0"
			(at 0 0 90)
			(unlocked yes)
			(layer "B.Fab")
			(hide yes)
			(effects
				(font
					(size 1 1)
					(thickness 0.15)
				)
				(justify mirror)
			)
		)
		(property "Author" "Antmicro"
			(at 0 0 90)
			(unlocked yes)
			(layer "B.Fab")
			(hide yes)
			(effects
				(font
					(size 1 1)
					(thickness 0.15)
				)
				(justify mirror)
			)
		)
		(property "Val" "100n"
			(at 0 0 90)
			(unlocked yes)
			(layer "B.Fab")
			(hide yes)
			(effects
				(font
					(size 1 1)
					(thickness 0.15)
				)
				(justify mirror)
			)
		)
		(property "Voltage" "50V"
			(at 0 0 90)
			(unlocked yes)
			(layer "B.Fab")
			(hide yes)
			(effects
				(font
					(size 1 1)
					(thickness 0.15)
				)
				(justify mirror)
			)
		)
		(property "Dielectric" "X5R"
			(at 0 0 90)
			(unlocked yes)
			(layer "B.Fab")
			(hide yes)
			(effects
				(font
					(size 1 1)
					(thickness 0.15)
				)
				(justify mirror)
			)
		)
		(sheetname "/FPGA power/")
		(sheetfile "fpga-power.kicad_sch")
		(attr smd)
		(fp_rect
			(start -0.95 0.45)
			(end 0.95 -0.45)
			(stroke
				(width 0.05)
				(type default)
			)
			(fill no)
			(layer "B.CrtYd")
		)
		(fp_line
			(start 0.498 -0.248)
			(end -0.5 -0.248)
			(stroke
				(width 0.15)
				(type solid)
			)
			(layer "B.Fab")
		)
		(fp_line
			(start -0.5 -0.248)
			(end -0.5 0.25)
			(stroke
				(width 0.15)
				(type solid)
			)
			(layer "B.Fab")
		)
		(fp_line
			(start 0.498 0.25)
			(end 0.498 -0.248)
			(stroke
				(width 0.15)
				(type solid)
			)
			(layer "B.Fab")
		)
		(fp_line
			(start -0.5 0.25)
			(end 0.498 0.25)
			(stroke
				(width 0.15)
				(type solid)
			)
			(layer "B.Fab")
		)
		(fp_text user "Author: Antmicro"
			(at -0.9656 -5.569 270)
			(layer "B.Fab")
			(effects
				(font
					(size 0.7 0.7)
					(thickness 0.15)
				)
				(justify left bottom mirror)
			)
		)
		(fp_text user "${REFERENCE}"
			(at -0.9656 -3.169 270)
			(layer "B.Fab")
			(effects
				(font
					(size 0.7 0.7)
					(thickness 0.15)
				)
				(justify left bottom mirror)
			)
		)
		(fp_text user "License: Apache-2.0"
			(at -0.9656 -4.369 270)
			(layer "B.Fab")
			(effects
				(font
					(size 0.7 0.7)
					(thickness 0.15)
				)
				(justify left bottom mirror)
			)
		)
		(pad "1" smd roundrect
			(at -0.5 0)
			(size 0.6 0.6)
			(layers "B.Cu" "B.Mask" "B.Paste")
			(roundrect_rratio 0.25)
			(net 1 "GND")
			(pintype "passive")
		)
		(pad "2" smd roundrect
			(at 0.498 0 90)
			(size 0.6 0.6)
			(layers "B.Cu" "B.Mask" "B.Paste")
			(roundrect_rratio 0.25)
			(net 553 "+0V85")
			(pintype "passive")
		)
	)
	(footprint "antmicro-footprints:R_0402_1005Metric"
		(layer "B.Cu")
		(at 238.777999 143.09)
		(descr "Resistor SMD 0402")
		(tags "resistor SMD 0402")
		(property "Reference" "R235"
			(at 1.397001 0.385 0)
			(layer "B.SilkS")
			(effects
				(font
					(size 0.7 0.7)
					(thickness 0.15)
				)
				(justify right bottom mirror)
			)
		)
		(property "Value" "R_47k_0402"
			(at -1.011843 -1.772047 0)
			(layer "B.Fab")
			(effects
				(font
					(size 0.7 0.7)
					(thickness 0.15)
				)
				(justify right bottom mirror)
			)
		)
		(property "Datasheet" "https://www.bourns.com/docs/product-datasheets/cr.pdf"
			(at 0 0 0)
			(layer "F.Fab")
			(hide yes)
			(effects
				(font
					(size 1.27 1.27)
					(thickness 0.15)
				)
			)
		)
		(property "Manufacturer" "Bourns"
			(at 0 0 0)
			(unlocked yes)
			(layer "B.Fab")
			(hide yes)
			(effects
				(font
					(size 1 1)
					(thickness 0.15)
				)
				(justify mirror)
			)
		)
		(property "MPN" "CR0402-FX-4702GLF"
			(at 0 0 0)
			(unlocked yes)
			(layer "B.Fab")
			(hide yes)
			(effects
				(font
					(size 1 1)
					(thickness 0.15)
				)
				(justify mirror)
			)
		)
		(property "Val" "47k"
			(at 0 0 0)
			(unlocked yes)
			(layer "B.Fab")
			(hide yes)
			(effects
				(font
					(size 1 1)
					(thickness 0.15)
				)
				(justify mirror)
			)
		)
		(property "License" "Apache-2.0"
			(at 0 0 0)
			(unlocked yes)
			(layer "B.Fab")
			(hide yes)
			(effects
				(font
					(size 1 1)
					(thickness 0.15)
				)
				(justify mirror)
			)
		)
		(property "Author" "Antmicro"
			(at 0 0 0)
			(unlocked yes)
			(layer "B.Fab")
			(hide yes)
			(effects
				(font
					(size 1 1)
					(thickness 0.15)
				)
				(justify mirror)
			)
		)
		(property "Tolerance" "1%"
			(at 0 0 0)
			(unlocked yes)
			(layer "B.Fab")
			(hide yes)
			(effects
				(font
					(size 1 1)
					(thickness 0.15)
				)
				(justify mirror)
			)
		)
		(sheetname "/Supply/")
		(sheetfile "supply.kicad_sch")
		(attr smd)
		(fp_rect
			(start -0.925 0.47)
			(end 0.925 -0.47)
			(stroke
				(width 0.05)
				(type default)
			)
			(fill no)
			(layer "B.CrtYd")
		)
		(fp_rect
			(start -0.5 0.25)
			(end 0.5 -0.25)
			(stroke
				(width 0.15)
				(type solid)
			)
			(fill no)
			(layer "B.Fab")
		)
		(fp_text user "${REFERENCE}"
			(at -0.95 -3.168 180)
			(layer "B.Fab")
			(effects
				(font
					(size 0.7 0.7)
					(thickness 0.15)
				)
				(justify left bottom mirror)
			)
		)
		(fp_text user "License: Apache-2.0"
			(at -0.95 -5.169 180)
			(layer "B.Fab")
			(effects
				(font
					(size 0.7 0.7)
					(thickness 0.15)
				)
				(justify left bottom mirror)
			)
		)
		(fp_text user "Author: Antmicro"
			(at -0.95 -4.169 180)
			(layer "B.Fab")
			(effects
				(font
					(size 0.7 0.7)
					(thickness 0.15)
				)
				(justify left bottom mirror)
			)
		)
		(pad "1" smd roundrect
			(at -0.48 0)
			(size 0.59 0.64)
			(layers "B.Cu" "B.Mask" "B.Paste")
			(roundrect_rratio 0.25)
			(net 1 "GND")
			(pintype "passive")
		)
		(pad "2" smd roundrect
			(at 0.48 0)
			(size 0.59 0.64)
			(layers "B.Cu" "B.Mask" "B.Paste")
			(roundrect_rratio 0.25)
			(net 626 "USER_IN")
			(pintype "passive")
		)
	)
	(footprint "antmicro-footprints:R_0402_1005Metric"
		(layer "B.Cu")
		(at 252.2 186.349)
		(descr "Resistor SMD 0402")
		(tags "resistor SMD 0402")
		(property "Reference" "R241"
			(at 1 0.551 0)
			(layer "B.SilkS")
			(effects
				(font
					(size 0.7 0.7)
					(thickness 0.15)
				)
				(justify right bottom mirror)
			)
		)
		(property "Value" "R_4k7_0402"
			(at -1.011843 -1.772047 0)
			(layer "B.Fab")
			(effects
				(font
					(size 0.7 0.7)
					(thickness 0.15)
				)
				(justify right bottom mirror)
			)
		)
		(property "Datasheet" "https://www.bourns.com/docs/product-datasheets/cr.pdf"
			(at 0 0 0)
			(layer "F.Fab")
			(hide yes)
			(effects
				(font
					(size 1.27 1.27)
					(thickness 0.15)
				)
			)
		)
		(property "MPN" "CR0402-FX-4701GLF"
			(at 0 0 0)
			(unlocked yes)
			(layer "B.Fab")
			(hide yes)
			(effects
				(font
					(size 1 1)
					(thickness 0.15)
				)
				(justify mirror)
			)
		)
		(property "Manufacturer" "Bourns"
			(at 0 0 0)
			(unlocked yes)
			(layer "B.Fab")
			(hide yes)
			(effects
				(font
					(size 1 1)
					(thickness 0.15)
				)
				(justify mirror)
			)
		)
		(property "License" "Apache-2.0"
			(at 0 0 0)
			(unlocked yes)
			(layer "B.Fab")
			(hide yes)
			(effects
				(font
					(size 1 1)
					(thickness 0.15)
				)
				(justify mirror)
			)
		)
		(property "Author" "Antmicro"
			(at 0 0 0)
			(unlocked yes)
			(layer "B.Fab")
			(hide yes)
			(effects
				(font
					(size 1 1)
					(thickness 0.15)
				)
				(justify mirror)
			)
		)
		(property "Val" "4k7"
			(at 0 0 0)
			(unlocked yes)
			(layer "B.Fab")
			(hide yes)
			(effects
				(font
					(size 1 1)
					(thickness 0.15)
				)
				(justify mirror)
			)
		)
		(property "Tolerance" "1%"
			(at 0 0 0)
			(unlocked yes)
			(layer "B.Fab")
			(hide yes)
			(effects
				(font
					(size 1 1)
					(thickness 0.15)
				)
				(justify mirror)
			)
		)
		(sheetname "/I^{2}C + I3C/")
		(sheetfile "i2c.kicad_sch")
		(attr smd)
		(fp_rect
			(start -0.925 0.47)
			(end 0.925 -0.47)
			(stroke
				(width 0.05)
				(type default)
			)
			(fill no)
			(layer "B.CrtYd")
		)
		(fp_rect
			(start -0.5 0.25)
			(end 0.5 -0.25)
			(stroke
				(width 0.15)
				(type solid)
			)
			(fill no)
			(layer "B.Fab")
		)
		(fp_text user "Author: Antmicro"
			(at -0.95 -4.169 180)
			(layer "B.Fab")
			(effects
				(font
					(size 0.7 0.7)
					(thickness 0.15)
				)
				(justify left bottom mirror)
			)
		)
		(fp_text user "${REFERENCE}"
			(at -0.95 -3.168 180)
			(layer "B.Fab")
			(effects
				(font
					(size 0.7 0.7)
					(thickness 0.15)
				)
				(justify left bottom mirror)
			)
		)
		(fp_text user "License: Apache-2.0"
			(at -0.95 -5.169 180)
			(layer "B.Fab")
			(effects
				(font
					(size 0.7 0.7)
					(thickness 0.15)
				)
				(justify left bottom mirror)
			)
		)
		(pad "1" smd roundrect
			(at -0.48 0)
			(size 0.59 0.64)
			(layers "B.Cu" "B.Mask" "B.Paste")
			(roundrect_rratio 0.25)
			(net 369 "/I^{2}C + I3C/I3C_EXT.SCL")
			(pintype "passive")
		)
		(pad "2" smd roundrect
			(at 0.48 0)
			(size 0.59 0.64)
			(layers "B.Cu" "B.Mask" "B.Paste")
			(roundrect_rratio 0.25)
			(net 782 "Net-(Q24-D)")
			(pintype "passive")
		)
	)
	(footprint "antmicro-footprints:Fiducial_1mm_Mask2mm"
		(layer "B.Cu")
		(at 113.585 186.315 180)
		(descr "Circular Fiducial, 1mm bare copper, 3mm soldermask opening")
		(tags "fiducial")
		(property "Reference" "FID1001"
			(at 0 1.4 0)
			(layer "B.SilkS")
			(hide yes)
			(effects
				(font
					(size 0.7 0.7)
					(thickness 0.15)
				)
				(justify left bottom mirror)
			)
		)
		(property "Value" "Fiducial_1mm_Mask2mm"
			(at 0 -2.2 0)
			(layer "B.Fab")
			(effects
				(font
					(size 0.7 0.7)
					(thickness 0.15)
				)
				(justify left bottom mirror)
			)
		)
		(sheetfile "data-center-rdimm-ddr5-tester.kicad_sch")
		(attr board_only exclude_from_pos_files exclude_from_bom)
		(fp_circle
			(center 0 0)
			(end 1.24 0)
			(stroke
				(width 0.05)
				(type solid)
			)
			(fill no)
			(layer "B.CrtYd")
		)
		(fp_circle
			(center 0 0)
			(end 0.999 0)
			(stroke
				(width 0.15)
				(type solid)
			)
			(fill no)
			(layer "B.Fab")
		)
		(fp_text user "License: Apache-2.0"
			(at -1.25 -7.003 0)
			(layer "B.Fab")
			(effects
				(font
					(size 0.7 0.7)
					(thickness 0.15)
				)
				(justify left bottom mirror)
			)
		)
		(fp_text user "${REFERENCE}"
			(at -1.25 -4.603 0)
			(layer "B.Fab")
			(effects
				(font
					(size 0.7 0.7)
					(thickness 0.15)
				)
				(justify left bottom mirror)
			)
		)
		(fp_text user "Author: Antmicro"
			(at -1.25 -5.803 0)
			(layer "B.Fab")
			(effects
				(font
					(size 0.7 0.7)
					(thickness 0.15)
				)
				(justify left bottom mirror)
			)
		)
		(pad "" smd circle
			(at 0 0 180)
			(size 1 1)
			(layers "B.Cu" "B.Mask")
			(solder_mask_margin 0.5)
			(clearance 0.5)
		)
	)
	(footprint "antmicro-footprints:C_0402_1005Metric"
		(layer "B.Cu")
		(at 187.49 167.45 90)
		(descr "Capacitor SMD 0402")
		(tags "capacitor SMD 0402")
		(property "Reference" "C276"
			(at -4 0.724 90)
			(layer "B.SilkS")
			(effects
				(font
					(size 0.7 0.7)
					(thickness 0.15)
				)
				(justify right bottom mirror)
			)
		)
		(property "Value" "C_100n_0402"
			(at -1.022927 -2.155213 90)
			(layer "B.Fab")
			(effects
				(font
					(size 0.7 0.7)
					(thickness 0.15)
				)
				(justify right bottom mirror)
			)
		)
		(property "Datasheet" "https://www.murata.com/products/productdetail?partno=GRM155R61H104KE14%23"
			(at 0 0 90)
			(layer "F.Fab")
			(hide yes)
			(effects
				(font
					(size 1.27 1.27)
					(thickness 0.15)
				)
			)
		)
		(property "Manufacturer" "Murata"
			(at 0 0 90)
			(unlocked yes)
			(layer "B.Fab")
			(hide yes)
			(effects
				(font
					(size 1 1)
					(thickness 0.15)
				)
				(justify mirror)
			)
		)
		(property "MPN" "GRM155R61H104KE14D"
			(at 0 0 90)
			(unlocked yes)
			(layer "B.Fab")
			(hide yes)
			(effects
				(font
					(size 1 1)
					(thickness 0.15)
				)
				(justify mirror)
			)
		)
		(property "Val" "100n"
			(at 0 0 90)
			(unlocked yes)
			(layer "B.Fab")
			(hide yes)
			(effects
				(font
					(size 1 1)
					(thickness 0.15)
				)
				(justify mirror)
			)
		)
		(property "License" "Apache-2.0"
			(at 0 0 90)
			(unlocked yes)
			(layer "B.Fab")
			(hide yes)
			(effects
				(font
					(size 1 1)
					(thickness 0.15)
				)
				(justify mirror)
			)
		)
		(property "Author" "Antmicro"
			(at 0 0 90)
			(unlocked yes)
			(layer "B.Fab")
			(hide yes)
			(effects
				(font
					(size 1 1)
					(thickness 0.15)
				)
				(justify mirror)
			)
		)
		(property "Voltage" "50V"
			(at 0 0 90)
			(unlocked yes)
			(layer "B.Fab")
			(hide yes)
			(effects
				(font
					(size 1 1)
					(thickness 0.15)
				)
				(justify mirror)
			)
		)
		(property "Dielectric" "X5R"
			(at 0 0 90)
			(unlocked yes)
			(layer "B.Fab")
			(hide yes)
			(effects
				(font
					(size 1 1)
					(thickness 0.15)
				)
				(justify mirror)
			)
		)
		(sheetname "/FPGA MGT Interface/")
		(sheetfile "fpga-mgt.kicad_sch")
		(attr smd)
		(fp_rect
			(start -0.925 0.47)
			(end 0.925 -0.47)
			(stroke
				(width 0.05)
				(type default)
			)
			(fill no)
			(layer "B.CrtYd")
		)
		(fp_line
			(start 0.504 -0.248)
			(end -0.494 -0.248)
			(stroke
				(width 0.15)
				(type solid)
			)
			(layer "B.Fab")
		)
		(fp_line
			(start -0.494 -0.248)
			(end -0.494 0.25)
			(stroke
				(width 0.15)
				(type solid)
			)
			(layer "B.Fab")
		)
		(fp_line
			(start 0.504 0.25)
			(end 0.504 -0.248)
			(stroke
				(width 0.15)
				(type solid)
			)
			(layer "B.Fab")
		)
		(fp_line
			(start -0.494 0.25)
			(end 0.504 0.25)
			(stroke
				(width 0.15)
				(type solid)
			)
			(layer "B.Fab")
		)
		(fp_text user "License: Apache-2.0"
			(at -0.939 -5.799 270)
			(layer "B.Fab")
			(effects
				(font
					(size 0.7 0.7)
					(thickness 0.15)
				)
				(justify left bottom mirror)
			)
		)
		(fp_text user "${REFERENCE}"
			(at -0.939 -4.599 270)
			(layer "B.Fab")
			(effects
				(font
					(size 0.7 0.7)
					(thickness 0.15)
				)
				(justify left bottom mirror)
			)
		)
		(fp_text user "Author: Antmicro"
			(at -0.939 -3.399 270)
			(layer "B.Fab")
			(effects
				(font
					(size 0.7 0.7)
					(thickness 0.15)
				)
				(justify left bottom mirror)
			)
		)
		(pad "1" smd roundrect
			(at -0.48 0 90)
			(size 0.59 0.64)
			(layers "B.Cu" "B.Mask" "B.Paste")
			(roundrect_rratio 0.25)
			(net 248 "/FPGA MGT Interface/HDMI_OUT.D0_N")
			(pintype "passive")
		)
		(pad "2" smd roundrect
			(at 0.48 0 90)
			(size 0.59 0.64)
			(layers "B.Cu" "B.Mask" "B.Paste")
			(roundrect_rratio 0.25)
			(net 631 "/FPGA MGT Interface/HDMI_FPGA.TX0_N")
			(pintype "passive")
		)
	)
	(footprint "antmicro-footprints:R_0402_1005Metric"
		(layer "B.Cu")
		(at 238.424499 181.449 180)
		(descr "Resistor SMD 0402")
		(tags "resistor SMD 0402")
		(property "Reference" "R178"
			(at -3.95 -0.5 0)
			(layer "B.SilkS")
			(effects
				(font
					(size 0.7 0.7)
					(thickness 0.15)
				)
				(justify left bottom mirror)
			)
		)
		(property "Value" "R_0R_0402"
			(at -1.011843 -1.772047 0)
			(layer "B.Fab")
			(effects
				(font
					(size 0.7 0.7)
					(thickness 0.15)
				)
				(justify left bottom mirror)
			)
		)
		(property "Datasheet" "https://industrial.panasonic.com/cdbs/www-data/pdf/RDA0000/AOA0000C301.pdf"
			(at 0 0 180)
			(layer "F.Fab")
			(hide yes)
			(effects
				(font
					(size 1.27 1.27)
					(thickness 0.15)
				)
			)
		)
		(property "Manufacturer" "Panasonic"
			(at 0 0 180)
			(unlocked yes)
			(layer "B.Fab")
			(hide yes)
			(effects
				(font
					(size 1 1)
					(thickness 0.15)
				)
				(justify mirror)
			)
		)
		(property "MPN" "ERJ2GE0R00X"
			(at 0 0 180)
			(unlocked yes)
			(layer "B.Fab")
			(hide yes)
			(effects
				(font
					(size 1 1)
					(thickness 0.15)
				)
				(justify mirror)
			)
		)
		(property "Val" "0R"
			(at 0 0 180)
			(unlocked yes)
			(layer "B.Fab")
			(hide yes)
			(effects
				(font
					(size 1 1)
					(thickness 0.15)
				)
				(justify mirror)
			)
		)
		(property "License" "Apache-2.0"
			(at 0 0 180)
			(unlocked yes)
			(layer "B.Fab")
			(hide yes)
			(effects
				(font
					(size 1 1)
					(thickness 0.15)
				)
				(justify mirror)
			)
		)
		(property "Author" "Antmicro"
			(at 0 0 180)
			(unlocked yes)
			(layer "B.Fab")
			(hide yes)
			(effects
				(font
					(size 1 1)
					(thickness 0.15)
				)
				(justify mirror)
			)
		)
		(property "Tolerance" "~"
			(at 0 0 180)
			(unlocked yes)
			(layer "B.Fab")
			(hide yes)
			(effects
				(font
					(size 1 1)
					(thickness 0.15)
				)
				(justify mirror)
			)
		)
		(property "Current" "1A"
			(at 0 0 180)
			(unlocked yes)
			(layer "B.Fab")
			(hide yes)
			(effects
				(font
					(size 1 1)
					(thickness 0.15)
				)
				(justify mirror)
			)
		)
		(sheetname "/I^{2}C + I3C/")
		(sheetfile "i2c.kicad_sch")
		(attr smd exclude_from_bom dnp)
		(fp_rect
			(start -0.925 0.47)
			(end 0.925 -0.47)
			(stroke
				(width 0.05)
				(type default)
			)
			(fill no)
			(layer "B.CrtYd")
		)
		(fp_rect
			(start -0.5 0.25)
			(end 0.5 -0.25)
			(stroke
				(width 0.15)
				(type solid)
			)
			(fill no)
			(layer "B.Fab")
		)
		(fp_text user "Author: Antmicro"
			(at -0.95 -4.169 0)
			(layer "B.Fab")
			(effects
				(font
					(size 0.7 0.7)
					(thickness 0.15)
				)
				(justify left bottom mirror)
			)
		)
		(fp_text user "License: Apache-2.0"
			(at -0.95 -5.169 0)
			(layer "B.Fab")
			(effects
				(font
					(size 0.7 0.7)
					(thickness 0.15)
				)
				(justify left bottom mirror)
			)
		)
		(fp_text user "${REFERENCE}"
			(at -0.95 -3.168 0)
			(layer "B.Fab")
			(effects
				(font
					(size 0.7 0.7)
					(thickness 0.15)
				)
				(justify left bottom mirror)
			)
		)
		(pad "1" smd roundrect
			(at -0.48 0 180)
			(size 0.59 0.64)
			(layers "B.Cu" "B.Mask" "B.Paste")
			(roundrect_rratio 0.25)
			(net 749 "/I^{2}C + I3C/PWR.SCL")
			(pintype "passive")
		)
		(pad "2" smd roundrect
			(at 0.48 0 180)
			(size 0.59 0.64)
			(layers "B.Cu" "B.Mask" "B.Paste")
			(roundrect_rratio 0.25)
			(net 747 "/FPGA Config/FPGA_PWR.SCL")
			(pintype "passive")
		)
	)
	(footprint "antmicro-footprints:C_0805_2012Metric"
		(layer "B.Cu")
		(at 230.005 187.67)
		(descr "Capacitor SMD 0805")
		(tags "capacitor SMD 0805")
		(property "Reference" "C202"
			(at 1.945 1.13 0)
			(layer "B.SilkS")
			(effects
				(font
					(size 0.7 0.7)
					(thickness 0.15)
				)
				(justify right bottom mirror)
			)
		)
		(property "Value" "C_22u_25V_0805"
			(at -2.055717 -1.963152 0)
			(layer "B.Fab")
			(effects
				(font
					(size 0.7 0.7)
					(thickness 0.15)
				)
				(justify right bottom mirror)
			)
		)
		(property "Datasheet" "https://product.samsungsem.com/mlcc/CL21A226MAYNNN.do"
			(at 0 0 0)
			(layer "F.Fab")
			(hide yes)
			(effects
				(font
					(size 1.27 1.27)
					(thickness 0.15)
				)
			)
		)
		(property "MPN" "CL21A226MAYNNNE"
			(at 0 0 0)
			(unlocked yes)
			(layer "B.Fab")
			(hide yes)
			(effects
				(font
					(size 1 1)
					(thickness 0.15)
				)
				(justify mirror)
			)
		)
		(property "Manufacturer" "Samsung Electro-Mechanics"
			(at 0 0 0)
			(unlocked yes)
			(layer "B.Fab")
			(hide yes)
			(effects
				(font
					(size 1 1)
					(thickness 0.15)
				)
				(justify mirror)
			)
		)
		(property "License" "Apache-2.0"
			(at 0 0 0)
			(unlocked yes)
			(layer "B.Fab")
			(hide yes)
			(effects
				(font
					(size 1 1)
					(thickness 0.15)
				)
				(justify mirror)
			)
		)
		(property "Author" "Antmicro"
			(at 0 0 0)
			(unlocked yes)
			(layer "B.Fab")
			(hide yes)
			(effects
				(font
					(size 1 1)
					(thickness 0.15)
				)
				(justify mirror)
			)
		)
		(property "Val" "22u"
			(at 0 0 0)
			(unlocked yes)
			(layer "B.Fab")
			(hide yes)
			(effects
				(font
					(size 1 1)
					(thickness 0.15)
				)
				(justify mirror)
			)
		)
		(property "Voltage" "25V"
			(at 0 0 0)
			(unlocked yes)
			(layer "B.Fab")
			(hide yes)
			(effects
				(font
					(size 1 1)
					(thickness 0.15)
				)
				(justify mirror)
			)
		)
		(property "Dielectric" "X5R"
			(at 0 0 0)
			(unlocked yes)
			(layer "B.Fab")
			(hide yes)
			(effects
				(font
					(size 1 1)
					(thickness 0.15)
				)
				(justify mirror)
			)
		)
		(property "Public" "False"
			(at 0 0 0)
			(unlocked yes)
			(layer "B.Fab")
			(hide yes)
			(effects
				(font
					(size 1 1)
					(thickness 0.15)
				)
				(justify mirror)
			)
		)
		(sheetname "/Supply/DC-DC VCCINT/")
		(sheetfile "dc-dc-vccint.kicad_sch")
		(attr smd)
		(fp_line
			(start -0.3 -0.7)
			(end 0.3 -0.7)
			(stroke
				(width 0.15)
				(type solid)
			)
			(layer "B.SilkS")
		)
		(fp_line
			(start -0.3 0.7)
			(end 0.3 0.7)
			(stroke
				(width 0.15)
				(type solid)
			)
			(layer "B.SilkS")
		)
		(fp_rect
			(start 1.95 0.9)
			(end -1.95 -0.9)
			(stroke
				(width 0.05)
				(type default)
			)
			(fill no)
			(layer "B.CrtYd")
		)
		(fp_rect
			(start -0.95 0.675)
			(end 0.95 -0.675)
			(stroke
				(width 0.15)
				(type solid)
			)
			(fill no)
			(layer "B.Fab")
		)
		(fp_text user "${REFERENCE}"
			(at -1.9 -3.947 180)
			(layer "B.Fab")
			(effects
				(font
					(size 0.7 0.7)
					(thickness 0.15)
				)
				(justify left bottom mirror)
			)
		)
		(fp_text user "License: Apache-2.0"
			(at -1.9 -4.947 180)
			(layer "B.Fab")
			(effects
				(font
					(size 0.7 0.7)
					(thickness 0.15)
				)
				(justify left bottom mirror)
			)
		)
		(fp_text user "Author: Antmicro"
			(at -1.9 -5.947 180)
			(layer "B.Fab")
			(effects
				(font
					(size 0.7 0.7)
					(thickness 0.15)
				)
				(justify left bottom mirror)
			)
		)
		(pad "1" smd roundrect
			(at -1.1 0)
			(size 1.2 1.3)
			(layers "B.Cu" "B.Mask" "B.Paste")
			(roundrect_rratio 0.25)
			(net 1 "GND")
			(pintype "passive")
		)
		(pad "2" smd roundrect
			(at 1.1 0)
			(size 1.2 1.3)
			(layers "B.Cu" "B.Mask" "B.Paste")
			(roundrect_rratio 0.25)
			(net 35 "VDC")
			(pintype "passive")
		)
	)
	(footprint "antmicro-footprints:R_0402_1005Metric_EIA"
		(layer "B.Cu")
		(at 196.51 158)
		(descr "Resistor SMD 0402 (1005 Metric), square (rectangular) end terminal, IPC_7351 nominal, (Body size source: IPC-SM-782 page 76, https://www.pcb-3d.com/wordpress/wp-content/uploads/ipc-sm-782a_amendment_1_and_2.pdf)")
		(tags "resistor 0402")
		(property "Reference" "R18"
			(at -29.885 -10.35 180)
			(layer "B.SilkS")
			(effects
				(font
					(size 0.7 0.7)
					(thickness 0.15)
				)
				(justify left bottom mirror)
			)
		)
		(property "Value" "R_4k7_0402"
			(at 0 -1.169 180)
			(layer "B.Fab")
			(effects
				(font
					(size 0.7 0.7)
					(thickness 0.15)
				)
				(justify left bottom mirror)
			)
		)
		(property "Datasheet" "https://www.bourns.com/docs/product-datasheets/cr.pdf"
			(at 0 0 0)
			(layer "F.Fab")
			(hide yes)
			(effects
				(font
					(size 1.27 1.27)
					(thickness 0.15)
				)
			)
		)
		(property "Manufacturer" "Bourns"
			(at 0 0 0)
			(unlocked yes)
			(layer "B.Fab")
			(hide yes)
			(effects
				(font
					(size 1 1)
					(thickness 0.15)
				)
				(justify mirror)
			)
		)
		(property "MPN" "CR0402-FX-4701GLF"
			(at 0 0 0)
			(unlocked yes)
			(layer "B.Fab")
			(hide yes)
			(effects
				(font
					(size 1 1)
					(thickness 0.15)
				)
				(justify mirror)
			)
		)
		(property "Val" "4k7"
			(at 0 0 0)
			(unlocked yes)
			(layer "B.Fab")
			(hide yes)
			(effects
				(font
					(size 1 1)
					(thickness 0.15)
				)
				(justify mirror)
			)
		)
		(property "License" "Apache-2.0"
			(at 0 0 0)
			(unlocked yes)
			(layer "B.Fab")
			(hide yes)
			(effects
				(font
					(size 1 1)
					(thickness 0.15)
				)
				(justify mirror)
			)
		)
		(property "Author" "Antmicro"
			(at 0 0 0)
			(unlocked yes)
			(layer "B.Fab")
			(hide yes)
			(effects
				(font
					(size 1 1)
					(thickness 0.15)
				)
				(justify mirror)
			)
		)
		(property "Tolerance" "1%"
			(at 0 0 0)
			(unlocked yes)
			(layer "B.Fab")
			(hide yes)
			(effects
				(font
					(size 1 1)
					(thickness 0.15)
				)
				(justify mirror)
			)
		)
		(sheetname "/FPGA Config/")
		(sheetfile "fpga-config.kicad_sch")
		(attr smd)
		(fp_rect
			(start -0.95 0.45)
			(end 0.95 -0.45)
			(stroke
				(width 0.05)
				(type default)
			)
			(fill no)
			(layer "B.CrtYd")
		)
		(fp_line
			(start -0.5 -0.249)
			(end -0.5 0.25)
			(stroke
				(width 0.15)
				(type solid)
			)
			(layer "B.Fab")
		)
		(fp_line
			(start -0.5 0.25)
			(end 0.499 0.25)
			(stroke
				(width 0.15)
				(type solid)
			)
			(layer "B.Fab")
		)
		(fp_line
			(start 0.499 -0.249)
			(end -0.5 -0.249)
			(stroke
				(width 0.15)
				(type solid)
			)
			(layer "B.Fab")
		)
		(fp_line
			(start 0.499 0.25)
			(end 0.499 -0.249)
			(stroke
				(width 0.15)
				(type solid)
			)
			(layer "B.Fab")
		)
		(fp_text user "Author: Antmicro"
			(at -0.95 -5.569 180)
			(layer "B.Fab")
			(effects
				(font
					(size 0.7 0.7)
					(thickness 0.15)
				)
				(justify left bottom mirror)
			)
		)
		(fp_text user "License: Apache-2.0"
			(at -0.95 -4.369 180)
			(layer "B.Fab")
			(effects
				(font
					(size 0.7 0.7)
					(thickness 0.15)
				)
				(justify left bottom mirror)
			)
		)
		(fp_text user "${REFERENCE}"
			(at -0.95 -3.169 180)
			(layer "B.Fab")
			(effects
				(font
					(size 0.7 0.7)
					(thickness 0.15)
				)
				(justify left bottom mirror)
			)
		)
		(pad "1" smd roundrect
			(at -0.5 0 270)
			(size 0.6 0.6)
			(layers "B.Cu" "B.Mask" "B.Paste")
			(roundrect_rratio 0.25)
			(net 797 "+1V8")
			(pintype "passive")
		)
		(pad "2" smd roundrect
			(at 0.499 0)
			(size 0.6 0.6)
			(layers "B.Cu" "B.Mask" "B.Paste")
			(roundrect_rratio 0.25)
			(net 357 "/FPGA Config/PROGRAM_B")
			(pintype "passive")
		)
	)
	(footprint "antmicro-footprints:R_0402_1005Metric"
		(layer "B.Cu")
		(at 236.22 156.182 -90)
		(descr "Resistor SMD 0402")
		(tags "resistor SMD 0402")
		(property "Reference" "R209"
			(at 0.918 -0.44 90)
			(layer "B.SilkS")
			(effects
				(font
					(size 0.7 0.7)
					(thickness 0.15)
				)
				(justify left bottom mirror)
			)
		)
		(property "Value" "R_0R_0402"
			(at -1.011843 -1.772047 90)
			(layer "B.Fab")
			(effects
				(font
					(size 0.7 0.7)
					(thickness 0.15)
				)
				(justify left bottom mirror)
			)
		)
		(property "Datasheet" "https://industrial.panasonic.com/cdbs/www-data/pdf/RDA0000/AOA0000C301.pdf"
			(at 0 0 270)
			(layer "F.Fab")
			(hide yes)
			(effects
				(font
					(size 1.27 1.27)
					(thickness 0.15)
				)
			)
		)
		(property "MPN" "ERJ2GE0R00X"
			(at 0 0 270)
			(unlocked yes)
			(layer "B.Fab")
			(hide yes)
			(effects
				(font
					(size 1 1)
					(thickness 0.15)
				)
				(justify mirror)
			)
		)
		(property "Manufacturer" "Panasonic"
			(at 0 0 270)
			(unlocked yes)
			(layer "B.Fab")
			(hide yes)
			(effects
				(font
					(size 1 1)
					(thickness 0.15)
				)
				(justify mirror)
			)
		)
		(property "License" "Apache-2.0"
			(at 0 0 270)
			(unlocked yes)
			(layer "B.Fab")
			(hide yes)
			(effects
				(font
					(size 1 1)
					(thickness 0.15)
				)
				(justify mirror)
			)
		)
		(property "Author" "Antmicro"
			(at 0 0 270)
			(unlocked yes)
			(layer "B.Fab")
			(hide yes)
			(effects
				(font
					(size 1 1)
					(thickness 0.15)
				)
				(justify mirror)
			)
		)
		(property "Val" "0R"
			(at 0 0 270)
			(unlocked yes)
			(layer "B.Fab")
			(hide yes)
			(effects
				(font
					(size 1 1)
					(thickness 0.15)
				)
				(justify mirror)
			)
		)
		(property "Tolerance" "~"
			(at 0 0 270)
			(unlocked yes)
			(layer "B.Fab")
			(hide yes)
			(effects
				(font
					(size 1 1)
					(thickness 0.15)
				)
				(justify mirror)
			)
		)
		(property "Current" "1A"
			(at 0 0 270)
			(unlocked yes)
			(layer "B.Fab")
			(hide yes)
			(effects
				(font
					(size 1 1)
					(thickness 0.15)
				)
				(justify mirror)
			)
		)
		(sheetname "/Supply/DC-DC IO/")
		(sheetfile "dc-dc-io.kicad_sch")
		(attr smd)
		(fp_rect
			(start -0.925 0.47)
			(end 0.925 -0.47)
			(stroke
				(width 0.05)
				(type default)
			)
			(fill no)
			(layer "B.CrtYd")
		)
		(fp_rect
			(start -0.5 0.25)
			(end 0.5 -0.25)
			(stroke
				(width 0.15)
				(type solid)
			)
			(fill no)
			(layer "B.Fab")
		)
		(fp_text user "Author: Antmicro"
			(at -0.95 -4.169 90)
			(layer "B.Fab")
			(effects
				(font
					(size 0.7 0.7)
					(thickness 0.15)
				)
				(justify left bottom mirror)
			)
		)
		(fp_text user "${REFERENCE}"
			(at -0.95 -3.168 90)
			(layer "B.Fab")
			(effects
				(font
					(size 0.7 0.7)
					(thickness 0.15)
				)
				(justify left bottom mirror)
			)
		)
		(fp_text user "License: Apache-2.0"
			(at -0.95 -5.169 90)
			(layer "B.Fab")
			(effects
				(font
					(size 0.7 0.7)
					(thickness 0.15)
				)
				(justify left bottom mirror)
			)
		)
		(pad "1" smd roundrect
			(at -0.48 0 270)
			(size 0.59 0.64)
			(layers "B.Cu" "B.Mask" "B.Paste")
			(roundrect_rratio 0.25)
			(net 730 "Net-(U28-IN1+)")
			(pintype "passive")
		)
		(pad "2" smd roundrect
			(at 0.48 0 270)
			(size 0.59 0.64)
			(layers "B.Cu" "B.Mask" "B.Paste")
			(roundrect_rratio 0.25)
			(net 685 "/Supply/DC-DC IO/3V3_SEN_+")
			(pintype "passive")
		)
	)
	(footprint "antmicro-footprints:TP_SMD_1mm"
		(layer "B.Cu")
		(at 215 180.65 90)
		(property "Reference" "TP10"
			(at 0.7 0.4 90)
			(layer "B.SilkS")
			(effects
				(font
					(size 0.7 0.7)
					(thickness 0.15)
				)
				(justify right bottom mirror)
			)
		)
		(property "Value" "TP_1mm_SMD"
			(at 0 -1.4 90)
			(layer "B.Fab")
			(effects
				(font
					(size 0.7 0.7)
					(thickness 0.15)
				)
				(justify right bottom mirror)
			)
		)
		(property "MPN" ""
			(at 0 0 90)
			(unlocked yes)
			(layer "B.Fab")
			(hide yes)
			(effects
				(font
					(size 1 1)
					(thickness 0.15)
				)
				(justify mirror)
			)
		)
		(property "Manufacturer" ""
			(at 0 0 90)
			(unlocked yes)
			(layer "B.Fab")
			(hide yes)
			(effects
				(font
					(size 1 1)
					(thickness 0.15)
				)
				(justify mirror)
			)
		)
		(property "Author" "Antmicro"
			(at 0 0 90)
			(unlocked yes)
			(layer "B.Fab")
			(hide yes)
			(effects
				(font
					(size 1 1)
					(thickness 0.15)
				)
				(justify mirror)
			)
		)
		(property "License" "Apache-2.0"
			(at 0 0 90)
			(unlocked yes)
			(layer "B.Fab")
			(hide yes)
			(effects
				(font
					(size 1 1)
					(thickness 0.15)
				)
				(justify mirror)
			)
		)
		(sheetname "/Supply/DC-DC VCCINT/")
		(sheetfile "dc-dc-vccint.kicad_sch")
		(attr exclude_from_pos_files)
		(fp_circle
			(center 0 0)
			(end 0.6 0)
			(stroke
				(width 0.05)
				(type default)
			)
			(fill no)
			(layer "B.CrtYd")
		)
		(fp_text user "License: Apache-2.0"
			(at -0.5 -5.2 270)
			(layer "B.Fab")
			(effects
				(font
					(size 0.7 0.7)
					(thickness 0.15)
				)
				(justify left bottom mirror)
			)
		)
		(fp_text user "${REFERENCE}"
			(at -0.5 -2.8 270)
			(layer "B.Fab")
			(effects
				(font
					(size 0.7 0.7)
					(thickness 0.15)
				)
				(justify left bottom mirror)
			)
		)
		(fp_text user "Author: Antmicro"
			(at -0.5 -4 270)
			(layer "B.Fab")
			(effects
				(font
					(size 0.7 0.7)
					(thickness 0.15)
				)
				(justify left bottom mirror)
			)
		)
		(pad "1" smd circle
			(at 0 0 90)
			(size 1 1)
			(layers "B.Cu" "B.Mask")
			(net 741 "/Supply/DC-DC VCCINT/PWR.~{ALT}1")
			(pinfunction "1")
			(pintype "passive")
		)
	)
	(footprint "antmicro-footprints:C_0402_1005Metric_EIA"
		(layer "B.Cu")
		(at 194.5 158)
		(descr "Capacitor SMD 0402 (1005 Metric), square (rectangular) end terminal, IPC_7351 nominal, (Body size source: IPC-SM-782 page 76, https://www.pcb-3d.com/wordpress/wp-content/uploads/ipc-sm-782a_amendment_1_and_2.pdf)")
		(tags "capacitor 0402")
		(property "Reference" "C18"
			(at -32.15 -10.3 0)
			(layer "B.SilkS")
			(effects
				(font
					(size 0.7 0.7)
					(thickness 0.15)
				)
				(justify right bottom mirror)
			)
		)
		(property "Value" "C_10u_10V_0402"
			(at 0 -1.169 0)
			(layer "B.Fab")
			(effects
				(font
					(size 0.7 0.7)
					(thickness 0.15)
				)
				(justify right bottom mirror)
			)
		)
		(property "Datasheet" "https://www.murata.com/products/productdetail?partno=GRM155R61A106ME11%23"
			(at 0 0 0)
			(layer "F.Fab")
			(hide yes)
			(effects
				(font
					(size 1.27 1.27)
					(thickness 0.15)
				)
			)
		)
		(property "MPN" "GRM155R61A106ME11D"
			(at 0 0 0)
			(unlocked yes)
			(layer "B.Fab")
			(hide yes)
			(effects
				(font
					(size 1 1)
					(thickness 0.15)
				)
				(justify mirror)
			)
		)
		(property "Manufacturer" "Murata"
			(at 0 0 0)
			(unlocked yes)
			(layer "B.Fab")
			(hide yes)
			(effects
				(font
					(size 1 1)
					(thickness 0.15)
				)
				(justify mirror)
			)
		)
		(property "License" "Apache-2.0"
			(at 0 0 0)
			(unlocked yes)
			(layer "B.Fab")
			(hide yes)
			(effects
				(font
					(size 1 1)
					(thickness 0.15)
				)
				(justify mirror)
			)
		)
		(property "Author" "Antmicro"
			(at 0 0 0)
			(unlocked yes)
			(layer "B.Fab")
			(hide yes)
			(effects
				(font
					(size 1 1)
					(thickness 0.15)
				)
				(justify mirror)
			)
		)
		(property "Val" "10u"
			(at 0 0 0)
			(unlocked yes)
			(layer "B.Fab")
			(hide yes)
			(effects
				(font
					(size 1 1)
					(thickness 0.15)
				)
				(justify mirror)
			)
		)
		(property "Voltage" "10V"
			(at 0 0 0)
			(unlocked yes)
			(layer "B.Fab")
			(hide yes)
			(effects
				(font
					(size 1 1)
					(thickness 0.15)
				)
				(justify mirror)
			)
		)
		(property "Dielectric" "X5R"
			(at 0 0 0)
			(unlocked yes)
			(layer "B.Fab")
			(hide yes)
			(effects
				(font
					(size 1 1)
					(thickness 0.15)
				)
				(justify mirror)
			)
		)
		(sheetname "/FPGA power/")
		(sheetfile "fpga-power.kicad_sch")
		(attr smd)
		(fp_rect
			(start -0.95 0.45)
			(end 0.95 -0.45)
			(stroke
				(width 0.05)
				(type default)
			)
			(fill no)
			(layer "B.CrtYd")
		)
		(fp_line
			(start -0.5 -0.248)
			(end -0.5 0.25)
			(stroke
				(width 0.15)
				(type solid)
			)
			(layer "B.Fab")
		)
		(fp_line
			(start -0.5 0.25)
			(end 0.498 0.25)
			(stroke
				(width 0.15)
				(type solid)
			)
			(layer "B.Fab")
		)
		(fp_line
			(start 0.498 -0.248)
			(end -0.5 -0.248)
			(stroke
				(width 0.15)
				(type solid)
			)
			(layer "B.Fab")
		)
		(fp_line
			(start 0.498 0.25)
			(end 0.498 -0.248)
			(stroke
				(width 0.15)
				(type solid)
			)
			(layer "B.Fab")
		)
		(fp_text user "License: Apache-2.0"
			(at -0.9656 -4.369 180)
			(layer "B.Fab")
			(effects
				(font
					(size 0.7 0.7)
					(thickness 0.15)
				)
				(justify left bottom mirror)
			)
		)
		(fp_text user "Author: Antmicro"
			(at -0.9656 -5.569 180)
			(layer "B.Fab")
			(effects
				(font
					(size 0.7 0.7)
					(thickness 0.15)
				)
				(justify left bottom mirror)
			)
		)
		(fp_text user "${REFERENCE}"
			(at -0.9656 -3.169 180)
			(layer "B.Fab")
			(effects
				(font
					(size 0.7 0.7)
					(thickness 0.15)
				)
				(justify left bottom mirror)
			)
		)
		(pad "1" smd roundrect
			(at -0.5 0 270)
			(size 0.6 0.6)
			(layers "B.Cu" "B.Mask" "B.Paste")
			(roundrect_rratio 0.25)
			(net 1 "GND")
			(pintype "passive")
		)
		(pad "2" smd roundrect
			(at 0.498 0)
			(size 0.6 0.6)
			(layers "B.Cu" "B.Mask" "B.Paste")
			(roundrect_rratio 0.25)
			(net 797 "+1V8")
			(pintype "passive")
		)
	)
	(footprint "antmicro-footprints:R_0402_1005Metric"
		(layer "B.Cu")
		(at 168.1 154.5)
		(descr "Resistor SMD 0402")
		(tags "resistor SMD 0402")
		(property "Reference" "R1"
			(at 0.9 0.4 0)
			(layer "B.SilkS")
			(effects
				(font
					(size 0.7 0.7)
					(thickness 0.15)
				)
				(justify right bottom mirror)
			)
		)
		(property "Value" "R_10k_0402"
			(at -1.011843 -1.772047 0)
			(layer "B.Fab")
			(effects
				(font
					(size 0.7 0.7)
					(thickness 0.15)
				)
				(justify right bottom mirror)
			)
		)
		(property "Datasheet" "https://www.bourns.com/docs/product-datasheets/cr.pdf"
			(at 0 0 0)
			(layer "F.Fab")
			(hide yes)
			(effects
				(font
					(size 1.27 1.27)
					(thickness 0.15)
				)
			)
		)
		(property "Manufacturer" "Bourns"
			(at 0 0 0)
			(unlocked yes)
			(layer "B.Fab")
			(hide yes)
			(effects
				(font
					(size 1 1)
					(thickness 0.15)
				)
				(justify mirror)
			)
		)
		(property "MPN" "CR0402-FX-1002GLF"
			(at 0 0 0)
			(unlocked yes)
			(layer "B.Fab")
			(hide yes)
			(effects
				(font
					(size 1 1)
					(thickness 0.15)
				)
				(justify mirror)
			)
		)
		(property "Val" "10k"
			(at 0 0 0)
			(unlocked yes)
			(layer "B.Fab")
			(hide yes)
			(effects
				(font
					(size 1 1)
					(thickness 0.15)
				)
				(justify mirror)
			)
		)
		(property "License" "Apache-2.0"
			(at 0 0 0)
			(unlocked yes)
			(layer "B.Fab")
			(hide yes)
			(effects
				(font
					(size 1 1)
					(thickness 0.15)
				)
				(justify mirror)
			)
		)
		(property "Author" "Antmicro"
			(at 0 0 0)
			(unlocked yes)
			(layer "B.Fab")
			(hide yes)
			(effects
				(font
					(size 1 1)
					(thickness 0.15)
				)
				(justify mirror)
			)
		)
		(property "Tolerance" "1%"
			(at 0 0 0)
			(unlocked yes)
			(layer "B.Fab")
			(hide yes)
			(effects
				(font
					(size 1 1)
					(thickness 0.15)
				)
				(justify mirror)
			)
		)
		(sheetname "/HyperRAM + QSPI Flash/")
		(sheetfile "hyperram-flash.kicad_sch")
		(attr smd)
		(fp_rect
			(start -0.925 0.47)
			(end 0.925 -0.47)
			(stroke
				(width 0.05)
				(type default)
			)
			(fill no)
			(layer "B.CrtYd")
		)
		(fp_rect
			(start -0.5 0.25)
			(end 0.5 -0.25)
			(stroke
				(width 0.15)
				(type solid)
			)
			(fill no)
			(layer "B.Fab")
		)
		(fp_text user "${REFERENCE}"
			(at -0.95 -3.168 180)
			(layer "B.Fab")
			(effects
				(font
					(size 0.7 0.7)
					(thickness 0.15)
				)
				(justify left bottom mirror)
			)
		)
		(fp_text user "License: Apache-2.0"
			(at -0.95 -5.169 180)
			(layer "B.Fab")
			(effects
				(font
					(size 0.7 0.7)
					(thickness 0.15)
				)
				(justify left bottom mirror)
			)
		)
		(fp_text user "Author: Antmicro"
			(at -0.95 -4.169 180)
			(layer "B.Fab")
			(effects
				(font
					(size 0.7 0.7)
					(thickness 0.15)
				)
				(justify left bottom mirror)
			)
		)
		(pad "1" smd roundrect
			(at -0.48 0)
			(size 0.59 0.64)
			(layers "B.Cu" "B.Mask" "B.Paste")
			(roundrect_rratio 0.25)
			(net 797 "+1V8")
			(pintype "passive")
		)
		(pad "2" smd roundrect
			(at 0.48 0)
			(size 0.59 0.64)
			(layers "B.Cu" "B.Mask" "B.Paste")
			(roundrect_rratio 0.25)
			(net 623 "/FPGA banks HP/HyperRAM.~{RESET}")
			(pintype "passive")
		)
	)
	(footprint "antmicro-footprints:R_0402_1005Metric"
		(layer "B.Cu")
		(at 222.875 177.915 90)
		(descr "Resistor SMD 0402")
		(tags "resistor SMD 0402")
		(property "Reference" "R203"
			(at -1.11 1.75 90)
			(layer "B.SilkS")
			(effects
				(font
					(size 0.7 0.7)
					(thickness 0.15)
				)
				(justify right bottom mirror)
			)
		)
		(property "Value" "R_0R_0402"
			(at 0.215 1.675 90)
			(layer "B.Fab")
			(effects
				(font
					(size 0.7 0.7)
					(thickness 0.15)
				)
				(justify right bottom mirror)
			)
		)
		(property "Datasheet" "https://industrial.panasonic.com/cdbs/www-data/pdf/RDA0000/AOA0000C301.pdf"
			(at 0 0 90)
			(layer "F.Fab")
			(hide yes)
			(effects
				(font
					(size 1.27 1.27)
					(thickness 0.15)
				)
			)
		)
		(property "MPN" "ERJ2GE0R00X"
			(at 0 0 90)
			(unlocked yes)
			(layer "B.Fab")
			(hide yes)
			(effects
				(font
					(size 1 1)
					(thickness 0.15)
				)
				(justify mirror)
			)
		)
		(property "Manufacturer" "Panasonic"
			(at 0 0 90)
			(unlocked yes)
			(layer "B.Fab")
			(hide yes)
			(effects
				(font
					(size 1 1)
					(thickness 0.15)
				)
				(justify mirror)
			)
		)
		(property "License" "Apache-2.0"
			(at 0 0 90)
			(unlocked yes)
			(layer "B.Fab")
			(hide yes)
			(effects
				(font
					(size 1 1)
					(thickness 0.15)
				)
				(justify mirror)
			)
		)
		(property "Author" "Antmicro"
			(at 0 0 90)
			(unlocked yes)
			(layer "B.Fab")
			(hide yes)
			(effects
				(font
					(size 1 1)
					(thickness 0.15)
				)
				(justify mirror)
			)
		)
		(property "Val" "0R"
			(at 0 0 90)
			(unlocked yes)
			(layer "B.Fab")
			(hide yes)
			(effects
				(font
					(size 1 1)
					(thickness 0.15)
				)
				(justify mirror)
			)
		)
		(property "Tolerance" "~"
			(at 0 0 90)
			(unlocked yes)
			(layer "B.Fab")
			(hide yes)
			(effects
				(font
					(size 1 1)
					(thickness 0.15)
				)
				(justify mirror)
			)
		)
		(property "Current" "1A"
			(at 0 0 90)
			(unlocked yes)
			(layer "B.Fab")
			(hide yes)
			(effects
				(font
					(size 1 1)
					(thickness 0.15)
				)
				(justify mirror)
			)
		)
		(sheetname "/Supply/DC-DC VCCINT/")
		(sheetfile "dc-dc-vccint.kicad_sch")
		(attr smd exclude_from_bom dnp)
		(fp_rect
			(start -0.925 0.47)
			(end 0.925 -0.47)
			(stroke
				(width 0.05)
				(type default)
			)
			(fill no)
			(layer "B.CrtYd")
		)
		(fp_rect
			(start -0.5 0.25)
			(end 0.5 -0.25)
			(stroke
				(width 0.15)
				(type solid)
			)
			(fill no)
			(layer "B.Fab")
		)
		(fp_text user "${REFERENCE}"
			(at -0.95 -3.168 270)
			(layer "B.Fab")
			(effects
				(font
					(size 0.7 0.7)
					(thickness 0.15)
				)
				(justify left bottom mirror)
			)
		)
		(fp_text user "License: Apache-2.0"
			(at -0.95 -5.169 270)
			(layer "B.Fab")
			(effects
				(font
					(size 0.7 0.7)
					(thickness 0.15)
				)
				(justify left bottom mirror)
			)
		)
		(fp_text user "Author: Antmicro"
			(at -0.95 -4.169 270)
			(layer "B.Fab")
			(effects
				(font
					(size 0.7 0.7)
					(thickness 0.15)
				)
				(justify left bottom mirror)
			)
		)
		(pad "1" smd roundrect
			(at -0.48 0 90)
			(size 0.59 0.64)
			(layers "B.Cu" "B.Mask" "B.Paste")
			(roundrect_rratio 0.25)
			(net 756 "Net-(C264-Pad2)")
			(pintype "passive")
		)
		(pad "2" smd roundrect
			(at 0.48 0 90)
			(size 0.59 0.64)
			(layers "B.Cu" "B.Mask" "B.Paste")
			(roundrect_rratio 0.25)
			(net 223 "/Supply/DC-DC VCCINT/0V85_REG0")
			(pintype "passive")
		)
	)
	(footprint "antmicro-footprints:R_0402_1005Metric"
		(layer "B.Cu")
		(at 238.424499 188.849 180)
		(descr "Resistor SMD 0402")
		(tags "resistor SMD 0402")
		(property "Reference" "R174"
			(at -3.95 -0.5 0)
			(layer "B.SilkS")
			(effects
				(font
					(size 0.7 0.7)
					(thickness 0.15)
				)
				(justify left bottom mirror)
			)
		)
		(property "Value" "R_0R_0402"
			(at -1.011843 -1.772047 0)
			(layer "B.Fab")
			(effects
				(font
					(size 0.7 0.7)
					(thickness 0.15)
				)
				(justify left bottom mirror)
			)
		)
		(property "Datasheet" "https://industrial.panasonic.com/cdbs/www-data/pdf/RDA0000/AOA0000C301.pdf"
			(at 0 0 180)
			(layer "F.Fab")
			(hide yes)
			(effects
				(font
					(size 1.27 1.27)
					(thickness 0.15)
				)
			)
		)
		(property "Manufacturer" "Panasonic"
			(at 0 0 180)
			(unlocked yes)
			(layer "B.Fab")
			(hide yes)
			(effects
				(font
					(size 1 1)
					(thickness 0.15)
				)
				(justify mirror)
			)
		)
		(property "MPN" "ERJ2GE0R00X"
			(at 0 0 180)
			(unlocked yes)
			(layer "B.Fab")
			(hide yes)
			(effects
				(font
					(size 1 1)
					(thickness 0.15)
				)
				(justify mirror)
			)
		)
		(property "Val" "0R"
			(at 0 0 180)
			(unlocked yes)
			(layer "B.Fab")
			(hide yes)
			(effects
				(font
					(size 1 1)
					(thickness 0.15)
				)
				(justify mirror)
			)
		)
		(property "License" "Apache-2.0"
			(at 0 0 180)
			(unlocked yes)
			(layer "B.Fab")
			(hide yes)
			(effects
				(font
					(size 1 1)
					(thickness 0.15)
				)
				(justify mirror)
			)
		)
		(property "Author" "Antmicro"
			(at 0 0 180)
			(unlocked yes)
			(layer "B.Fab")
			(hide yes)
			(effects
				(font
					(size 1 1)
					(thickness 0.15)
				)
				(justify mirror)
			)
		)
		(property "Tolerance" "~"
			(at 0 0 180)
			(unlocked yes)
			(layer "B.Fab")
			(hide yes)
			(effects
				(font
					(size 1 1)
					(thickness 0.15)
				)
				(justify mirror)
			)
		)
		(property "Current" "1A"
			(at 0 0 180)
			(unlocked yes)
			(layer "B.Fab")
			(hide yes)
			(effects
				(font
					(size 1 1)
					(thickness 0.15)
				)
				(justify mirror)
			)
		)
		(sheetname "/I^{2}C + I3C/")
		(sheetfile "i2c.kicad_sch")
		(attr smd exclude_from_bom dnp)
		(fp_rect
			(start -0.925 0.47)
			(end 0.925 -0.47)
			(stroke
				(width 0.05)
				(type default)
			)
			(fill no)
			(layer "B.CrtYd")
		)
		(fp_rect
			(start -0.5 0.25)
			(end 0.5 -0.25)
			(stroke
				(width 0.15)
				(type solid)
			)
			(fill no)
			(layer "B.Fab")
		)
		(fp_text user "Author: Antmicro"
			(at -0.95 -4.169 0)
			(layer "B.Fab")
			(effects
				(font
					(size 0.7 0.7)
					(thickness 0.15)
				)
				(justify left bottom mirror)
			)
		)
		(fp_text user "License: Apache-2.0"
			(at -0.95 -5.169 0)
			(layer "B.Fab")
			(effects
				(font
					(size 0.7 0.7)
					(thickness 0.15)
				)
				(justify left bottom mirror)
			)
		)
		(fp_text user "${REFERENCE}"
			(at -0.95 -3.168 0)
			(layer "B.Fab")
			(effects
				(font
					(size 0.7 0.7)
					(thickness 0.15)
				)
				(justify left bottom mirror)
			)
		)
		(pad "1" smd roundrect
			(at -0.48 0 180)
			(size 0.59 0.64)
			(layers "B.Cu" "B.Mask" "B.Paste")
			(roundrect_rratio 0.25)
			(net 533 "/I^{2}C + I3C/PWR.SDA")
			(pintype "passive")
		)
		(pad "2" smd roundrect
			(at 0.48 0 180)
			(size 0.59 0.64)
			(layers "B.Cu" "B.Mask" "B.Paste")
			(roundrect_rratio 0.25)
			(net 472 "/FPGA banks HD/FPGA_DDR.SDA")
			(pintype "passive")
		)
	)
	(footprint "antmicro-footprints:R_0402_1005Metric"
		(layer "B.Cu")
		(at 188.4 105.5 180)
		(descr "Resistor SMD 0402")
		(tags "resistor SMD 0402")
		(property "Reference" "R27"
			(at -3.16 0.81 0)
			(layer "B.SilkS")
			(effects
				(font
					(size 0.7 0.7)
					(thickness 0.15)
				)
				(justify left bottom mirror)
			)
		)
		(property "Value" "R_0R_0402"
			(at -1.011843 -1.772047 0)
			(layer "B.Fab")
			(effects
				(font
					(size 0.7 0.7)
					(thickness 0.15)
				)
				(justify left bottom mirror)
			)
		)
		(property "Datasheet" "https://industrial.panasonic.com/cdbs/www-data/pdf/RDA0000/AOA0000C301.pdf"
			(at 0 0 180)
			(layer "F.Fab")
			(hide yes)
			(effects
				(font
					(size 1.27 1.27)
					(thickness 0.15)
				)
			)
		)
		(property "MPN" "ERJ2GE0R00X"
			(at 0 0 180)
			(unlocked yes)
			(layer "B.Fab")
			(hide yes)
			(effects
				(font
					(size 1 1)
					(thickness 0.15)
				)
				(justify mirror)
			)
		)
		(property "Manufacturer" "Panasonic"
			(at 0 0 180)
			(unlocked yes)
			(layer "B.Fab")
			(hide yes)
			(effects
				(font
					(size 1 1)
					(thickness 0.15)
				)
				(justify mirror)
			)
		)
		(property "License" "Apache-2.0"
			(at 0 0 180)
			(unlocked yes)
			(layer "B.Fab")
			(hide yes)
			(effects
				(font
					(size 1 1)
					(thickness 0.15)
				)
				(justify mirror)
			)
		)
		(property "Author" "Antmicro"
			(at 0 0 180)
			(unlocked yes)
			(layer "B.Fab")
			(hide yes)
			(effects
				(font
					(size 1 1)
					(thickness 0.15)
				)
				(justify mirror)
			)
		)
		(property "Val" "0R"
			(at 0 0 180)
			(unlocked yes)
			(layer "B.Fab")
			(hide yes)
			(effects
				(font
					(size 1 1)
					(thickness 0.15)
				)
				(justify mirror)
			)
		)
		(property "Tolerance" "~"
			(at 0 0 180)
			(unlocked yes)
			(layer "B.Fab")
			(hide yes)
			(effects
				(font
					(size 1 1)
					(thickness 0.15)
				)
				(justify mirror)
			)
		)
		(property "Current" "1A"
			(at 0 0 180)
			(unlocked yes)
			(layer "B.Fab")
			(hide yes)
			(effects
				(font
					(size 1 1)
					(thickness 0.15)
				)
				(justify mirror)
			)
		)
		(sheetname "/DDR5 RDIMM/")
		(sheetfile "ddr5-rdimm.kicad_sch")
		(attr smd)
		(fp_rect
			(start -0.925 0.47)
			(end 0.925 -0.47)
			(stroke
				(width 0.05)
				(type default)
			)
			(fill no)
			(layer "B.CrtYd")
		)
		(fp_rect
			(start -0.5 0.25)
			(end 0.5 -0.25)
			(stroke
				(width 0.15)
				(type solid)
			)
			(fill no)
			(layer "B.Fab")
		)
		(fp_text user "${REFERENCE}"
			(at -0.95 -3.168 0)
			(layer "B.Fab")
			(effects
				(font
					(size 0.7 0.7)
					(thickness 0.15)
				)
				(justify left bottom mirror)
			)
		)
		(fp_text user "License: Apache-2.0"
			(at -0.95 -5.169 0)
			(layer "B.Fab")
			(effects
				(font
					(size 0.7 0.7)
					(thickness 0.15)
				)
				(justify left bottom mirror)
			)
		)
		(fp_text user "Author: Antmicro"
			(at -0.95 -4.169 0)
			(layer "B.Fab")
			(effects
				(font
					(size 0.7 0.7)
					(thickness 0.15)
				)
				(justify left bottom mirror)
			)
		)
		(pad "1" smd roundrect
			(at -0.48 0 180)
			(size 0.59 0.64)
			(layers "B.Cu" "B.Mask" "B.Paste")
			(roundrect_rratio 0.25)
			(net 703 "/DDR5 RDIMM/VSS_DET1")
			(pintype "passive")
		)
		(pad "2" smd roundrect
			(at 0.48 0 180)
			(size 0.59 0.64)
			(layers "B.Cu" "B.Mask" "B.Paste")
			(roundrect_rratio 0.25)
			(net 704 "~{DDR_PRESENCE}")
			(pintype "passive")
		)
	)
	(footprint "antmicro-footprints:C_0402_1005Metric"
		(layer "B.Cu")
		(at 240.55 122.22)
		(descr "Capacitor SMD 0402")
		(tags "capacitor SMD 0402")
		(property "Reference" "C321"
			(at -1.32 2.94 0)
			(layer "B.SilkS")
			(effects
				(font
					(size 0.7 0.7)
					(thickness 0.15)
				)
				(justify right bottom mirror)
			)
		)
		(property "Value" "C_100n_0402"
			(at -1.022927 -2.155213 0)
			(layer "B.Fab")
			(effects
				(font
					(size 0.7 0.7)
					(thickness 0.15)
				)
				(justify right bottom mirror)
			)
		)
		(property "Datasheet" "https://www.murata.com/products/productdetail?partno=GRM155R61H104KE14%23"
			(at 0 0 0)
			(layer "F.Fab")
			(hide yes)
			(effects
				(font
					(size 1.27 1.27)
					(thickness 0.15)
				)
			)
		)
		(property "MPN" "GRM155R61H104KE14D"
			(at 0 0 0)
			(unlocked yes)
			(layer "B.Fab")
			(hide yes)
			(effects
				(font
					(size 1 1)
					(thickness 0.15)
				)
				(justify mirror)
			)
		)
		(property "Manufacturer" "Murata"
			(at 0 0 0)
			(unlocked yes)
			(layer "B.Fab")
			(hide yes)
			(effects
				(font
					(size 1 1)
					(thickness 0.15)
				)
				(justify mirror)
			)
		)
		(property "License" "Apache-2.0"
			(at 0 0 0)
			(unlocked yes)
			(layer "B.Fab")
			(hide yes)
			(effects
				(font
					(size 1 1)
					(thickness 0.15)
				)
				(justify mirror)
			)
		)
		(property "Author" "Antmicro"
			(at 0 0 0)
			(unlocked yes)
			(layer "B.Fab")
			(hide yes)
			(effects
				(font
					(size 1 1)
					(thickness 0.15)
				)
				(justify mirror)
			)
		)
		(property "Val" "100n"
			(at 0 0 0)
			(unlocked yes)
			(layer "B.Fab")
			(hide yes)
			(effects
				(font
					(size 1 1)
					(thickness 0.15)
				)
				(justify mirror)
			)
		)
		(property "Voltage" "50V"
			(at 0 0 0)
			(unlocked yes)
			(layer "B.Fab")
			(hide yes)
			(effects
				(font
					(size 1 1)
					(thickness 0.15)
				)
				(justify mirror)
			)
		)
		(property "Dielectric" "X5R"
			(at 0 0 0)
			(unlocked yes)
			(layer "B.Fab")
			(hide yes)
			(effects
				(font
					(size 1 1)
					(thickness 0.15)
				)
				(justify mirror)
			)
		)
		(sheetname "/Supply/")
		(sheetfile "supply.kicad_sch")
		(attr smd)
		(fp_rect
			(start -0.925 0.47)
			(end 0.925 -0.47)
			(stroke
				(width 0.05)
				(type default)
			)
			(fill no)
			(layer "B.CrtYd")
		)
		(fp_line
			(start -0.494 -0.248)
			(end -0.494 0.25)
			(stroke
				(width 0.15)
				(type solid)
			)
			(layer "B.Fab")
		)
		(fp_line
			(start -0.494 0.25)
			(end 0.504 0.25)
			(stroke
				(width 0.15)
				(type solid)
			)
			(layer "B.Fab")
		)
		(fp_line
			(start 0.504 -0.248)
			(end -0.494 -0.248)
			(stroke
				(width 0.15)
				(type solid)
			)
			(layer "B.Fab")
		)
		(fp_line
			(start 0.504 0.25)
			(end 0.504 -0.248)
			(stroke
				(width 0.15)
				(type solid)
			)
			(layer "B.Fab")
		)
		(fp_text user "License: Apache-2.0"
			(at -0.939 -5.799 180)
			(layer "B.Fab")
			(effects
				(font
					(size 0.7 0.7)
					(thickness 0.15)
				)
				(justify left bottom mirror)
			)
		)
		(fp_text user "Author: Antmicro"
			(at -0.939 -3.399 180)
			(layer "B.Fab")
			(effects
				(font
					(size 0.7 0.7)
					(thickness 0.15)
				)
				(justify left bottom mirror)
			)
		)
		(fp_text user "${REFERENCE}"
			(at -0.939 -4.599 180)
			(layer "B.Fab")
			(effects
				(font
					(size 0.7 0.7)
					(thickness 0.15)
				)
				(justify left bottom mirror)
			)
		)
		(pad "1" smd roundrect
			(at -0.48 0)
			(size 0.59 0.64)
			(layers "B.Cu" "B.Mask" "B.Paste")
			(roundrect_rratio 0.25)
			(net 1 "GND")
			(pintype "passive")
		)
		(pad "2" smd roundrect
			(at 0.48 0)
			(size 0.59 0.64)
			(layers "B.Cu" "B.Mask" "B.Paste")
			(roundrect_rratio 0.25)
			(net 811 "/Supply/heater")
			(pintype "passive")
		)
	)
	(footprint "antmicro-footprints:C_0402_1005Metric_EIA"
		(layer "B.Cu")
		(at 178 159.5 -90)
		(descr "Capacitor SMD 0402 (1005 Metric), square (rectangular) end terminal, IPC_7351 nominal, (Body size source: IPC-SM-782 page 76, https://www.pcb-3d.com/wordpress/wp-content/uploads/ipc-sm-782a_amendment_1_and_2.pdf)")
		(tags "capacitor 0402")
		(property "Reference" "C311"
			(at -0.65 -1.4 90)
			(layer "B.SilkS")
			(effects
				(font
					(size 0.7 0.7)
					(thickness 0.15)
				)
				(justify left bottom mirror)
			)
		)
		(property "Value" "C_100n_0402"
			(at 0 -1.169 90)
			(layer "B.Fab")
			(effects
				(font
					(size 0.7 0.7)
					(thickness 0.15)
				)
				(justify left bottom mirror)
			)
		)
		(property "Datasheet" "https://www.murata.com/products/productdetail?partno=GRM155R61H104KE14%23"
			(at 0 0 270)
			(layer "F.Fab")
			(hide yes)
			(effects
				(font
					(size 1.27 1.27)
					(thickness 0.15)
				)
			)
		)
		(property "MPN" "GRM155R61H104KE14D"
			(at 0 0 270)
			(unlocked yes)
			(layer "B.Fab")
			(hide yes)
			(effects
				(font
					(size 1 1)
					(thickness 0.15)
				)
				(justify mirror)
			)
		)
		(property "Manufacturer" "Murata"
			(at 0 0 270)
			(unlocked yes)
			(layer "B.Fab")
			(hide yes)
			(effects
				(font
					(size 1 1)
					(thickness 0.15)
				)
				(justify mirror)
			)
		)
		(property "License" "Apache-2.0"
			(at 0 0 270)
			(unlocked yes)
			(layer "B.Fab")
			(hide yes)
			(effects
				(font
					(size 1 1)
					(thickness 0.15)
				)
				(justify mirror)
			)
		)
		(property "Author" "Antmicro"
			(at 0 0 270)
			(unlocked yes)
			(layer "B.Fab")
			(hide yes)
			(effects
				(font
					(size 1 1)
					(thickness 0.15)
				)
				(justify mirror)
			)
		)
		(property "Val" "100n"
			(at 0 0 270)
			(unlocked yes)
			(layer "B.Fab")
			(hide yes)
			(effects
				(font
					(size 1 1)
					(thickness 0.15)
				)
				(justify mirror)
			)
		)
		(property "Voltage" "50V"
			(at 0 0 270)
			(unlocked yes)
			(layer "B.Fab")
			(hide yes)
			(effects
				(font
					(size 1 1)
					(thickness 0.15)
				)
				(justify mirror)
			)
		)
		(property "Dielectric" "X5R"
			(at 0 0 270)
			(unlocked yes)
			(layer "B.Fab")
			(hide yes)
			(effects
				(font
					(size 1 1)
					(thickness 0.15)
				)
				(justify mirror)
			)
		)
		(sheetname "/FPGA power/")
		(sheetfile "fpga-power.kicad_sch")
		(attr smd)
		(fp_rect
			(start -0.95 0.45)
			(end 0.95 -0.45)
			(stroke
				(width 0.05)
				(type default)
			)
			(fill no)
			(layer "B.CrtYd")
		)
		(fp_line
			(start -0.5 0.25)
			(end 0.498 0.25)
			(stroke
				(width 0.15)
				(type solid)
			)
			(layer "B.Fab")
		)
		(fp_line
			(start 0.498 0.25)
			(end 0.498 -0.248)
			(stroke
				(width 0.15)
				(type solid)
			)
			(layer "B.Fab")
		)
		(fp_line
			(start -0.5 -0.248)
			(end -0.5 0.25)
			(stroke
				(width 0.15)
				(type solid)
			)
			(layer "B.Fab")
		)
		(fp_line
			(start 0.498 -0.248)
			(end -0.5 -0.248)
			(stroke
				(width 0.15)
				(type solid)
			)
			(layer "B.Fab")
		)
		(fp_text user "License: Apache-2.0"
			(at -0.9656 -4.369 90)
			(layer "B.Fab")
			(effects
				(font
					(size 0.7 0.7)
					(thickness 0.15)
				)
				(justify left bottom mirror)
			)
		)
		(fp_text user "${REFERENCE}"
			(at -0.9656 -3.169 90)
			(layer "B.Fab")
			(effects
				(font
					(size 0.7 0.7)
					(thickness 0.15)
				)
				(justify left bottom mirror)
			)
		)
		(fp_text user "Author: Antmicro"
			(at -0.9656 -5.569 90)
			(layer "B.Fab")
			(effects
				(font
					(size 0.7 0.7)
					(thickness 0.15)
				)
				(justify left bottom mirror)
			)
		)
		(pad "1" smd roundrect
			(at -0.5 0 180)
			(size 0.6 0.6)
			(layers "B.Cu" "B.Mask" "B.Paste")
			(roundrect_rratio 0.25)
			(net 1 "GND")
			(pintype "passive")
		)
		(pad "2" smd roundrect
			(at 0.498 0 270)
			(size 0.6 0.6)
			(layers "B.Cu" "B.Mask" "B.Paste")
			(roundrect_rratio 0.25)
			(net 172 "+1V2_MGTAVTT")
			(pintype "passive")
		)
	)
	(footprint "antmicro-footprints:C_0402_1005Metric"
		(layer "B.Cu")
		(at 160.674499 193.224 -90)
		(descr "Capacitor SMD 0402")
		(tags "capacitor SMD 0402")
		(property "Reference" "C222"
			(at -3.774 -0.435501 90)
			(layer "B.SilkS")
			(effects
				(font
					(size 0.7 0.7)
					(thickness 0.15)
				)
				(justify left bottom mirror)
			)
		)
		(property "Value" "C_10n_0402"
			(at -1.022927 -2.155213 90)
			(layer "B.Fab")
			(effects
				(font
					(size 0.7 0.7)
					(thickness 0.15)
				)
				(justify left bottom mirror)
			)
		)
		(property "Datasheet" "https://www.murata.com/products/productdetail?partno=GRM155R71H103KA88%23"
			(at 0 0 270)
			(layer "F.Fab")
			(hide yes)
			(effects
				(font
					(size 1.27 1.27)
					(thickness 0.15)
				)
			)
		)
		(property "MPN" "GRM155R71H103KA88D"
			(at 0 0 270)
			(unlocked yes)
			(layer "B.Fab")
			(hide yes)
			(effects
				(font
					(size 1 1)
					(thickness 0.15)
				)
				(justify mirror)
			)
		)
		(property "Manufacturer" "Murata"
			(at 0 0 270)
			(unlocked yes)
			(layer "B.Fab")
			(hide yes)
			(effects
				(font
					(size 1 1)
					(thickness 0.15)
				)
				(justify mirror)
			)
		)
		(property "License" "Apache-2.0"
			(at 0 0 270)
			(unlocked yes)
			(layer "B.Fab")
			(hide yes)
			(effects
				(font
					(size 1 1)
					(thickness 0.15)
				)
				(justify mirror)
			)
		)
		(property "Author" "Antmicro"
			(at 0 0 270)
			(unlocked yes)
			(layer "B.Fab")
			(hide yes)
			(effects
				(font
					(size 1 1)
					(thickness 0.15)
				)
				(justify mirror)
			)
		)
		(property "Val" "10n"
			(at 0 0 270)
			(unlocked yes)
			(layer "B.Fab")
			(hide yes)
			(effects
				(font
					(size 1 1)
					(thickness 0.15)
				)
				(justify mirror)
			)
		)
		(property "Voltage" "50V"
			(at 0 0 270)
			(unlocked yes)
			(layer "B.Fab")
			(hide yes)
			(effects
				(font
					(size 1 1)
					(thickness 0.15)
				)
				(justify mirror)
			)
		)
		(property "Dielectric" "X7R"
			(at 0 0 270)
			(unlocked yes)
			(layer "B.Fab")
			(hide yes)
			(effects
				(font
					(size 1 1)
					(thickness 0.15)
				)
				(justify mirror)
			)
		)
		(sheetname "/FPGA MGT Interface/")
		(sheetfile "fpga-mgt.kicad_sch")
		(attr smd)
		(fp_rect
			(start -0.925 0.47)
			(end 0.925 -0.47)
			(stroke
				(width 0.05)
				(type default)
			)
			(fill no)
			(layer "B.CrtYd")
		)
		(fp_line
			(start -0.494 0.25)
			(end 0.504 0.25)
			(stroke
				(width 0.15)
				(type solid)
			)
			(layer "B.Fab")
		)
		(fp_line
			(start 0.504 0.25)
			(end 0.504 -0.248)
			(stroke
				(width 0.15)
				(type solid)
			)
			(layer "B.Fab")
		)
		(fp_line
			(start -0.494 -0.248)
			(end -0.494 0.25)
			(stroke
				(width 0.15)
				(type solid)
			)
			(layer "B.Fab")
		)
		(fp_line
			(start 0.504 -0.248)
			(end -0.494 -0.248)
			(stroke
				(width 0.15)
				(type solid)
			)
			(layer "B.Fab")
		)
		(fp_text user "License: Apache-2.0"
			(at -0.939 -5.799 90)
			(layer "B.Fab")
			(effects
				(font
					(size 0.7 0.7)
					(thickness 0.15)
				)
				(justify left bottom mirror)
			)
		)
		(fp_text user "${REFERENCE}"
			(at -0.939 -4.599 90)
			(layer "B.Fab")
			(effects
				(font
					(size 0.7 0.7)
					(thickness 0.15)
				)
				(justify left bottom mirror)
			)
		)
		(fp_text user "Author: Antmicro"
			(at -0.939 -3.399 90)
			(layer "B.Fab")
			(effects
				(font
					(size 0.7 0.7)
					(thickness 0.15)
				)
				(justify left bottom mirror)
			)
		)
		(pad "1" smd roundrect
			(at -0.48 0 270)
			(size 0.59 0.64)
			(layers "B.Cu" "B.Mask" "B.Paste")
			(roundrect_rratio 0.25)
			(net 14 "/FPGA MGT Interface/GTR_REFCLK0_N")
			(pintype "passive")
		)
		(pad "2" smd roundrect
			(at 0.48 0 270)
			(size 0.59 0.64)
			(layers "B.Cu" "B.Mask" "B.Paste")
			(roundrect_rratio 0.25)
			(net 13 "/FPGA MGT Interface/PCIE.CLK_N")
			(pintype "passive")
		)
	)
	(footprint "antmicro-footprints:C_0402_1005Metric"
		(layer "B.Cu")
		(at 113.991885 127.08 90)
		(descr "Capacitor SMD 0402")
		(tags "capacitor SMD 0402")
		(property "Reference" "C137"
			(at 0.894487 0.464604 90)
			(layer "B.SilkS")
			(effects
				(font
					(size 0.7 0.7)
					(thickness 0.15)
				)
				(justify right bottom mirror)
			)
		)
		(property "Value" "C_100n_0402"
			(at -1.022927 -2.155213 90)
			(layer "B.Fab")
			(effects
				(font
					(size 0.7 0.7)
					(thickness 0.15)
				)
				(justify right bottom mirror)
			)
		)
		(property "Datasheet" "https://www.murata.com/products/productdetail?partno=GRM155R61H104KE14%23"
			(at 0 0 90)
			(layer "F.Fab")
			(hide yes)
			(effects
				(font
					(size 1.27 1.27)
					(thickness 0.15)
				)
			)
		)
		(property "MPN" "GRM155R61H104KE14D"
			(at 0 0 90)
			(unlocked yes)
			(layer "B.Fab")
			(hide yes)
			(effects
				(font
					(size 1 1)
					(thickness 0.15)
				)
				(justify mirror)
			)
		)
		(property "Manufacturer" "Murata"
			(at 0 0 90)
			(unlocked yes)
			(layer "B.Fab")
			(hide yes)
			(effects
				(font
					(size 1 1)
					(thickness 0.15)
				)
				(justify mirror)
			)
		)
		(property "License" "Apache-2.0"
			(at 0 0 90)
			(unlocked yes)
			(layer "B.Fab")
			(hide yes)
			(effects
				(font
					(size 1 1)
					(thickness 0.15)
				)
				(justify mirror)
			)
		)
		(property "Author" "Antmicro"
			(at 0 0 90)
			(unlocked yes)
			(layer "B.Fab")
			(hide yes)
			(effects
				(font
					(size 1 1)
					(thickness 0.15)
				)
				(justify mirror)
			)
		)
		(property "Val" "100n"
			(at 0 0 90)
			(unlocked yes)
			(layer "B.Fab")
			(hide yes)
			(effects
				(font
					(size 1 1)
					(thickness 0.15)
				)
				(justify mirror)
			)
		)
		(property "Voltage" "50V"
			(at 0 0 90)
			(unlocked yes)
			(layer "B.Fab")
			(hide yes)
			(effects
				(font
					(size 1 1)
					(thickness 0.15)
				)
				(justify mirror)
			)
		)
		(property "Dielectric" "X5R"
			(at 0 0 90)
			(unlocked yes)
			(layer "B.Fab")
			(hide yes)
			(effects
				(font
					(size 1 1)
					(thickness 0.15)
				)
				(justify mirror)
			)
		)
		(sheetname "/Ethernet/")
		(sheetfile "ethernet.kicad_sch")
		(attr smd)
		(fp_rect
			(start -0.925 0.47)
			(end 0.925 -0.47)
			(stroke
				(width 0.05)
				(type default)
			)
			(fill no)
			(layer "B.CrtYd")
		)
		(fp_line
			(start 0.504 -0.248)
			(end -0.494 -0.248)
			(stroke
				(width 0.15)
				(type solid)
			)
			(layer "B.Fab")
		)
		(fp_line
			(start -0.494 -0.248)
			(end -0.494 0.25)
			(stroke
				(width 0.15)
				(type solid)
			)
			(layer "B.Fab")
		)
		(fp_line
			(start 0.504 0.25)
			(end 0.504 -0.248)
			(stroke
				(width 0.15)
				(type solid)
			)
			(layer "B.Fab")
		)
		(fp_line
			(start -0.494 0.25)
			(end 0.504 0.25)
			(stroke
				(width 0.15)
				(type solid)
			)
			(layer "B.Fab")
		)
		(fp_text user "${REFERENCE}"
			(at -0.939 -4.599 270)
			(layer "B.Fab")
			(effects
				(font
					(size 0.7 0.7)
					(thickness 0.15)
				)
				(justify left bottom mirror)
			)
		)
		(fp_text user "License: Apache-2.0"
			(at -0.939 -5.799 270)
			(layer "B.Fab")
			(effects
				(font
					(size 0.7 0.7)
					(thickness 0.15)
				)
				(justify left bottom mirror)
			)
		)
		(fp_text user "Author: Antmicro"
			(at -0.939 -3.399 270)
			(layer "B.Fab")
			(effects
				(font
					(size 0.7 0.7)
					(thickness 0.15)
				)
				(justify left bottom mirror)
			)
		)
		(pad "1" smd roundrect
			(at -0.48 0 90)
			(size 0.59 0.64)
			(layers "B.Cu" "B.Mask" "B.Paste")
			(roundrect_rratio 0.25)
			(net 1 "GND")
			(pintype "passive")
		)
		(pad "2" smd roundrect
			(at 0.48 0 90)
			(size 0.59 0.64)
			(layers "B.Cu" "B.Mask" "B.Paste")
			(roundrect_rratio 0.25)
			(net 822 "Net-(C137-Pad2)")
			(pintype "passive")
		)
	)
	(footprint "antmicro-footprints:C_0402_1005Metric_EIA"
		(layer "B.Cu")
		(at 194 154.5 90)
		(descr "Capacitor SMD 0402 (1005 Metric), square (rectangular) end terminal, IPC_7351 nominal, (Body size source: IPC-SM-782 page 76, https://www.pcb-3d.com/wordpress/wp-content/uploads/ipc-sm-782a_amendment_1_and_2.pdf)")
		(tags "capacitor 0402")
		(property "Reference" "C42"
			(at 9.8 -30.65 90)
			(layer "B.SilkS")
			(effects
				(font
					(size 0.7 0.7)
					(thickness 0.15)
				)
				(justify right bottom mirror)
			)
		)
		(property "Value" "C_100n_0402"
			(at 0 -1.169 90)
			(layer "B.Fab")
			(effects
				(font
					(size 0.7 0.7)
					(thickness 0.15)
				)
				(justify right bottom mirror)
			)
		)
		(property "Datasheet" "https://www.murata.com/products/productdetail?partno=GRM155R61H104KE14%23"
			(at 0 0 90)
			(layer "F.Fab")
			(hide yes)
			(effects
				(font
					(size 1.27 1.27)
					(thickness 0.15)
				)
			)
		)
		(property "MPN" "GRM155R61H104KE14D"
			(at 0 0 90)
			(unlocked yes)
			(layer "B.Fab")
			(hide yes)
			(effects
				(font
					(size 1 1)
					(thickness 0.15)
				)
				(justify mirror)
			)
		)
		(property "Manufacturer" "Murata"
			(at 0 0 90)
			(unlocked yes)
			(layer "B.Fab")
			(hide yes)
			(effects
				(font
					(size 1 1)
					(thickness 0.15)
				)
				(justify mirror)
			)
		)
		(property "License" "Apache-2.0"
			(at 0 0 90)
			(unlocked yes)
			(layer "B.Fab")
			(hide yes)
			(effects
				(font
					(size 1 1)
					(thickness 0.15)
				)
				(justify mirror)
			)
		)
		(property "Author" "Antmicro"
			(at 0 0 90)
			(unlocked yes)
			(layer "B.Fab")
			(hide yes)
			(effects
				(font
					(size 1 1)
					(thickness 0.15)
				)
				(justify mirror)
			)
		)
		(property "Val" "100n"
			(at 0 0 90)
			(unlocked yes)
			(layer "B.Fab")
			(hide yes)
			(effects
				(font
					(size 1 1)
					(thickness 0.15)
				)
				(justify mirror)
			)
		)
		(property "Voltage" "50V"
			(at 0 0 90)
			(unlocked yes)
			(layer "B.Fab")
			(hide yes)
			(effects
				(font
					(size 1 1)
					(thickness 0.15)
				)
				(justify mirror)
			)
		)
		(property "Dielectric" "X5R"
			(at 0 0 90)
			(unlocked yes)
			(layer "B.Fab")
			(hide yes)
			(effects
				(font
					(size 1 1)
					(thickness 0.15)
				)
				(justify mirror)
			)
		)
		(sheetname "/FPGA power/")
		(sheetfile "fpga-power.kicad_sch")
		(attr smd)
		(fp_rect
			(start -0.95 0.45)
			(end 0.95 -0.45)
			(stroke
				(width 0.05)
				(type default)
			)
			(fill no)
			(layer "B.CrtYd")
		)
		(fp_line
			(start 0.498 -0.248)
			(end -0.5 -0.248)
			(stroke
				(width 0.15)
				(type solid)
			)
			(layer "B.Fab")
		)
		(fp_line
			(start -0.5 -0.248)
			(end -0.5 0.25)
			(stroke
				(width 0.15)
				(type solid)
			)
			(layer "B.Fab")
		)
		(fp_line
			(start 0.498 0.25)
			(end 0.498 -0.248)
			(stroke
				(width 0.15)
				(type solid)
			)
			(layer "B.Fab")
		)
		(fp_line
			(start -0.5 0.25)
			(end 0.498 0.25)
			(stroke
				(width 0.15)
				(type solid)
			)
			(layer "B.Fab")
		)
		(fp_text user "License: Apache-2.0"
			(at -0.9656 -4.369 270)
			(layer "B.Fab")
			(effects
				(font
					(size 0.7 0.7)
					(thickness 0.15)
				)
				(justify left bottom mirror)
			)
		)
		(fp_text user "${REFERENCE}"
			(at -0.9656 -3.169 270)
			(layer "B.Fab")
			(effects
				(font
					(size 0.7 0.7)
					(thickness 0.15)
				)
				(justify left bottom mirror)
			)
		)
		(fp_text user "Author: Antmicro"
			(at -0.9656 -5.569 270)
			(layer "B.Fab")
			(effects
				(font
					(size 0.7 0.7)
					(thickness 0.15)
				)
				(justify left bottom mirror)
			)
		)
		(pad "1" smd roundrect
			(at -0.5 0)
			(size 0.6 0.6)
			(layers "B.Cu" "B.Mask" "B.Paste")
			(roundrect_rratio 0.25)
			(net 1 "GND")
			(pintype "passive")
		)
		(pad "2" smd roundrect
			(at 0.498 0 90)
			(size 0.6 0.6)
			(layers "B.Cu" "B.Mask" "B.Paste")
			(roundrect_rratio 0.25)
			(net 553 "+0V85")
			(pintype "passive")
		)
	)
	(footprint "antmicro-footprints:C_0402_1005Metric_EIA"
		(layer "B.Cu")
		(at 186 160.5 90)
		(descr "Capacitor SMD 0402 (1005 Metric), square (rectangular) end terminal, IPC_7351 nominal, (Body size source: IPC-SM-782 page 76, https://www.pcb-3d.com/wordpress/wp-content/uploads/ipc-sm-782a_amendment_1_and_2.pdf)")
		(tags "capacitor 0402")
		(property "Reference" "C101"
			(at 8.725 -30.725 90)
			(layer "B.SilkS")
			(effects
				(font
					(size 0.7 0.7)
					(thickness 0.15)
				)
				(justify right bottom mirror)
			)
		)
		(property "Value" "C_100n_0402"
			(at 0 -1.169 90)
			(layer "B.Fab")
			(effects
				(font
					(size 0.7 0.7)
					(thickness 0.15)
				)
				(justify right bottom mirror)
			)
		)
		(property "Datasheet" "https://www.murata.com/products/productdetail?partno=GRM155R61H104KE14%23"
			(at 0 0 90)
			(layer "F.Fab")
			(hide yes)
			(effects
				(font
					(size 1.27 1.27)
					(thickness 0.15)
				)
			)
		)
		(property "MPN" "GRM155R61H104KE14D"
			(at 0 0 90)
			(unlocked yes)
			(layer "B.Fab")
			(hide yes)
			(effects
				(font
					(size 1 1)
					(thickness 0.15)
				)
				(justify mirror)
			)
		)
		(property "Manufacturer" "Murata"
			(at 0 0 90)
			(unlocked yes)
			(layer "B.Fab")
			(hide yes)
			(effects
				(font
					(size 1 1)
					(thickness 0.15)
				)
				(justify mirror)
			)
		)
		(property "License" "Apache-2.0"
			(at 0 0 90)
			(unlocked yes)
			(layer "B.Fab")
			(hide yes)
			(effects
				(font
					(size 1 1)
					(thickness 0.15)
				)
				(justify mirror)
			)
		)
		(property "Author" "Antmicro"
			(at 0 0 90)
			(unlocked yes)
			(layer "B.Fab")
			(hide yes)
			(effects
				(font
					(size 1 1)
					(thickness 0.15)
				)
				(justify mirror)
			)
		)
		(property "Val" "100n"
			(at 0 0 90)
			(unlocked yes)
			(layer "B.Fab")
			(hide yes)
			(effects
				(font
					(size 1 1)
					(thickness 0.15)
				)
				(justify mirror)
			)
		)
		(property "Voltage" "50V"
			(at 0 0 90)
			(unlocked yes)
			(layer "B.Fab")
			(hide yes)
			(effects
				(font
					(size 1 1)
					(thickness 0.15)
				)
				(justify mirror)
			)
		)
		(property "Dielectric" "X5R"
			(at 0 0 90)
			(unlocked yes)
			(layer "B.Fab")
			(hide yes)
			(effects
				(font
					(size 1 1)
					(thickness 0.15)
				)
				(justify mirror)
			)
		)
		(sheetname "/FPGA power/")
		(sheetfile "fpga-power.kicad_sch")
		(attr smd)
		(fp_rect
			(start -0.95 0.45)
			(end 0.95 -0.45)
			(stroke
				(width 0.05)
				(type default)
			)
			(fill no)
			(layer "B.CrtYd")
		)
		(fp_line
			(start 0.498 -0.248)
			(end -0.5 -0.248)
			(stroke
				(width 0.15)
				(type solid)
			)
			(layer "B.Fab")
		)
		(fp_line
			(start -0.5 -0.248)
			(end -0.5 0.25)
			(stroke
				(width 0.15)
				(type solid)
			)
			(layer "B.Fab")
		)
		(fp_line
			(start 0.498 0.25)
			(end 0.498 -0.248)
			(stroke
				(width 0.15)
				(type solid)
			)
			(layer "B.Fab")
		)
		(fp_line
			(start -0.5 0.25)
			(end 0.498 0.25)
			(stroke
				(width 0.15)
				(type solid)
			)
			(layer "B.Fab")
		)
		(fp_text user "${REFERENCE}"
			(at -0.9656 -3.169 270)
			(layer "B.Fab")
			(effects
				(font
					(size 0.7 0.7)
					(thickness 0.15)
				)
				(justify left bottom mirror)
			)
		)
		(fp_text user "License: Apache-2.0"
			(at -0.9656 -4.369 270)
			(layer "B.Fab")
			(effects
				(font
					(size 0.7 0.7)
					(thickness 0.15)
				)
				(justify left bottom mirror)
			)
		)
		(fp_text user "Author: Antmicro"
			(at -0.9656 -5.569 270)
			(layer "B.Fab")
			(effects
				(font
					(size 0.7 0.7)
					(thickness 0.15)
				)
				(justify left bottom mirror)
			)
		)
		(pad "1" smd roundrect
			(at -0.5 0)
			(size 0.6 0.6)
			(layers "B.Cu" "B.Mask" "B.Paste")
			(roundrect_rratio 0.25)
			(net 1 "GND")
			(pintype "passive")
		)
		(pad "2" smd roundrect
			(at 0.498 0 90)
			(size 0.6 0.6)
			(layers "B.Cu" "B.Mask" "B.Paste")
			(roundrect_rratio 0.25)
			(net 820 "+0V9_MGTAVCC")
			(pintype "passive")
		)
	)
	(footprint "antmicro-footprints:R_0402_1005Metric_EIA"
		(layer "B.Cu")
		(at 194 143.5 90)
		(descr "Resistor SMD 0402 (1005 Metric), square (rectangular) end terminal, IPC_7351 nominal, (Body size source: IPC-SM-782 page 76, https://www.pcb-3d.com/wordpress/wp-content/uploads/ipc-sm-782a_amendment_1_and_2.pdf)")
		(tags "resistor 0402")
		(property "Reference" "R134"
			(at -1.5 1.5 90)
			(layer "B.SilkS")
			(effects
				(font
					(size 0.7 0.7)
					(thickness 0.15)
				)
				(justify right bottom mirror)
			)
		)
		(property "Value" "R_240R_0402"
			(at 0 -1.169 90)
			(layer "B.Fab")
			(effects
				(font
					(size 0.7 0.7)
					(thickness 0.15)
				)
				(justify right bottom mirror)
			)
		)
		(property "Datasheet" "https://www.bourns.com/docs/product-datasheets/cr.pdf"
			(at 0 0 90)
			(layer "F.Fab")
			(hide yes)
			(effects
				(font
					(size 1.27 1.27)
					(thickness 0.15)
				)
			)
		)
		(property "MPN" "CR0402-FX-2400GLF"
			(at 0 0 90)
			(unlocked yes)
			(layer "B.Fab")
			(hide yes)
			(effects
				(font
					(size 1 1)
					(thickness 0.15)
				)
				(justify mirror)
			)
		)
		(property "Manufacturer" "Bourns"
			(at 0 0 90)
			(unlocked yes)
			(layer "B.Fab")
			(hide yes)
			(effects
				(font
					(size 1 1)
					(thickness 0.15)
				)
				(justify mirror)
			)
		)
		(property "License" "Apache-2.0"
			(at 0 0 90)
			(unlocked yes)
			(layer "B.Fab")
			(hide yes)
			(effects
				(font
					(size 1 1)
					(thickness 0.15)
				)
				(justify mirror)
			)
		)
		(property "Author" "Antmicro"
			(at 0 0 90)
			(unlocked yes)
			(layer "B.Fab")
			(hide yes)
			(effects
				(font
					(size 1 1)
					(thickness 0.15)
				)
				(justify mirror)
			)
		)
		(property "Val" "240R"
			(at 0 0 90)
			(unlocked yes)
			(layer "B.Fab")
			(hide yes)
			(effects
				(font
					(size 1 1)
					(thickness 0.15)
				)
				(justify mirror)
			)
		)
		(property "Tolerance" "1%"
			(at 0 0 90)
			(unlocked yes)
			(layer "B.Fab")
			(hide yes)
			(effects
				(font
					(size 1 1)
					(thickness 0.15)
				)
				(justify mirror)
			)
		)
		(sheetname "/FPGA banks HP/")
		(sheetfile "fpga-hp-banks.kicad_sch")
		(attr smd)
		(fp_rect
			(start -0.95 0.45)
			(end 0.95 -0.45)
			(stroke
				(width 0.05)
				(type default)
			)
			(fill no)
			(layer "B.CrtYd")
		)
		(fp_line
			(start 0.499 -0.249)
			(end -0.5 -0.249)
			(stroke
				(width 0.15)
				(type solid)
			)
			(layer "B.Fab")
		)
		(fp_line
			(start -0.5 -0.249)
			(end -0.5 0.25)
			(stroke
				(width 0.15)
				(type solid)
			)
			(layer "B.Fab")
		)
		(fp_line
			(start 0.499 0.25)
			(end 0.499 -0.249)
			(stroke
				(width 0.15)
				(type solid)
			)
			(layer "B.Fab")
		)
		(fp_line
			(start -0.5 0.25)
			(end 0.499 0.25)
			(stroke
				(width 0.15)
				(type solid)
			)
			(layer "B.Fab")
		)
		(fp_text user "Author: Antmicro"
			(at -0.95 -5.569 270)
			(layer "B.Fab")
			(effects
				(font
					(size 0.7 0.7)
					(thickness 0.15)
				)
				(justify left bottom mirror)
			)
		)
		(fp_text user "${REFERENCE}"
			(at -0.95 -3.169 270)
			(layer "B.Fab")
			(effects
				(font
					(size 0.7 0.7)
					(thickness 0.15)
				)
				(justify left bottom mirror)
			)
		)
		(fp_text user "License: Apache-2.0"
			(at -0.95 -4.369 270)
			(layer "B.Fab")
			(effects
				(font
					(size 0.7 0.7)
					(thickness 0.15)
				)
				(justify left bottom mirror)
			)
		)
		(pad "1" smd roundrect
			(at -0.5 0)
			(size 0.6 0.6)
			(layers "B.Cu" "B.Mask" "B.Paste")
			(roundrect_rratio 0.25)
			(net 548 "/FPGA banks HP/VRP_65")
			(pintype "passive")
		)
		(pad "2" smd roundrect
			(at 0.499 0 90)
			(size 0.6 0.6)
			(layers "B.Cu" "B.Mask" "B.Paste")
			(roundrect_rratio 0.25)
			(net 1 "GND")
			(pintype "passive")
		)
	)
	(footprint "antmicro-footprints:NetTie-2_SMD_Pad0.127mm"
		(layer "B.Cu")
		(at 205.823 151.15 180)
		(descr "Net tie, 2 pin, 0.127mm  SMD pads")
		(tags "net tie")
		(property "Reference" "TP4"
			(at -0.128 1.345 0)
			(layer "B.SilkS")
			(hide yes)
			(effects
				(font
					(size 0.7 0.7)
					(thickness 0.15)
				)
				(justify left bottom mirror)
			)
		)
		(property "Value" "Net-Tie_P0.127mm"
			(at 0 -1.199 0)
			(layer "B.Fab")
			(effects
				(font
					(size 0.7 0.7)
					(thickness 0.15)
				)
				(justify left bottom mirror)
			)
		)
		(property "MPN" ""
			(at 0 0 180)
			(unlocked yes)
			(layer "B.Fab")
			(hide yes)
			(effects
				(font
					(size 1 1)
					(thickness 0.15)
				)
				(justify mirror)
			)
		)
		(property "Manufacturer" ""
			(at 0 0 180)
			(unlocked yes)
			(layer "B.Fab")
			(hide yes)
			(effects
				(font
					(size 1 1)
					(thickness 0.15)
				)
				(justify mirror)
			)
		)
		(property "Author" "Antmicro"
			(at 0 0 180)
			(unlocked yes)
			(layer "B.Fab")
			(hide yes)
			(effects
				(font
					(size 1 1)
					(thickness 0.15)
				)
				(justify mirror)
			)
		)
		(property "License" "Apache-2.0"
			(at 0 0 180)
			(unlocked yes)
			(layer "B.Fab")
			(hide yes)
			(effects
				(font
					(size 1 1)
					(thickness 0.15)
				)
				(justify mirror)
			)
		)
		(property ki_fp_filters "Net*Tie*")
		(sheetname "/FPGA Config/")
		(sheetfile "fpga-config.kicad_sch")
		(attr through_hole exclude_from_pos_files exclude_from_bom)
		(net_tie_pad_groups "1, 2")
		(fp_poly
			(pts
				(xy -0.0635 0.0635) (xy 0.0625 0.0635) (xy 0.0625 -0.0635) (xy -0.0635 -0.0635)
			)
			(stroke
				(width 0)
				(type solid)
			)
			(fill yes)
			(layer "B.Cu")
		)
		(fp_poly
			(pts
				(xy 0.2 0.16) (xy 0.29 0.07) (xy 0.29 -0.07) (xy 0.2 -0.16) (xy -0.2 -0.16) (xy -0.29 -0.07) (xy -0.29 0.06)
				(xy -0.19 0.16)
			)
			(stroke
				(width 0.05)
				(type solid)
			)
			(fill no)
			(layer "B.CrtYd")
		)
		(fp_text user "Author: Antmicro"
			(at -0.128 -4.4 0)
			(layer "B.Fab")
			(effects
				(font
					(size 0.7 0.7)
					(thickness 0.15)
				)
				(justify left bottom mirror)
			)
		)
		(fp_text user "${REFERENCE}"
			(at -0.128 -3.2 0)
			(layer "B.Fab")
			(effects
				(font
					(size 0.7 0.7)
					(thickness 0.15)
				)
				(justify left bottom mirror)
			)
		)
		(fp_text user "License: Apache-2.0"
			(at -0.128 -5.6 0)
			(layer "B.Fab")
			(effects
				(font
					(size 0.7 0.7)
					(thickness 0.15)
				)
				(justify left bottom mirror)
			)
		)
		(pad "1" smd roundrect
			(at -0.127 0)
			(size 0.127 0.127)
			(layers "B.Cu")
			(roundrect_rratio 0.5)
			(chamfer_ratio 0)
			(chamfer top_left bottom_left)
			(net 1 "GND")
			(pinfunction "1")
			(pintype "passive")
		)
		(pad "2" smd roundrect
			(at 0.126 0 180)
			(size 0.127 0.127)
			(layers "B.Cu")
			(roundrect_rratio 0.5)
			(chamfer_ratio 0)
			(chamfer top_left bottom_left)
			(net 598 "/FPGA Config/VREFN")
			(pinfunction "2")
			(pintype "passive")
		)
	)
	(footprint "antmicro-footprints:C_0402_1005Metric"
		(layer "B.Cu")
		(at 168.65 193.299501 -90)
		(descr "Capacitor SMD 0402")
		(tags "capacitor SMD 0402")
		(property "Reference" "C233"
			(at -3.859501 -0.43 90)
			(layer "B.SilkS")
			(effects
				(font
					(size 0.7 0.7)
					(thickness 0.15)
				)
				(justify left bottom mirror)
			)
		)
		(property "Value" "C_100n_0402"
			(at -1.022927 -2.155213 90)
			(layer "B.Fab")
			(effects
				(font
					(size 0.7 0.7)
					(thickness 0.15)
				)
				(justify left bottom mirror)
			)
		)
		(property "Datasheet" "https://www.murata.com/products/productdetail?partno=GRM155R61H104KE14%23"
			(at 0 0 270)
			(layer "F.Fab")
			(hide yes)
			(effects
				(font
					(size 1.27 1.27)
					(thickness 0.15)
				)
			)
		)
		(property "Manufacturer" "Murata"
			(at 0 0 270)
			(unlocked yes)
			(layer "B.Fab")
			(hide yes)
			(effects
				(font
					(size 1 1)
					(thickness 0.15)
				)
				(justify mirror)
			)
		)
		(property "MPN" "GRM155R61H104KE14D"
			(at 0 0 270)
			(unlocked yes)
			(layer "B.Fab")
			(hide yes)
			(effects
				(font
					(size 1 1)
					(thickness 0.15)
				)
				(justify mirror)
			)
		)
		(property "Val" "100n"
			(at 0 0 270)
			(unlocked yes)
			(layer "B.Fab")
			(hide yes)
			(effects
				(font
					(size 1 1)
					(thickness 0.15)
				)
				(justify mirror)
			)
		)
		(property "License" "Apache-2.0"
			(at 0 0 270)
			(unlocked yes)
			(layer "B.Fab")
			(hide yes)
			(effects
				(font
					(size 1 1)
					(thickness 0.15)
				)
				(justify mirror)
			)
		)
		(property "Author" "Antmicro"
			(at 0 0 270)
			(unlocked yes)
			(layer "B.Fab")
			(hide yes)
			(effects
				(font
					(size 1 1)
					(thickness 0.15)
				)
				(justify mirror)
			)
		)
		(property "Voltage" "50V"
			(at 0 0 270)
			(unlocked yes)
			(layer "B.Fab")
			(hide yes)
			(effects
				(font
					(size 1 1)
					(thickness 0.15)
				)
				(justify mirror)
			)
		)
		(property "Dielectric" "X5R"
			(at 0 0 270)
			(unlocked yes)
			(layer "B.Fab")
			(hide yes)
			(effects
				(font
					(size 1 1)
					(thickness 0.15)
				)
				(justify mirror)
			)
		)
		(sheetname "/FPGA MGT Interface/")
		(sheetfile "fpga-mgt.kicad_sch")
		(attr smd)
		(fp_rect
			(start -0.925 0.47)
			(end 0.925 -0.47)
			(stroke
				(width 0.05)
				(type default)
			)
			(fill no)
			(layer "B.CrtYd")
		)
		(fp_line
			(start -0.494 0.25)
			(end 0.504 0.25)
			(stroke
				(width 0.15)
				(type solid)
			)
			(layer "B.Fab")
		)
		(fp_line
			(start 0.504 0.25)
			(end 0.504 -0.248)
			(stroke
				(width 0.15)
				(type solid)
			)
			(layer "B.Fab")
		)
		(fp_line
			(start -0.494 -0.248)
			(end -0.494 0.25)
			(stroke
				(width 0.15)
				(type solid)
			)
			(layer "B.Fab")
		)
		(fp_line
			(start 0.504 -0.248)
			(end -0.494 -0.248)
			(stroke
				(width 0.15)
				(type solid)
			)
			(layer "B.Fab")
		)
		(fp_text user "${REFERENCE}"
			(at -0.939 -4.599 90)
			(layer "B.Fab")
			(effects
				(font
					(size 0.7 0.7)
					(thickness 0.15)
				)
				(justify left bottom mirror)
			)
		)
		(fp_text user "Author: Antmicro"
			(at -0.939 -3.399 90)
			(layer "B.Fab")
			(effects
				(font
					(size 0.7 0.7)
					(thickness 0.15)
				)
				(justify left bottom mirror)
			)
		)
		(fp_text user "License: Apache-2.0"
			(at -0.939 -5.799 90)
			(layer "B.Fab")
			(effects
				(font
					(size 0.7 0.7)
					(thickness 0.15)
				)
				(justify left bottom mirror)
			)
		)
		(pad "1" smd roundrect
			(at -0.48 0 270)
			(size 0.59 0.64)
			(layers "B.Cu" "B.Mask" "B.Paste")
			(roundrect_rratio 0.25)
			(net 29 "/FPGA MGT Interface/GTY_225_TX2_N")
			(pintype "passive")
		)
		(pad "2" smd roundrect
			(at 0.48 0 270)
			(size 0.59 0.64)
			(layers "B.Cu" "B.Mask" "B.Paste")
			(roundrect_rratio 0.25)
			(net 30 "/FPGA MGT Interface/PCIE.TXD1_N")
			(pintype "passive")
		)
	)
	(footprint "antmicro-footprints:R_0402_1005Metric"
		(layer "B.Cu")
		(at 205.23 136.0045)
		(descr "Resistor SMD 0402")
		(tags "resistor SMD 0402")
		(property "Reference" "R253"
			(at -0.03 -1.0045 0)
			(layer "B.SilkS")
			(effects
				(font
					(size 0.7 0.7)
					(thickness 0.15)
				)
				(justify mirror)
			)
		)
		(property "Value" "R_1k_0402"
			(at -1.011843 -1.772047 0)
			(layer "B.Fab")
			(effects
				(font
					(size 0.7 0.7)
					(thickness 0.15)
				)
				(justify right top mirror)
			)
		)
		(property "Datasheet" "https://www.bourns.com/docs/product-datasheets/cr.pdf"
			(at 0 0 0)
			(layer "B.Fab")
			(hide yes)
			(effects
				(font
					(size 1.27 1.27)
					(thickness 0.15)
				)
				(justify mirror)
			)
		)
		(property "MPN" "CR0402-FX-1001GLF"
			(at 0 0 180)
			(unlocked yes)
			(layer "B.Fab")
			(hide yes)
			(effects
				(font
					(size 1 1)
					(thickness 0.15)
				)
				(justify mirror)
			)
		)
		(property "Manufacturer" "Bourns"
			(at 0 0 180)
			(unlocked yes)
			(layer "B.Fab")
			(hide yes)
			(effects
				(font
					(size 1 1)
					(thickness 0.15)
				)
				(justify mirror)
			)
		)
		(property "License" "Apache-2.0"
			(at 0 0 180)
			(unlocked yes)
			(layer "B.Fab")
			(hide yes)
			(effects
				(font
					(size 1 1)
					(thickness 0.15)
				)
				(justify mirror)
			)
		)
		(property "Author" "Antmicro"
			(at 0 0 180)
			(unlocked yes)
			(layer "B.Fab")
			(hide yes)
			(effects
				(font
					(size 1 1)
					(thickness 0.15)
				)
				(justify mirror)
			)
		)
		(property "Val" "1k"
			(at 0 0 180)
			(unlocked yes)
			(layer "B.Fab")
			(hide yes)
			(effects
				(font
					(size 1 1)
					(thickness 0.15)
				)
				(justify mirror)
			)
		)
		(property "Tolerance" "1%"
			(at 0 0 180)
			(unlocked yes)
			(layer "B.Fab")
			(hide yes)
			(effects
				(font
					(size 1 1)
					(thickness 0.15)
				)
				(justify mirror)
			)
		)
		(sheetname "/FPGA banks HP/")
		(sheetfile "fpga-hp-banks.kicad_sch")
		(attr smd)
		(fp_rect
			(start -0.925 0.47)
			(end 0.925 -0.47)
			(stroke
				(width 0.05)
				(type default)
			)
			(fill no)
			(layer "B.CrtYd")
		)
		(fp_rect
			(start -0.5 0.25)
			(end 0.5 -0.25)
			(stroke
				(width 0.15)
				(type solid)
			)
			(fill no)
			(layer "B.Fab")
		)
		(fp_text user "License: Apache-2.0"
			(at -0.95 -5.169 0)
			(layer "B.Fab")
			(effects
				(font
					(size 0.7 0.7)
					(thickness 0.15)
				)
				(justify right top mirror)
			)
		)
		(fp_text user "Author: Antmicro"
			(at -0.95 -4.169 0)
			(layer "B.Fab")
			(effects
				(font
					(size 0.7 0.7)
					(thickness 0.15)
				)
				(justify right top mirror)
			)
		)
		(fp_text user "${REFERENCE}"
			(at -0.95 -3.168 0)
			(layer "B.Fab")
			(effects
				(font
					(size 0.7 0.7)
					(thickness 0.15)
				)
				(justify right top mirror)
			)
		)
		(pad "1" smd roundrect
			(at -0.48 0)
			(size 0.59 0.64)
			(layers "B.Cu" "B.Mask" "B.Paste")
			(roundrect_rratio 0.25)
			(net 827 "Net-(R253-Pad1)")
			(pintype "passive")
		)
		(pad "2" smd roundrect
			(at 0.48 0)
			(size 0.59 0.64)
			(layers "B.Cu" "B.Mask" "B.Paste")
			(roundrect_rratio 0.25)
			(net 687 "VDDQ")
			(pintype "passive")
		)
	)
	(footprint "antmicro-footprints:C_0402_1005Metric"
		(layer "B.Cu")
		(at 162.65 193.299501 90)
		(descr "Capacitor SMD 0402")
		(tags "capacitor SMD 0402")
		(property "Reference" "C229"
			(at 0.994 0.403501 90)
			(layer "B.SilkS")
			(effects
				(font
					(size 0.7 0.7)
					(thickness 0.15)
				)
				(justify right bottom mirror)
			)
		)
		(property "Value" "C_100n_0402"
			(at -1.022927 -2.155213 90)
			(layer "B.Fab")
			(effects
				(font
					(size 0.7 0.7)
					(thickness 0.15)
				)
				(justify right bottom mirror)
			)
		)
		(property "Datasheet" "https://www.murata.com/products/productdetail?partno=GRM155R61H104KE14%23"
			(at 0 0 90)
			(layer "F.Fab")
			(hide yes)
			(effects
				(font
					(size 1.27 1.27)
					(thickness 0.15)
				)
			)
		)
		(property "Manufacturer" "Murata"
			(at 0 0 90)
			(unlocked yes)
			(layer "B.Fab")
			(hide yes)
			(effects
				(font
					(size 1 1)
					(thickness 0.15)
				)
				(justify mirror)
			)
		)
		(property "MPN" "GRM155R61H104KE14D"
			(at 0 0 90)
			(unlocked yes)
			(layer "B.Fab")
			(hide yes)
			(effects
				(font
					(size 1 1)
					(thickness 0.15)
				)
				(justify mirror)
			)
		)
		(property "Val" "100n"
			(at 0 0 90)
			(unlocked yes)
			(layer "B.Fab")
			(hide yes)
			(effects
				(font
					(size 1 1)
					(thickness 0.15)
				)
				(justify mirror)
			)
		)
		(property "License" "Apache-2.0"
			(at 0 0 90)
			(unlocked yes)
			(layer "B.Fab")
			(hide yes)
			(effects
				(font
					(size 1 1)
					(thickness 0.15)
				)
				(justify mirror)
			)
		)
		(property "Author" "Antmicro"
			(at 0 0 90)
			(unlocked yes)
			(layer "B.Fab")
			(hide yes)
			(effects
				(font
					(size 1 1)
					(thickness 0.15)
				)
				(justify mirror)
			)
		)
		(property "Voltage" "50V"
			(at 0 0 90)
			(unlocked yes)
			(layer "B.Fab")
			(hide yes)
			(effects
				(font
					(size 1 1)
					(thickness 0.15)
				)
				(justify mirror)
			)
		)
		(property "Dielectric" "X5R"
			(at 0 0 90)
			(unlocked yes)
			(layer "B.Fab")
			(hide yes)
			(effects
				(font
					(size 1 1)
					(thickness 0.15)
				)
				(justify mirror)
			)
		)
		(sheetname "/FPGA MGT Interface/")
		(sheetfile "fpga-mgt.kicad_sch")
		(attr smd)
		(fp_rect
			(start -0.925 0.47)
			(end 0.925 -0.47)
			(stroke
				(width 0.05)
				(type default)
			)
			(fill no)
			(layer "B.CrtYd")
		)
		(fp_line
			(start 0.504 -0.248)
			(end -0.494 -0.248)
			(stroke
				(width 0.15)
				(type solid)
			)
			(layer "B.Fab")
		)
		(fp_line
			(start -0.494 -0.248)
			(end -0.494 0.25)
			(stroke
				(width 0.15)
				(type solid)
			)
			(layer "B.Fab")
		)
		(fp_line
			(start 0.504 0.25)
			(end 0.504 -0.248)
			(stroke
				(width 0.15)
				(type solid)
			)
			(layer "B.Fab")
		)
		(fp_line
			(start -0.494 0.25)
			(end 0.504 0.25)
			(stroke
				(width 0.15)
				(type solid)
			)
			(layer "B.Fab")
		)
		(fp_text user "Author: Antmicro"
			(at -0.939 -3.399 270)
			(layer "B.Fab")
			(effects
				(font
					(size 0.7 0.7)
					(thickness 0.15)
				)
				(justify left bottom mirror)
			)
		)
		(fp_text user "License: Apache-2.0"
			(at -0.939 -5.799 270)
			(layer "B.Fab")
			(effects
				(font
					(size 0.7 0.7)
					(thickness 0.15)
				)
				(justify left bottom mirror)
			)
		)
		(fp_text user "${REFERENCE}"
			(at -0.939 -4.599 270)
			(layer "B.Fab")
			(effects
				(font
					(size 0.7 0.7)
					(thickness 0.15)
				)
				(justify left bottom mirror)
			)
		)
		(pad "1" smd roundrect
			(at -0.48 0 90)
			(size 0.59 0.64)
			(layers "B.Cu" "B.Mask" "B.Paste")
			(roundrect_rratio 0.25)
			(net 21 "/FPGA MGT Interface/PCIE.TXD0_P")
			(pintype "passive")
		)
		(pad "2" smd roundrect
			(at 0.48 0 90)
			(size 0.59 0.64)
			(layers "B.Cu" "B.Mask" "B.Paste")
			(roundrect_rratio 0.25)
			(net 22 "/FPGA MGT Interface/GTY_225_TX3_P")
			(pintype "passive")
		)
	)
	(footprint "antmicro-footprints:R_0402_1005Metric"
		(layer "B.Cu")
		(at 132.63 174.35 -90)
		(descr "Resistor SMD 0402")
		(tags "resistor SMD 0402")
		(property "Reference" "R234"
			(at -3.8 -0.47 90)
			(layer "B.SilkS")
			(effects
				(font
					(size 0.7 0.7)
					(thickness 0.15)
				)
				(justify left bottom mirror)
			)
		)
		(property "Value" "R_2k2_0402"
			(at -1.011843 -1.772047 90)
			(layer "B.Fab")
			(effects
				(font
					(size 0.7 0.7)
					(thickness 0.15)
				)
				(justify left bottom mirror)
			)
		)
		(property "Datasheet" "https://www.bourns.com/docs/product-datasheets/cr.pdf"
			(at 0 0 270)
			(layer "F.Fab")
			(hide yes)
			(effects
				(font
					(size 1.27 1.27)
					(thickness 0.15)
				)
			)
		)
		(property "MPN" "CR0402-FX-2201GLF"
			(at 0 0 270)
			(unlocked yes)
			(layer "B.Fab")
			(hide yes)
			(effects
				(font
					(size 1 1)
					(thickness 0.15)
				)
				(justify mirror)
			)
		)
		(property "Manufacturer" "Bourns"
			(at 0 0 270)
			(unlocked yes)
			(layer "B.Fab")
			(hide yes)
			(effects
				(font
					(size 1 1)
					(thickness 0.15)
				)
				(justify mirror)
			)
		)
		(property "License" "Apache-2.0"
			(at 0 0 270)
			(unlocked yes)
			(layer "B.Fab")
			(hide yes)
			(effects
				(font
					(size 1 1)
					(thickness 0.15)
				)
				(justify mirror)
			)
		)
		(property "Author" "Antmicro"
			(at 0 0 270)
			(unlocked yes)
			(layer "B.Fab")
			(hide yes)
			(effects
				(font
					(size 1 1)
					(thickness 0.15)
				)
				(justify mirror)
			)
		)
		(property "Val" "2k2"
			(at 0 0 270)
			(unlocked yes)
			(layer "B.Fab")
			(hide yes)
			(effects
				(font
					(size 1 1)
					(thickness 0.15)
				)
				(justify mirror)
			)
		)
		(property "Tolerance" "1%"
			(at 0 0 270)
			(unlocked yes)
			(layer "B.Fab")
			(hide yes)
			(effects
				(font
					(size 1 1)
					(thickness 0.15)
				)
				(justify mirror)
			)
		)
		(property "Public" ""
			(at 0 0 270)
			(unlocked yes)
			(layer "B.Fab")
			(hide yes)
			(effects
				(font
					(size 1 1)
					(thickness 0.15)
				)
				(justify mirror)
			)
		)
		(sheetname "/HDMI + SD Card/")
		(sheetfile "hdmi-sd-card.kicad_sch")
		(attr smd)
		(fp_rect
			(start -0.925 0.47)
			(end 0.925 -0.47)
			(stroke
				(width 0.05)
				(type default)
			)
			(fill no)
			(layer "B.CrtYd")
		)
		(fp_rect
			(start -0.5 0.25)
			(end 0.5 -0.25)
			(stroke
				(width 0.15)
				(type solid)
			)
			(fill no)
			(layer "B.Fab")
		)
		(fp_text user "License: Apache-2.0"
			(at -0.95 -5.169 90)
			(layer "B.Fab")
			(effects
				(font
					(size 0.7 0.7)
					(thickness 0.15)
				)
				(justify left bottom mirror)
			)
		)
		(fp_text user "Author: Antmicro"
			(at -0.95 -4.169 90)
			(layer "B.Fab")
			(effects
				(font
					(size 0.7 0.7)
					(thickness 0.15)
				)
				(justify left bottom mirror)
			)
		)
		(fp_text user "${REFERENCE}"
			(at -0.95 -3.168 90)
			(layer "B.Fab")
			(effects
				(font
					(size 0.7 0.7)
					(thickness 0.15)
				)
				(justify left bottom mirror)
			)
		)
		(pad "1" smd roundrect
			(at -0.48 0 270)
			(size 0.59 0.64)
			(layers "B.Cu" "B.Mask" "B.Paste")
			(roundrect_rratio 0.25)
			(net 769 "/FPGA MGT Interface/HDMI_CTL.SDA")
			(pintype "passive")
		)
		(pad "2" smd roundrect
			(at 0.48 0 270)
			(size 0.59 0.64)
			(layers "B.Cu" "B.Mask" "B.Paste")
			(roundrect_rratio 0.25)
			(net 151 "+3V3")
			(pintype "passive")
		)
	)
	(footprint "antmicro-footprints:C_0402_1005Metric"
		(layer "B.Cu")
		(at 115.413499 118.149)
		(descr "Capacitor SMD 0402")
		(tags "capacitor SMD 0402")
		(property "Reference" "C234"
			(at 1.286501 0.151 0)
			(layer "B.SilkS")
			(effects
				(font
					(size 0.7 0.7)
					(thickness 0.15)
				)
				(justify right bottom mirror)
			)
		)
		(property "Value" "C_100n_0402"
			(at -1.022927 -2.155213 0)
			(layer "B.Fab")
			(effects
				(font
					(size 0.7 0.7)
					(thickness 0.15)
				)
				(justify right bottom mirror)
			)
		)
		(property "Datasheet" "https://www.murata.com/products/productdetail?partno=GRM155R61H104KE14%23"
			(at 0 0 0)
			(layer "F.Fab")
			(hide yes)
			(effects
				(font
					(size 1.27 1.27)
					(thickness 0.15)
				)
			)
		)
		(property "Manufacturer" "Murata"
			(at 0 0 0)
			(unlocked yes)
			(layer "B.Fab")
			(hide yes)
			(effects
				(font
					(size 1 1)
					(thickness 0.15)
				)
				(justify mirror)
			)
		)
		(property "MPN" "GRM155R61H104KE14D"
			(at 0 0 0)
			(unlocked yes)
			(layer "B.Fab")
			(hide yes)
			(effects
				(font
					(size 1 1)
					(thickness 0.15)
				)
				(justify mirror)
			)
		)
		(property "Val" "100n"
			(at 0 0 0)
			(unlocked yes)
			(layer "B.Fab")
			(hide yes)
			(effects
				(font
					(size 1 1)
					(thickness 0.15)
				)
				(justify mirror)
			)
		)
		(property "License" "Apache-2.0"
			(at 0 0 0)
			(unlocked yes)
			(layer "B.Fab")
			(hide yes)
			(effects
				(font
					(size 1 1)
					(thickness 0.15)
				)
				(justify mirror)
			)
		)
		(property "Author" "Antmicro"
			(at 0 0 0)
			(unlocked yes)
			(layer "B.Fab")
			(hide yes)
			(effects
				(font
					(size 1 1)
					(thickness 0.15)
				)
				(justify mirror)
			)
		)
		(property "Voltage" "50V"
			(at 0 0 0)
			(unlocked yes)
			(layer "B.Fab")
			(hide yes)
			(effects
				(font
					(size 1 1)
					(thickness 0.15)
				)
				(justify mirror)
			)
		)
		(property "Dielectric" "X5R"
			(at 0 0 0)
			(unlocked yes)
			(layer "B.Fab")
			(hide yes)
			(effects
				(font
					(size 1 1)
					(thickness 0.15)
				)
				(justify mirror)
			)
		)
		(sheetname "/Ethernet/")
		(sheetfile "ethernet.kicad_sch")
		(attr smd)
		(fp_rect
			(start -0.925 0.47)
			(end 0.925 -0.47)
			(stroke
				(width 0.05)
				(type default)
			)
			(fill no)
			(layer "B.CrtYd")
		)
		(fp_line
			(start -0.494 -0.248)
			(end -0.494 0.25)
			(stroke
				(width 0.15)
				(type solid)
			)
			(layer "B.Fab")
		)
		(fp_line
			(start -0.494 0.25)
			(end 0.504 0.25)
			(stroke
				(width 0.15)
				(type solid)
			)
			(layer "B.Fab")
		)
		(fp_line
			(start 0.504 -0.248)
			(end -0.494 -0.248)
			(stroke
				(width 0.15)
				(type solid)
			)
			(layer "B.Fab")
		)
		(fp_line
			(start 0.504 0.25)
			(end 0.504 -0.248)
			(stroke
				(width 0.15)
				(type solid)
			)
			(layer "B.Fab")
		)
		(fp_text user "License: Apache-2.0"
			(at -0.939 -5.799 180)
			(layer "B.Fab")
			(effects
				(font
					(size 0.7 0.7)
					(thickness 0.15)
				)
				(justify left bottom mirror)
			)
		)
		(fp_text user "${REFERENCE}"
			(at -0.939 -4.599 180)
			(layer "B.Fab")
			(effects
				(font
					(size 0.7 0.7)
					(thickness 0.15)
				)
				(justify left bottom mirror)
			)
		)
		(fp_text user "Author: Antmicro"
			(at -0.939 -3.399 180)
			(layer "B.Fab")
			(effects
				(font
					(size 0.7 0.7)
					(thickness 0.15)
				)
				(justify left bottom mirror)
			)
		)
		(pad "1" smd roundrect
			(at -0.48 0)
			(size 0.59 0.64)
			(layers "B.Cu" "B.Mask" "B.Paste")
			(roundrect_rratio 0.25)
			(net 31 "Net-(C234-Pad1)")
			(pintype "passive")
		)
		(pad "2" smd roundrect
			(at 0.48 0)
			(size 0.59 0.64)
			(layers "B.Cu" "B.Mask" "B.Paste")
			(roundrect_rratio 0.25)
			(net 1 "GND")
			(pintype "passive")
		)
	)
	(footprint "antmicro-footprints:C_0603_1608Metric"
		(layer "B.Cu")
		(at 180.1 152.525)
		(descr "Capacitor SMD 0603")
		(tags "capacitor 0603")
		(property "Reference" "C22"
			(at -0.975 1.925 0)
			(layer "B.SilkS")
			(effects
				(font
					(size 0.7 0.7)
					(thickness 0.15)
				)
				(justify right bottom mirror)
			)
		)
		(property "Value" "C_47u_0603"
			(at -1.42757 -1.770288 0)
			(layer "B.Fab")
			(effects
				(font
					(size 0.7 0.7)
					(thickness 0.15)
				)
				(justify right bottom mirror)
			)
		)
		(property "Datasheet" "https://www.murata.com/products/productdetail?partno=GRM188R60J476ME15%23"
			(at 0 0 0)
			(layer "F.Fab")
			(hide yes)
			(effects
				(font
					(size 1.27 1.27)
					(thickness 0.15)
				)
			)
		)
		(property "Manufacturer" "Murata"
			(at 0 0 0)
			(unlocked yes)
			(layer "B.Fab")
			(hide yes)
			(effects
				(font
					(size 1 1)
					(thickness 0.15)
				)
				(justify mirror)
			)
		)
		(property "MPN" "GRM188R60J476ME15D"
			(at 0 0 0)
			(unlocked yes)
			(layer "B.Fab")
			(hide yes)
			(effects
				(font
					(size 1 1)
					(thickness 0.15)
				)
				(justify mirror)
			)
		)
		(property "Val" "47u"
			(at 0 0 0)
			(unlocked yes)
			(layer "B.Fab")
			(hide yes)
			(effects
				(font
					(size 1 1)
					(thickness 0.15)
				)
				(justify mirror)
			)
		)
		(property "License" "Apache-2.0"
			(at 0 0 0)
			(unlocked yes)
			(layer "B.Fab")
			(hide yes)
			(effects
				(font
					(size 1 1)
					(thickness 0.15)
				)
				(justify mirror)
			)
		)
		(property "Author" "Antmicro"
			(at 0 0 0)
			(unlocked yes)
			(layer "B.Fab")
			(hide yes)
			(effects
				(font
					(size 1 1)
					(thickness 0.15)
				)
				(justify mirror)
			)
		)
		(property "Voltage" ""
			(at 0 0 0)
			(unlocked yes)
			(layer "B.Fab")
			(hide yes)
			(effects
				(font
					(size 1 1)
					(thickness 0.15)
				)
				(justify mirror)
			)
		)
		(property "Dielectric" ""
			(at 0 0 0)
			(unlocked yes)
			(layer "B.Fab")
			(hide yes)
			(effects
				(font
					(size 1 1)
					(thickness 0.15)
				)
				(justify mirror)
			)
		)
		(sheetname "/FPGA power/")
		(sheetfile "fpga-power.kicad_sch")
		(attr smd)
		(fp_line
			(start -0.15 -0.4)
			(end 0.15 -0.4)
			(stroke
				(width 0.15)
				(type solid)
			)
			(layer "B.SilkS")
		)
		(fp_line
			(start -0.15 0.4)
			(end 0.15 0.4)
			(stroke
				(width 0.15)
				(type solid)
			)
			(layer "B.SilkS")
		)
		(fp_rect
			(start -1.25 0.65)
			(end 1.25 -0.65)
			(stroke
				(width 0.05)
				(type solid)
			)
			(fill no)
			(layer "B.CrtYd")
		)
		(fp_rect
			(start -0.8 0.4)
			(end 0.8 -0.4)
			(stroke
				(width 0.15)
				(type solid)
			)
			(fill no)
			(layer "B.Fab")
		)
		(fp_text user "Author: Antmicro"
			(at -1.682 -4.894 180)
			(layer "B.Fab")
			(effects
				(font
					(size 0.7 0.7)
					(thickness 0.15)
				)
				(justify left bottom mirror)
			)
		)
		(fp_text user "License: Apache-2.0"
			(at -1.682 -5.895 180)
			(layer "B.Fab")
			(effects
				(font
					(size 0.7 0.7)
					(thickness 0.15)
				)
				(justify left bottom mirror)
			)
		)
		(fp_text user "${REFERENCE}"
			(at -1.682 -3.895 180)
			(layer "B.Fab")
			(effects
				(font
					(size 0.7 0.7)
					(thickness 0.15)
				)
				(justify left bottom mirror)
			)
		)
		(pad "1" smd roundrect
			(at -0.7 0)
			(size 0.8 1)
			(layers "B.Cu" "B.Mask" "B.Paste")
			(roundrect_rratio 0.2)
			(net 151 "+3V3")
			(pintype "passive")
		)
		(pad "2" smd roundrect
			(at 0.7 0)
			(size 0.8 1)
			(layers "B.Cu" "B.Mask" "B.Paste")
			(roundrect_rratio 0.2)
			(net 1 "GND")
			(pintype "passive")
		)
	)
	(footprint "antmicro-footprints:R_0402_1005Metric"
		(layer "B.Cu")
		(at 238.451999 163.175)
		(descr "Resistor SMD 0402")
		(tags "resistor SMD 0402")
		(property "Reference" "R138"
			(at 1.173001 0.475 0)
			(layer "B.SilkS")
			(effects
				(font
					(size 0.7 0.7)
					(thickness 0.15)
				)
				(justify right bottom mirror)
			)
		)
		(property "Value" "R_0R_0402"
			(at -1.011843 -1.772047 0)
			(layer "B.Fab")
			(effects
				(font
					(size 0.7 0.7)
					(thickness 0.15)
				)
				(justify right bottom mirror)
			)
		)
		(property "Datasheet" "https://industrial.panasonic.com/cdbs/www-data/pdf/RDA0000/AOA0000C301.pdf"
			(at 0 0 0)
			(layer "F.Fab")
			(hide yes)
			(effects
				(font
					(size 1.27 1.27)
					(thickness 0.15)
				)
			)
		)
		(property "MPN" "ERJ2GE0R00X"
			(at 0 0 0)
			(unlocked yes)
			(layer "B.Fab")
			(hide yes)
			(effects
				(font
					(size 1 1)
					(thickness 0.15)
				)
				(justify mirror)
			)
		)
		(property "Manufacturer" "Panasonic"
			(at 0 0 0)
			(unlocked yes)
			(layer "B.Fab")
			(hide yes)
			(effects
				(font
					(size 1 1)
					(thickness 0.15)
				)
				(justify mirror)
			)
		)
		(property "License" "Apache-2.0"
			(at 0 0 0)
			(unlocked yes)
			(layer "B.Fab")
			(hide yes)
			(effects
				(font
					(size 1 1)
					(thickness 0.15)
				)
				(justify mirror)
			)
		)
		(property "Author" "Antmicro"
			(at 0 0 0)
			(unlocked yes)
			(layer "B.Fab")
			(hide yes)
			(effects
				(font
					(size 1 1)
					(thickness 0.15)
				)
				(justify mirror)
			)
		)
		(property "Val" "0R"
			(at 0 0 0)
			(unlocked yes)
			(layer "B.Fab")
			(hide yes)
			(effects
				(font
					(size 1 1)
					(thickness 0.15)
				)
				(justify mirror)
			)
		)
		(property "Tolerance" "~"
			(at 0 0 0)
			(unlocked yes)
			(layer "B.Fab")
			(hide yes)
			(effects
				(font
					(size 1 1)
					(thickness 0.15)
				)
				(justify mirror)
			)
		)
		(property "Current" "1A"
			(at 0 0 0)
			(unlocked yes)
			(layer "B.Fab")
			(hide yes)
			(effects
				(font
					(size 1 1)
					(thickness 0.15)
				)
				(justify mirror)
			)
		)
		(sheetname "/Supply/")
		(sheetfile "supply.kicad_sch")
		(attr smd)
		(fp_rect
			(start -0.925 0.47)
			(end 0.925 -0.47)
			(stroke
				(width 0.05)
				(type default)
			)
			(fill no)
			(layer "B.CrtYd")
		)
		(fp_rect
			(start -0.5 0.25)
			(end 0.5 -0.25)
			(stroke
				(width 0.15)
				(type solid)
			)
			(fill no)
			(layer "B.Fab")
		)
		(fp_text user "License: Apache-2.0"
			(at -0.95 -5.169 180)
			(layer "B.Fab")
			(effects
				(font
					(size 0.7 0.7)
					(thickness 0.15)
				)
				(justify left bottom mirror)
			)
		)
		(fp_text user "${REFERENCE}"
			(at -0.95 -3.168 180)
			(layer "B.Fab")
			(effects
				(font
					(size 0.7 0.7)
					(thickness 0.15)
				)
				(justify left bottom mirror)
			)
		)
		(fp_text user "Author: Antmicro"
			(at -0.95 -4.169 180)
			(layer "B.Fab")
			(effects
				(font
					(size 0.7 0.7)
					(thickness 0.15)
				)
				(justify left bottom mirror)
			)
		)
		(pad "1" smd roundrect
			(at -0.48 0)
			(size 0.59 0.64)
			(layers "B.Cu" "B.Mask" "B.Paste")
			(roundrect_rratio 0.25)
			(net 183 "POWER")
			(pintype "passive")
		)
		(pad "2" smd roundrect
			(at 0.48 0)
			(size 0.59 0.64)
			(layers "B.Cu" "B.Mask" "B.Paste")
			(roundrect_rratio 0.25)
			(net 485 "PG3")
			(pintype "passive")
		)
	)
	(footprint "antmicro-footprints:C_0402_1005Metric_EIA"
		(layer "B.Cu")
		(at 184 150.5 90)
		(descr "Capacitor SMD 0402 (1005 Metric), square (rectangular) end terminal, IPC_7351 nominal, (Body size source: IPC-SM-782 page 76, https://www.pcb-3d.com/wordpress/wp-content/uploads/ipc-sm-782a_amendment_1_and_2.pdf)")
		(tags "capacitor 0402")
		(property "Reference" "C13"
			(at 9.325 -30.625 90)
			(layer "B.SilkS")
			(effects
				(font
					(size 0.7 0.7)
					(thickness 0.15)
				)
				(justify right bottom mirror)
			)
		)
		(property "Value" "C_100n_0402"
			(at 0 -1.169 90)
			(layer "B.Fab")
			(effects
				(font
					(size 0.7 0.7)
					(thickness 0.15)
				)
				(justify right bottom mirror)
			)
		)
		(property "Datasheet" "https://www.murata.com/products/productdetail?partno=GRM155R61H104KE14%23"
			(at 0 0 90)
			(layer "F.Fab")
			(hide yes)
			(effects
				(font
					(size 1.27 1.27)
					(thickness 0.15)
				)
			)
		)
		(property "MPN" "GRM155R61H104KE14D"
			(at 0 0 90)
			(unlocked yes)
			(layer "B.Fab")
			(hide yes)
			(effects
				(font
					(size 1 1)
					(thickness 0.15)
				)
				(justify mirror)
			)
		)
		(property "Manufacturer" "Murata"
			(at 0 0 90)
			(unlocked yes)
			(layer "B.Fab")
			(hide yes)
			(effects
				(font
					(size 1 1)
					(thickness 0.15)
				)
				(justify mirror)
			)
		)
		(property "License" "Apache-2.0"
			(at 0 0 90)
			(unlocked yes)
			(layer "B.Fab")
			(hide yes)
			(effects
				(font
					(size 1 1)
					(thickness 0.15)
				)
				(justify mirror)
			)
		)
		(property "Author" "Antmicro"
			(at 0 0 90)
			(unlocked yes)
			(layer "B.Fab")
			(hide yes)
			(effects
				(font
					(size 1 1)
					(thickness 0.15)
				)
				(justify mirror)
			)
		)
		(property "Val" "100n"
			(at 0 0 90)
			(unlocked yes)
			(layer "B.Fab")
			(hide yes)
			(effects
				(font
					(size 1 1)
					(thickness 0.15)
				)
				(justify mirror)
			)
		)
		(property "Voltage" "50V"
			(at 0 0 90)
			(unlocked yes)
			(layer "B.Fab")
			(hide yes)
			(effects
				(font
					(size 1 1)
					(thickness 0.15)
				)
				(justify mirror)
			)
		)
		(property "Dielectric" "X5R"
			(at 0 0 90)
			(unlocked yes)
			(layer "B.Fab")
			(hide yes)
			(effects
				(font
					(size 1 1)
					(thickness 0.15)
				)
				(justify mirror)
			)
		)
		(sheetname "/FPGA power/")
		(sheetfile "fpga-power.kicad_sch")
		(attr smd)
		(fp_rect
			(start -0.95 0.45)
			(end 0.95 -0.45)
			(stroke
				(width 0.05)
				(type default)
			)
			(fill no)
			(layer "B.CrtYd")
		)
		(fp_line
			(start 0.498 -0.248)
			(end -0.5 -0.248)
			(stroke
				(width 0.15)
				(type solid)
			)
			(layer "B.Fab")
		)
		(fp_line
			(start -0.5 -0.248)
			(end -0.5 0.25)
			(stroke
				(width 0.15)
				(type solid)
			)
			(layer "B.Fab")
		)
		(fp_line
			(start 0.498 0.25)
			(end 0.498 -0.248)
			(stroke
				(width 0.15)
				(type solid)
			)
			(layer "B.Fab")
		)
		(fp_line
			(start -0.5 0.25)
			(end 0.498 0.25)
			(stroke
				(width 0.15)
				(type solid)
			)
			(layer "B.Fab")
		)
		(fp_text user "${REFERENCE}"
			(at -0.9656 -3.169 270)
			(layer "B.Fab")
			(effects
				(font
					(size 0.7 0.7)
					(thickness 0.15)
				)
				(justify left bottom mirror)
			)
		)
		(fp_text user "Author: Antmicro"
			(at -0.9656 -5.569 270)
			(layer "B.Fab")
			(effects
				(font
					(size 0.7 0.7)
					(thickness 0.15)
				)
				(justify left bottom mirror)
			)
		)
		(fp_text user "License: Apache-2.0"
			(at -0.9656 -4.369 270)
			(layer "B.Fab")
			(effects
				(font
					(size 0.7 0.7)
					(thickness 0.15)
				)
				(justify left bottom mirror)
			)
		)
		(pad "1" smd roundrect
			(at -0.5 0)
			(size 0.6 0.6)
			(layers "B.Cu" "B.Mask" "B.Paste")
			(roundrect_rratio 0.25)
			(net 1 "GND")
			(pintype "passive")
		)
		(pad "2" smd roundrect
			(at 0.498 0 90)
			(size 0.6 0.6)
			(layers "B.Cu" "B.Mask" "B.Paste")
			(roundrect_rratio 0.25)
			(net 553 "+0V85")
			(pintype "passive")
		)
	)
	(footprint "antmicro-footprints:R_0402_1005Metric"
		(layer "B.Cu")
		(at 252.924499 132.199 90)
		(descr "Resistor SMD 0402")
		(tags "resistor SMD 0402")
		(property "Reference" "R160"
			(at 1.329 -0.264499 90)
			(layer "B.SilkS")
			(effects
				(font
					(size 0.7 0.7)
					(thickness 0.15)
				)
				(justify right bottom mirror)
			)
		)
		(property "Value" "R_47k_0402"
			(at -1.011843 -1.772047 90)
			(layer "B.Fab")
			(effects
				(font
					(size 0.7 0.7)
					(thickness 0.15)
				)
				(justify right bottom mirror)
			)
		)
		(property "Datasheet" "https://www.bourns.com/docs/product-datasheets/cr.pdf"
			(at 0 0 90)
			(layer "F.Fab")
			(hide yes)
			(effects
				(font
					(size 1.27 1.27)
					(thickness 0.15)
				)
			)
		)
		(property "Manufacturer" "Bourns"
			(at 0 0 90)
			(unlocked yes)
			(layer "B.Fab")
			(hide yes)
			(effects
				(font
					(size 1 1)
					(thickness 0.15)
				)
				(justify mirror)
			)
		)
		(property "MPN" "CR0402-FX-4702GLF"
			(at 0 0 90)
			(unlocked yes)
			(layer "B.Fab")
			(hide yes)
			(effects
				(font
					(size 1 1)
					(thickness 0.15)
				)
				(justify mirror)
			)
		)
		(property "Val" "47k"
			(at 0 0 90)
			(unlocked yes)
			(layer "B.Fab")
			(hide yes)
			(effects
				(font
					(size 1 1)
					(thickness 0.15)
				)
				(justify mirror)
			)
		)
		(property "License" "Apache-2.0"
			(at 0 0 90)
			(unlocked yes)
			(layer "B.Fab")
			(hide yes)
			(effects
				(font
					(size 1 1)
					(thickness 0.15)
				)
				(justify mirror)
			)
		)
		(property "Author" "Antmicro"
			(at 0 0 90)
			(unlocked yes)
			(layer "B.Fab")
			(hide yes)
			(effects
				(font
					(size 1 1)
					(thickness 0.15)
				)
				(justify mirror)
			)
		)
		(property "Tolerance" "1%"
			(at 0 0 90)
			(unlocked yes)
			(layer "B.Fab")
			(hide yes)
			(effects
				(font
					(size 1 1)
					(thickness 0.15)
				)
				(justify mirror)
			)
		)
		(sheetname "/Supply/")
		(sheetfile "supply.kicad_sch")
		(attr smd)
		(fp_rect
			(start -0.925 0.47)
			(end 0.925 -0.47)
			(stroke
				(width 0.05)
				(type default)
			)
			(fill no)
			(layer "B.CrtYd")
		)
		(fp_rect
			(start -0.5 0.25)
			(end 0.5 -0.25)
			(stroke
				(width 0.15)
				(type solid)
			)
			(fill no)
			(layer "B.Fab")
		)
		(fp_text user "${REFERENCE}"
			(at -0.95 -3.168 270)
			(layer "B.Fab")
			(effects
				(font
					(size 0.7 0.7)
					(thickness 0.15)
				)
				(justify left bottom mirror)
			)
		)
		(fp_text user "License: Apache-2.0"
			(at -0.95 -5.169 270)
			(layer "B.Fab")
			(effects
				(font
					(size 0.7 0.7)
					(thickness 0.15)
				)
				(justify left bottom mirror)
			)
		)
		(fp_text user "Author: Antmicro"
			(at -0.95 -4.169 270)
			(layer "B.Fab")
			(effects
				(font
					(size 0.7 0.7)
					(thickness 0.15)
				)
				(justify left bottom mirror)
			)
		)
		(pad "1" smd roundrect
			(at -0.48 0 90)
			(size 0.59 0.64)
			(layers "B.Cu" "B.Mask" "B.Paste")
			(roundrect_rratio 0.25)
			(net 157 "/Supply/~{PB_CTRL_INT}")
			(pintype "passive")
		)
		(pad "2" smd roundrect
			(at 0.48 0 90)
			(size 0.59 0.64)
			(layers "B.Cu" "B.Mask" "B.Paste")
			(roundrect_rratio 0.25)
			(net 138 "/Supply/PB_CTRL_OUT")
			(pintype "passive")
		)
	)
	(footprint "antmicro-footprints:R_0402_1005Metric"
		(layer "B.Cu")
		(at 242.97 134.755 90)
		(descr "Resistor SMD 0402")
		(tags "resistor SMD 0402")
		(property "Reference" "R123"
			(at -3.805 0.33 90)
			(layer "B.SilkS")
			(effects
				(font
					(size 0.7 0.7)
					(thickness 0.15)
				)
				(justify right bottom mirror)
			)
		)
		(property "Value" "R_4k7_0402"
			(at -1.011843 -1.772047 90)
			(layer "B.Fab")
			(effects
				(font
					(size 0.7 0.7)
					(thickness 0.15)
				)
				(justify right bottom mirror)
			)
		)
		(property "Datasheet" "https://www.bourns.com/docs/product-datasheets/cr.pdf"
			(at 0 0 90)
			(layer "F.Fab")
			(hide yes)
			(effects
				(font
					(size 1.27 1.27)
					(thickness 0.15)
				)
			)
		)
		(property "Manufacturer" "Bourns"
			(at 0 0 90)
			(unlocked yes)
			(layer "B.Fab")
			(hide yes)
			(effects
				(font
					(size 1 1)
					(thickness 0.15)
				)
				(justify mirror)
			)
		)
		(property "MPN" "CR0402-FX-4701GLF"
			(at 0 0 90)
			(unlocked yes)
			(layer "B.Fab")
			(hide yes)
			(effects
				(font
					(size 1 1)
					(thickness 0.15)
				)
				(justify mirror)
			)
		)
		(property "Val" "4k7"
			(at 0 0 90)
			(unlocked yes)
			(layer "B.Fab")
			(hide yes)
			(effects
				(font
					(size 1 1)
					(thickness 0.15)
				)
				(justify mirror)
			)
		)
		(property "License" "Apache-2.0"
			(at 0 0 90)
			(unlocked yes)
			(layer "B.Fab")
			(hide yes)
			(effects
				(font
					(size 1 1)
					(thickness 0.15)
				)
				(justify mirror)
			)
		)
		(property "Author" "Antmicro"
			(at 0 0 90)
			(unlocked yes)
			(layer "B.Fab")
			(hide yes)
			(effects
				(font
					(size 1 1)
					(thickness 0.15)
				)
				(justify mirror)
			)
		)
		(property "Tolerance" "1%"
			(at 0 0 90)
			(unlocked yes)
			(layer "B.Fab")
			(hide yes)
			(effects
				(font
					(size 1 1)
					(thickness 0.15)
				)
				(justify mirror)
			)
		)
		(sheetname "/I^{2}C + I3C/")
		(sheetfile "i2c.kicad_sch")
		(attr smd)
		(fp_rect
			(start -0.925 0.47)
			(end 0.925 -0.47)
			(stroke
				(width 0.05)
				(type default)
			)
			(fill no)
			(layer "B.CrtYd")
		)
		(fp_rect
			(start -0.5 0.25)
			(end 0.5 -0.25)
			(stroke
				(width 0.15)
				(type solid)
			)
			(fill no)
			(layer "B.Fab")
		)
		(fp_text user "Author: Antmicro"
			(at -0.95 -4.169 270)
			(layer "B.Fab")
			(effects
				(font
					(size 0.7 0.7)
					(thickness 0.15)
				)
				(justify left bottom mirror)
			)
		)
		(fp_text user "${REFERENCE}"
			(at -0.95 -3.168 270)
			(layer "B.Fab")
			(effects
				(font
					(size 0.7 0.7)
					(thickness 0.15)
				)
				(justify left bottom mirror)
			)
		)
		(fp_text user "License: Apache-2.0"
			(at -0.95 -5.169 270)
			(layer "B.Fab")
			(effects
				(font
					(size 0.7 0.7)
					(thickness 0.15)
				)
				(justify left bottom mirror)
			)
		)
		(pad "1" smd roundrect
			(at -0.48 0 90)
			(size 0.59 0.64)
			(layers "B.Cu" "B.Mask" "B.Paste")
			(roundrect_rratio 0.25)
			(net 151 "+3V3")
			(pintype "passive")
		)
		(pad "2" smd roundrect
			(at 0.48 0 90)
			(size 0.59 0.64)
			(layers "B.Cu" "B.Mask" "B.Paste")
			(roundrect_rratio 0.25)
			(net 472 "/FPGA banks HD/FPGA_DDR.SDA")
			(pintype "passive")
		)
	)
	(footprint "antmicro-footprints:C_0603_1608Metric"
		(layer "B.Cu")
		(at 202.4 149.5 90)
		(descr "Capacitor SMD 0603")
		(tags "capacitor 0603")
		(property "Reference" "C94"
			(at -0.9 1.8 90)
			(layer "B.SilkS")
			(effects
				(font
					(size 0.7 0.7)
					(thickness 0.15)
				)
				(justify right bottom mirror)
			)
		)
		(property "Value" "C_47u_0603"
			(at -1.42757 -1.770288 90)
			(layer "B.Fab")
			(effects
				(font
					(size 0.7 0.7)
					(thickness 0.15)
				)
				(justify right bottom mirror)
			)
		)
		(property "Datasheet" "https://www.murata.com/products/productdetail?partno=GRM188R60J476ME15%23"
			(at 0 0 90)
			(layer "F.Fab")
			(hide yes)
			(effects
				(font
					(size 1.27 1.27)
					(thickness 0.15)
				)
			)
		)
		(property "Manufacturer" "Murata"
			(at 0 0 90)
			(unlocked yes)
			(layer "B.Fab")
			(hide yes)
			(effects
				(font
					(size 1 1)
					(thickness 0.15)
				)
				(justify mirror)
			)
		)
		(property "MPN" "GRM188R60J476ME15D"
			(at 0 0 90)
			(unlocked yes)
			(layer "B.Fab")
			(hide yes)
			(effects
				(font
					(size 1 1)
					(thickness 0.15)
				)
				(justify mirror)
			)
		)
		(property "Val" "47u"
			(at 0 0 90)
			(unlocked yes)
			(layer "B.Fab")
			(hide yes)
			(effects
				(font
					(size 1 1)
					(thickness 0.15)
				)
				(justify mirror)
			)
		)
		(property "License" "Apache-2.0"
			(at 0 0 90)
			(unlocked yes)
			(layer "B.Fab")
			(hide yes)
			(effects
				(font
					(size 1 1)
					(thickness 0.15)
				)
				(justify mirror)
			)
		)
		(property "Author" "Antmicro"
			(at 0 0 90)
			(unlocked yes)
			(layer "B.Fab")
			(hide yes)
			(effects
				(font
					(size 1 1)
					(thickness 0.15)
				)
				(justify mirror)
			)
		)
		(property "Voltage" ""
			(at 0 0 90)
			(unlocked yes)
			(layer "B.Fab")
			(hide yes)
			(effects
				(font
					(size 1 1)
					(thickness 0.15)
				)
				(justify mirror)
			)
		)
		(property "Dielectric" ""
			(at 0 0 90)
			(unlocked yes)
			(layer "B.Fab")
			(hide yes)
			(effects
				(font
					(size 1 1)
					(thickness 0.15)
				)
				(justify mirror)
			)
		)
		(sheetname "/FPGA power/")
		(sheetfile "fpga-power.kicad_sch")
		(attr smd)
		(fp_line
			(start -0.15 -0.4)
			(end 0.15 -0.4)
			(stroke
				(width 0.15)
				(type solid)
			)
			(layer "B.SilkS")
		)
		(fp_line
			(start -0.15 0.4)
			(end 0.15 0.4)
			(stroke
				(width 0.15)
				(type solid)
			)
			(layer "B.SilkS")
		)
		(fp_rect
			(start -1.25 0.65)
			(end 1.25 -0.65)
			(stroke
				(width 0.05)
				(type solid)
			)
			(fill no)
			(layer "B.CrtYd")
		)
		(fp_rect
			(start -0.8 0.4)
			(end 0.8 -0.4)
			(stroke
				(width 0.15)
				(type solid)
			)
			(fill no)
			(layer "B.Fab")
		)
		(fp_text user "License: Apache-2.0"
			(at -1.682 -5.895 270)
			(layer "B.Fab")
			(effects
				(font
					(size 0.7 0.7)
					(thickness 0.15)
				)
				(justify left bottom mirror)
			)
		)
		(fp_text user "Author: Antmicro"
			(at -1.682 -4.894 270)
			(layer "B.Fab")
			(effects
				(font
					(size 0.7 0.7)
					(thickness 0.15)
				)
				(justify left bottom mirror)
			)
		)
		(fp_text user "${REFERENCE}"
			(at -1.682 -3.895 270)
			(layer "B.Fab")
			(effects
				(font
					(size 0.7 0.7)
					(thickness 0.15)
				)
				(justify left bottom mirror)
			)
		)
		(pad "1" smd roundrect
			(at -0.7 0 90)
			(size 0.8 1)
			(layers "B.Cu" "B.Mask" "B.Paste")
			(roundrect_rratio 0.2)
			(net 151 "+3V3")
			(pintype "passive")
		)
		(pad "2" smd roundrect
			(at 0.7 0 90)
			(size 0.8 1)
			(layers "B.Cu" "B.Mask" "B.Paste")
			(roundrect_rratio 0.2)
			(net 1 "GND")
			(pintype "passive")
		)
	)
	(footprint "antmicro-footprints:C_0402_1005Metric_EIA"
		(layer "B.Cu")
		(at 179 142.5 90)
		(descr "Capacitor SMD 0402 (1005 Metric), square (rectangular) end terminal, IPC_7351 nominal, (Body size source: IPC-SM-782 page 76, https://www.pcb-3d.com/wordpress/wp-content/uploads/ipc-sm-782a_amendment_1_and_2.pdf)")
		(tags "capacitor 0402")
		(property "Reference" "C71"
			(at -1.15 1.4 90)
			(layer "B.SilkS")
			(effects
				(font
					(size 0.7 0.7)
					(thickness 0.15)
				)
				(justify right bottom mirror)
			)
		)
		(property "Value" "C_10u_10V_0402"
			(at 0 -1.169 90)
			(layer "B.Fab")
			(effects
				(font
					(size 0.7 0.7)
					(thickness 0.15)
				)
				(justify right bottom mirror)
			)
		)
		(property "Datasheet" "https://www.murata.com/products/productdetail?partno=GRM155R61A106ME11%23"
			(at 0 0 90)
			(layer "F.Fab")
			(hide yes)
			(effects
				(font
					(size 1.27 1.27)
					(thickness 0.15)
				)
			)
		)
		(property "MPN" "GRM155R61A106ME11D"
			(at 0 0 90)
			(unlocked yes)
			(layer "B.Fab")
			(hide yes)
			(effects
				(font
					(size 1 1)
					(thickness 0.15)
				)
				(justify mirror)
			)
		)
		(property "Manufacturer" "Murata"
			(at 0 0 90)
			(unlocked yes)
			(layer "B.Fab")
			(hide yes)
			(effects
				(font
					(size 1 1)
					(thickness 0.15)
				)
				(justify mirror)
			)
		)
		(property "License" "Apache-2.0"
			(at 0 0 90)
			(unlocked yes)
			(layer "B.Fab")
			(hide yes)
			(effects
				(font
					(size 1 1)
					(thickness 0.15)
				)
				(justify mirror)
			)
		)
		(property "Author" "Antmicro"
			(at 0 0 90)
			(unlocked yes)
			(layer "B.Fab")
			(hide yes)
			(effects
				(font
					(size 1 1)
					(thickness 0.15)
				)
				(justify mirror)
			)
		)
		(property "Val" "10u"
			(at 0 0 90)
			(unlocked yes)
			(layer "B.Fab")
			(hide yes)
			(effects
				(font
					(size 1 1)
					(thickness 0.15)
				)
				(justify mirror)
			)
		)
		(property "Voltage" "10V"
			(at 0 0 90)
			(unlocked yes)
			(layer "B.Fab")
			(hide yes)
			(effects
				(font
					(size 1 1)
					(thickness 0.15)
				)
				(justify mirror)
			)
		)
		(property "Dielectric" "X5R"
			(at 0 0 90)
			(unlocked yes)
			(layer "B.Fab")
			(hide yes)
			(effects
				(font
					(size 1 1)
					(thickness 0.15)
				)
				(justify mirror)
			)
		)
		(sheetname "/FPGA power/")
		(sheetfile "fpga-power.kicad_sch")
		(attr smd)
		(fp_rect
			(start -0.95 0.45)
			(end 0.95 -0.45)
			(stroke
				(width 0.05)
				(type default)
			)
			(fill no)
			(layer "B.CrtYd")
		)
		(fp_line
			(start 0.498 -0.248)
			(end -0.5 -0.248)
			(stroke
				(width 0.15)
				(type solid)
			)
			(layer "B.Fab")
		)
		(fp_line
			(start -0.5 -0.248)
			(end -0.5 0.25)
			(stroke
				(width 0.15)
				(type solid)
			)
			(layer "B.Fab")
		)
		(fp_line
			(start 0.498 0.25)
			(end 0.498 -0.248)
			(stroke
				(width 0.15)
				(type solid)
			)
			(layer "B.Fab")
		)
		(fp_line
			(start -0.5 0.25)
			(end 0.498 0.25)
			(stroke
				(width 0.15)
				(type solid)
			)
			(layer "B.Fab")
		)
		(fp_text user "License: Apache-2.0"
			(at -0.9656 -4.369 270)
			(layer "B.Fab")
			(effects
				(font
					(size 0.7 0.7)
					(thickness 0.15)
				)
				(justify left bottom mirror)
			)
		)
		(fp_text user "${REFERENCE}"
			(at -0.9656 -3.169 270)
			(layer "B.Fab")
			(effects
				(font
					(size 0.7 0.7)
					(thickness 0.15)
				)
				(justify left bottom mirror)
			)
		)
		(fp_text user "Author: Antmicro"
			(at -0.9656 -5.569 270)
			(layer "B.Fab")
			(effects
				(font
					(size 0.7 0.7)
					(thickness 0.15)
				)
				(justify left bottom mirror)
			)
		)
		(pad "1" smd roundrect
			(at -0.5 0)
			(size 0.6 0.6)
			(layers "B.Cu" "B.Mask" "B.Paste")
			(roundrect_rratio 0.25)
			(net 1 "GND")
			(pintype "passive")
		)
		(pad "2" smd roundrect
			(at 0.498 0 90)
			(size 0.6 0.6)
			(layers "B.Cu" "B.Mask" "B.Paste")
			(roundrect_rratio 0.25)
			(net 687 "VDDQ")
			(pintype "passive")
		)
	)
	(footprint "antmicro-footprints:C_0603_1608Metric"
		(layer "B.Cu")
		(at 240.55 120.765)
		(descr "Capacitor SMD 0603")
		(tags "capacitor 0603")
		(property "Reference" "C323"
			(at -1.25 2.915 0)
			(layer "B.SilkS")
			(effects
				(font
					(size 0.7 0.7)
					(thickness 0.15)
				)
				(justify right bottom mirror)
			)
		)
		(property "Value" "C_10u_25V_0603"
			(at -1.42757 -1.770288 0)
			(layer "B.Fab")
			(effects
				(font
					(size 0.7 0.7)
					(thickness 0.15)
				)
				(justify right bottom mirror)
			)
		)
		(property "Datasheet" "https://product.tdk.com/en/search/capacitor/ceramic/mlcc/info?part_no=C1608X5R1E106M080AC"
			(at 0 0 0)
			(layer "F.Fab")
			(hide yes)
			(effects
				(font
					(size 1.27 1.27)
					(thickness 0.15)
				)
			)
		)
		(property "MPN" "C1608X5R1E106M080AC"
			(at 0 0 0)
			(unlocked yes)
			(layer "B.Fab")
			(hide yes)
			(effects
				(font
					(size 1 1)
					(thickness 0.15)
				)
				(justify mirror)
			)
		)
		(property "Manufacturer" "TDK"
			(at 0 0 0)
			(unlocked yes)
			(layer "B.Fab")
			(hide yes)
			(effects
				(font
					(size 1 1)
					(thickness 0.15)
				)
				(justify mirror)
			)
		)
		(property "License" "Apache-2.0"
			(at 0 0 0)
			(unlocked yes)
			(layer "B.Fab")
			(hide yes)
			(effects
				(font
					(size 1 1)
					(thickness 0.15)
				)
				(justify mirror)
			)
		)
		(property "Author" "Antmicro"
			(at 0 0 0)
			(unlocked yes)
			(layer "B.Fab")
			(hide yes)
			(effects
				(font
					(size 1 1)
					(thickness 0.15)
				)
				(justify mirror)
			)
		)
		(property "Val" "10u"
			(at 0 0 0)
			(unlocked yes)
			(layer "B.Fab")
			(hide yes)
			(effects
				(font
					(size 1 1)
					(thickness 0.15)
				)
				(justify mirror)
			)
		)
		(property "Voltage" "25V"
			(at 0 0 0)
			(unlocked yes)
			(layer "B.Fab")
			(hide yes)
			(effects
				(font
					(size 1 1)
					(thickness 0.15)
				)
				(justify mirror)
			)
		)
		(property "Dielectric" ""
			(at 0 0 0)
			(unlocked yes)
			(layer "B.Fab")
			(hide yes)
			(effects
				(font
					(size 1 1)
					(thickness 0.15)
				)
				(justify mirror)
			)
		)
		(sheetname "/Supply/")
		(sheetfile "supply.kicad_sch")
		(attr smd)
		(fp_line
			(start -0.15 -0.4)
			(end 0.15 -0.4)
			(stroke
				(width 0.15)
				(type solid)
			)
			(layer "B.SilkS")
		)
		(fp_line
			(start -0.15 0.4)
			(end 0.15 0.4)
			(stroke
				(width 0.15)
				(type solid)
			)
			(layer "B.SilkS")
		)
		(fp_rect
			(start -1.25 0.65)
			(end 1.25 -0.65)
			(stroke
				(width 0.05)
				(type solid)
			)
			(fill no)
			(layer "B.CrtYd")
		)
		(fp_rect
			(start -0.8 0.4)
			(end 0.8 -0.4)
			(stroke
				(width 0.15)
				(type solid)
			)
			(fill no)
			(layer "B.Fab")
		)
		(fp_text user "${REFERENCE}"
			(at -1.682 -3.895 180)
			(layer "B.Fab")
			(effects
				(font
					(size 0.7 0.7)
					(thickness 0.15)
				)
				(justify left bottom mirror)
			)
		)
		(fp_text user "Author: Antmicro"
			(at -1.682 -4.894 180)
			(layer "B.Fab")
			(effects
				(font
					(size 0.7 0.7)
					(thickness 0.15)
				)
				(justify left bottom mirror)
			)
		)
		(fp_text user "License: Apache-2.0"
			(at -1.682 -5.895 180)
			(layer "B.Fab")
			(effects
				(font
					(size 0.7 0.7)
					(thickness 0.15)
				)
				(justify left bottom mirror)
			)
		)
		(pad "1" smd roundrect
			(at -0.7 0)
			(size 0.8 1)
			(layers "B.Cu" "B.Mask" "B.Paste")
			(roundrect_rratio 0.2)
			(net 1 "GND")
			(pintype "passive")
		)
		(pad "2" smd roundrect
			(at 0.7 0)
			(size 0.8 1)
			(layers "B.Cu" "B.Mask" "B.Paste")
			(roundrect_rratio 0.2)
			(net 811 "/Supply/heater")
			(pintype "passive")
		)
	)
	(footprint "antmicro-footprints:R_0402_1005Metric"
		(layer "B.Cu")
		(at 254.199499 135.749)
		(descr "Resistor SMD 0402")
		(tags "resistor SMD 0402")
		(property "Reference" "R172"
			(at 1.250501 0.451 0)
			(layer "B.SilkS")
			(effects
				(font
					(size 0.7 0.7)
					(thickness 0.15)
				)
				(justify right bottom mirror)
			)
		)
		(property "Value" "R_47k_0402"
			(at -1.011843 -1.772047 0)
			(layer "B.Fab")
			(effects
				(font
					(size 0.7 0.7)
					(thickness 0.15)
				)
				(justify right bottom mirror)
			)
		)
		(property "Datasheet" "https://www.bourns.com/docs/product-datasheets/cr.pdf"
			(at 0 0 0)
			(layer "F.Fab")
			(hide yes)
			(effects
				(font
					(size 1.27 1.27)
					(thickness 0.15)
				)
			)
		)
		(property "Manufacturer" "Bourns"
			(at 0 0 0)
			(unlocked yes)
			(layer "B.Fab")
			(hide yes)
			(effects
				(font
					(size 1 1)
					(thickness 0.15)
				)
				(justify mirror)
			)
		)
		(property "MPN" "CR0402-FX-4702GLF"
			(at 0 0 0)
			(unlocked yes)
			(layer "B.Fab")
			(hide yes)
			(effects
				(font
					(size 1 1)
					(thickness 0.15)
				)
				(justify mirror)
			)
		)
		(property "Val" "47k"
			(at 0 0 0)
			(unlocked yes)
			(layer "B.Fab")
			(hide yes)
			(effects
				(font
					(size 1 1)
					(thickness 0.15)
				)
				(justify mirror)
			)
		)
		(property "License" "Apache-2.0"
			(at 0 0 0)
			(unlocked yes)
			(layer "B.Fab")
			(hide yes)
			(effects
				(font
					(size 1 1)
					(thickness 0.15)
				)
				(justify mirror)
			)
		)
		(property "Author" "Antmicro"
			(at 0 0 0)
			(unlocked yes)
			(layer "B.Fab")
			(hide yes)
			(effects
				(font
					(size 1 1)
					(thickness 0.15)
				)
				(justify mirror)
			)
		)
		(property "Tolerance" "1%"
			(at 0 0 0)
			(unlocked yes)
			(layer "B.Fab")
			(hide yes)
			(effects
				(font
					(size 1 1)
					(thickness 0.15)
				)
				(justify mirror)
			)
		)
		(sheetname "/Supply/")
		(sheetfile "supply.kicad_sch")
		(attr smd)
		(fp_rect
			(start -0.925 0.47)
			(end 0.925 -0.47)
			(stroke
				(width 0.05)
				(type default)
			)
			(fill no)
			(layer "B.CrtYd")
		)
		(fp_rect
			(start -0.5 0.25)
			(end 0.5 -0.25)
			(stroke
				(width 0.15)
				(type solid)
			)
			(fill no)
			(layer "B.Fab")
		)
		(fp_text user "License: Apache-2.0"
			(at -0.95 -5.169 180)
			(layer "B.Fab")
			(effects
				(font
					(size 0.7 0.7)
					(thickness 0.15)
				)
				(justify left bottom mirror)
			)
		)
		(fp_text user "Author: Antmicro"
			(at -0.95 -4.169 180)
			(layer "B.Fab")
			(effects
				(font
					(size 0.7 0.7)
					(thickness 0.15)
				)
				(justify left bottom mirror)
			)
		)
		(fp_text user "${REFERENCE}"
			(at -0.95 -3.168 180)
			(layer "B.Fab")
			(effects
				(font
					(size 0.7 0.7)
					(thickness 0.15)
				)
				(justify left bottom mirror)
			)
		)
		(pad "1" smd roundrect
			(at -0.48 0)
			(size 0.59 0.64)
			(layers "B.Cu" "B.Mask" "B.Paste")
			(roundrect_rratio 0.25)
			(net 286 "Net-(Q16-D)")
			(pintype "passive")
		)
		(pad "2" smd roundrect
			(at 0.48 0)
			(size 0.59 0.64)
			(layers "B.Cu" "B.Mask" "B.Paste")
			(roundrect_rratio 0.25)
			(net 38 "+3V3_AON")
			(pintype "passive")
		)
	)
	(footprint "antmicro-footprints:R_0402_1005Metric"
		(layer "B.Cu")
		(at 254.05 122.225)
		(descr "Resistor SMD 0402")
		(tags "resistor SMD 0402")
		(property "Reference" "R245"
			(at -1.4 1.625 0)
			(layer "B.SilkS")
			(effects
				(font
					(size 0.7 0.7)
					(thickness 0.15)
				)
				(justify right bottom mirror)
			)
		)
		(property "Value" "R_47k_0402"
			(at -1.011843 -1.772047 0)
			(layer "B.Fab")
			(effects
				(font
					(size 0.7 0.7)
					(thickness 0.15)
				)
				(justify right bottom mirror)
			)
		)
		(property "Datasheet" "https://www.bourns.com/docs/product-datasheets/cr.pdf"
			(at 0 0 0)
			(layer "F.Fab")
			(hide yes)
			(effects
				(font
					(size 1.27 1.27)
					(thickness 0.15)
				)
			)
		)
		(property "MPN" "CR0402-FX-4702GLF"
			(at 0 0 0)
			(unlocked yes)
			(layer "B.Fab")
			(hide yes)
			(effects
				(font
					(size 1 1)
					(thickness 0.15)
				)
				(justify mirror)
			)
		)
		(property "Manufacturer" "Bourns"
			(at 0 0 0)
			(unlocked yes)
			(layer "B.Fab")
			(hide yes)
			(effects
				(font
					(size 1 1)
					(thickness 0.15)
				)
				(justify mirror)
			)
		)
		(property "License" "Apache-2.0"
			(at 0 0 0)
			(unlocked yes)
			(layer "B.Fab")
			(hide yes)
			(effects
				(font
					(size 1 1)
					(thickness 0.15)
				)
				(justify mirror)
			)
		)
		(property "Author" "Antmicro"
			(at 0 0 0)
			(unlocked yes)
			(layer "B.Fab")
			(hide yes)
			(effects
				(font
					(size 1 1)
					(thickness 0.15)
				)
				(justify mirror)
			)
		)
		(property "Val" "47k"
			(at 0 0 0)
			(unlocked yes)
			(layer "B.Fab")
			(hide yes)
			(effects
				(font
					(size 1 1)
					(thickness 0.15)
				)
				(justify mirror)
			)
		)
		(property "Tolerance" "1%"
			(at 0 0 0)
			(unlocked yes)
			(layer "B.Fab")
			(hide yes)
			(effects
				(font
					(size 1 1)
					(thickness 0.15)
				)
				(justify mirror)
			)
		)
		(sheetname "/DDR5 RDIMM/")
		(sheetfile "ddr5-rdimm.kicad_sch")
		(attr smd)
		(fp_rect
			(start -0.925 0.47)
			(end 0.925 -0.47)
			(stroke
				(width 0.05)
				(type default)
			)
			(fill no)
			(layer "B.CrtYd")
		)
		(fp_rect
			(start -0.5 0.25)
			(end 0.5 -0.25)
			(stroke
				(width 0.15)
				(type solid)
			)
			(fill no)
			(layer "B.Fab")
		)
		(fp_text user "${REFERENCE}"
			(at -0.95 -3.168 180)
			(layer "B.Fab")
			(effects
				(font
					(size 0.7 0.7)
					(thickness 0.15)
				)
				(justify left bottom mirror)
			)
		)
		(fp_text user "License: Apache-2.0"
			(at -0.95 -5.169 180)
			(layer "B.Fab")
			(effects
				(font
					(size 0.7 0.7)
					(thickness 0.15)
				)
				(justify left bottom mirror)
			)
		)
		(fp_text user "Author: Antmicro"
			(at -0.95 -4.169 180)
			(layer "B.Fab")
			(effects
				(font
					(size 0.7 0.7)
					(thickness 0.15)
				)
				(justify left bottom mirror)
			)
		)
		(pad "1" smd roundrect
			(at -0.48 0)
			(size 0.59 0.64)
			(layers "B.Cu" "B.Mask" "B.Paste")
			(roundrect_rratio 0.25)
			(net 1 "GND")
			(pintype "passive")
		)
		(pad "2" smd roundrect
			(at 0.48 0)
			(size 0.59 0.64)
			(layers "B.Cu" "B.Mask" "B.Paste")
			(roundrect_rratio 0.25)
			(net 809 "VIN_MGMT_EN")
			(pintype "passive")
		)
	)
	(footprint "antmicro-footprints:C_0402_1005Metric_EIA"
		(layer "B.Cu")
		(at 187 160.5 90)
		(descr "Capacitor SMD 0402 (1005 Metric), square (rectangular) end terminal, IPC_7351 nominal, (Body size source: IPC-SM-782 page 76, https://www.pcb-3d.com/wordpress/wp-content/uploads/ipc-sm-782a_amendment_1_and_2.pdf)")
		(tags "capacitor 0402")
		(property "Reference" "C100"
			(at 8.725 -30.675 90)
			(layer "B.SilkS")
			(effects
				(font
					(size 0.7 0.7)
					(thickness 0.15)
				)
				(justify right bottom mirror)
			)
		)
		(property "Value" "C_100n_0402"
			(at 0 -1.169 90)
			(layer "B.Fab")
			(effects
				(font
					(size 0.7 0.7)
					(thickness 0.15)
				)
				(justify right bottom mirror)
			)
		)
		(property "Datasheet" "https://www.murata.com/products/productdetail?partno=GRM155R61H104KE14%23"
			(at 0 0 90)
			(layer "F.Fab")
			(hide yes)
			(effects
				(font
					(size 1.27 1.27)
					(thickness 0.15)
				)
			)
		)
		(property "MPN" "GRM155R61H104KE14D"
			(at 0 0 90)
			(unlocked yes)
			(layer "B.Fab")
			(hide yes)
			(effects
				(font
					(size 1 1)
					(thickness 0.15)
				)
				(justify mirror)
			)
		)
		(property "Manufacturer" "Murata"
			(at 0 0 90)
			(unlocked yes)
			(layer "B.Fab")
			(hide yes)
			(effects
				(font
					(size 1 1)
					(thickness 0.15)
				)
				(justify mirror)
			)
		)
		(property "License" "Apache-2.0"
			(at 0 0 90)
			(unlocked yes)
			(layer "B.Fab")
			(hide yes)
			(effects
				(font
					(size 1 1)
					(thickness 0.15)
				)
				(justify mirror)
			)
		)
		(property "Author" "Antmicro"
			(at 0 0 90)
			(unlocked yes)
			(layer "B.Fab")
			(hide yes)
			(effects
				(font
					(size 1 1)
					(thickness 0.15)
				)
				(justify mirror)
			)
		)
		(property "Val" "100n"
			(at 0 0 90)
			(unlocked yes)
			(layer "B.Fab")
			(hide yes)
			(effects
				(font
					(size 1 1)
					(thickness 0.15)
				)
				(justify mirror)
			)
		)
		(property "Voltage" "50V"
			(at 0 0 90)
			(unlocked yes)
			(layer "B.Fab")
			(hide yes)
			(effects
				(font
					(size 1 1)
					(thickness 0.15)
				)
				(justify mirror)
			)
		)
		(property "Dielectric" "X5R"
			(at 0 0 90)
			(unlocked yes)
			(layer "B.Fab")
			(hide yes)
			(effects
				(font
					(size 1 1)
					(thickness 0.15)
				)
				(justify mirror)
			)
		)
		(sheetname "/FPGA power/")
		(sheetfile "fpga-power.kicad_sch")
		(attr smd)
		(fp_rect
			(start -0.95 0.45)
			(end 0.95 -0.45)
			(stroke
				(width 0.05)
				(type default)
			)
			(fill no)
			(layer "B.CrtYd")
		)
		(fp_line
			(start 0.498 -0.248)
			(end -0.5 -0.248)
			(stroke
				(width 0.15)
				(type solid)
			)
			(layer "B.Fab")
		)
		(fp_line
			(start -0.5 -0.248)
			(end -0.5 0.25)
			(stroke
				(width 0.15)
				(type solid)
			)
			(layer "B.Fab")
		)
		(fp_line
			(start 0.498 0.25)
			(end 0.498 -0.248)
			(stroke
				(width 0.15)
				(type solid)
			)
			(layer "B.Fab")
		)
		(fp_line
			(start -0.5 0.25)
			(end 0.498 0.25)
			(stroke
				(width 0.15)
				(type solid)
			)
			(layer "B.Fab")
		)
		(fp_text user "Author: Antmicro"
			(at -0.9656 -5.569 270)
			(layer "B.Fab")
			(effects
				(font
					(size 0.7 0.7)
					(thickness 0.15)
				)
				(justify left bottom mirror)
			)
		)
		(fp_text user "License: Apache-2.0"
			(at -0.9656 -4.369 270)
			(layer "B.Fab")
			(effects
				(font
					(size 0.7 0.7)
					(thickness 0.15)
				)
				(justify left bottom mirror)
			)
		)
		(fp_text user "${REFERENCE}"
			(at -0.9656 -3.169 270)
			(layer "B.Fab")
			(effects
				(font
					(size 0.7 0.7)
					(thickness 0.15)
				)
				(justify left bottom mirror)
			)
		)
		(pad "1" smd roundrect
			(at -0.5 0)
			(size 0.6 0.6)
			(layers "B.Cu" "B.Mask" "B.Paste")
			(roundrect_rratio 0.25)
			(net 1 "GND")
			(pintype "passive")
		)
		(pad "2" smd roundrect
			(at 0.498 0 90)
			(size 0.6 0.6)
			(layers "B.Cu" "B.Mask" "B.Paste")
			(roundrect_rratio 0.25)
			(net 820 "+0V9_MGTAVCC")
			(pintype "passive")
		)
	)
	(footprint "antmicro-footprints:C_0402_1005Metric"
		(layer "B.Cu")
		(at 211.91 154.425)
		(descr "Capacitor SMD 0402")
		(tags "capacitor SMD 0402")
		(property "Reference" "C5"
			(at 0.99 0.465 0)
			(layer "B.SilkS")
			(effects
				(font
					(size 0.7 0.7)
					(thickness 0.15)
				)
				(justify right bottom mirror)
			)
		)
		(property "Value" "C_100n_0402"
			(at -1.022927 -2.155213 0)
			(layer "B.Fab")
			(effects
				(font
					(size 0.7 0.7)
					(thickness 0.15)
				)
				(justify right bottom mirror)
			)
		)
		(property "Datasheet" "https://www.murata.com/products/productdetail?partno=GRM155R61H104KE14%23"
			(at 0 0 0)
			(layer "F.Fab")
			(hide yes)
			(effects
				(font
					(size 1.27 1.27)
					(thickness 0.15)
				)
			)
		)
		(property "Manufacturer" "Murata"
			(at 0 0 0)
			(unlocked yes)
			(layer "B.Fab")
			(hide yes)
			(effects
				(font
					(size 1 1)
					(thickness 0.15)
				)
				(justify mirror)
			)
		)
		(property "MPN" "GRM155R61H104KE14D"
			(at 0 0 0)
			(unlocked yes)
			(layer "B.Fab")
			(hide yes)
			(effects
				(font
					(size 1 1)
					(thickness 0.15)
				)
				(justify mirror)
			)
		)
		(property "Val" "100n"
			(at 0 0 0)
			(unlocked yes)
			(layer "B.Fab")
			(hide yes)
			(effects
				(font
					(size 1 1)
					(thickness 0.15)
				)
				(justify mirror)
			)
		)
		(property "License" "Apache-2.0"
			(at 0 0 0)
			(unlocked yes)
			(layer "B.Fab")
			(hide yes)
			(effects
				(font
					(size 1 1)
					(thickness 0.15)
				)
				(justify mirror)
			)
		)
		(property "Author" "Antmicro"
			(at 0 0 0)
			(unlocked yes)
			(layer "B.Fab")
			(hide yes)
			(effects
				(font
					(size 1 1)
					(thickness 0.15)
				)
				(justify mirror)
			)
		)
		(property "Voltage" "50V"
			(at 0 0 0)
			(unlocked yes)
			(layer "B.Fab")
			(hide yes)
			(effects
				(font
					(size 1 1)
					(thickness 0.15)
				)
				(justify mirror)
			)
		)
		(property "Dielectric" "X5R"
			(at 0 0 0)
			(unlocked yes)
			(layer "B.Fab")
			(hide yes)
			(effects
				(font
					(size 1 1)
					(thickness 0.15)
				)
				(justify mirror)
			)
		)
		(sheetname "/HyperRAM + QSPI Flash/")
		(sheetfile "hyperram-flash.kicad_sch")
		(attr smd)
		(fp_rect
			(start -0.925 0.47)
			(end 0.925 -0.47)
			(stroke
				(width 0.05)
				(type default)
			)
			(fill no)
			(layer "B.CrtYd")
		)
		(fp_line
			(start -0.494 -0.248)
			(end -0.494 0.25)
			(stroke
				(width 0.15)
				(type solid)
			)
			(layer "B.Fab")
		)
		(fp_line
			(start -0.494 0.25)
			(end 0.504 0.25)
			(stroke
				(width 0.15)
				(type solid)
			)
			(layer "B.Fab")
		)
		(fp_line
			(start 0.504 -0.248)
			(end -0.494 -0.248)
			(stroke
				(width 0.15)
				(type solid)
			)
			(layer "B.Fab")
		)
		(fp_line
			(start 0.504 0.25)
			(end 0.504 -0.248)
			(stroke
				(width 0.15)
				(type solid)
			)
			(layer "B.Fab")
		)
		(fp_text user "License: Apache-2.0"
			(at -0.939 -5.799 180)
			(layer "B.Fab")
			(effects
				(font
					(size 0.7 0.7)
					(thickness 0.15)
				)
				(justify left bottom mirror)
			)
		)
		(fp_text user "${REFERENCE}"
			(at -0.939 -4.599 180)
			(layer "B.Fab")
			(effects
				(font
					(size 0.7 0.7)
					(thickness 0.15)
				)
				(justify left bottom mirror)
			)
		)
		(fp_text user "Author: Antmicro"
			(at -0.939 -3.399 180)
			(layer "B.Fab")
			(effects
				(font
					(size 0.7 0.7)
					(thickness 0.15)
				)
				(justify left bottom mirror)
			)
		)
		(pad "1" smd roundrect
			(at -0.48 0)
			(size 0.59 0.64)
			(layers "B.Cu" "B.Mask" "B.Paste")
			(roundrect_rratio 0.25)
			(net 797 "+1V8")
			(pintype "passive")
		)
		(pad "2" smd roundrect
			(at 0.48 0)
			(size 0.59 0.64)
			(layers "B.Cu" "B.Mask" "B.Paste")
			(roundrect_rratio 0.25)
			(net 1 "GND")
			(pintype "passive")
		)
	)
	(footprint "antmicro-footprints:R_0402_1005Metric"
		(layer "B.Cu")
		(at 128.879 102.638 180)
		(descr "Resistor SMD 0402")
		(tags "resistor SMD 0402")
		(property "Reference" "R233"
			(at -1.122484 0.772697 0)
			(layer "B.SilkS")
			(effects
				(font
					(size 0.7 0.7)
					(thickness 0.15)
				)
				(justify left bottom mirror)
			)
		)
		(property "Value" "R_49R9_0402"
			(at -1.011843 -1.772047 0)
			(layer "B.Fab")
			(effects
				(font
					(size 0.7 0.7)
					(thickness 0.15)
				)
				(justify left bottom mirror)
			)
		)
		(property "Datasheet" "https://www.bourns.com/docs/product-datasheets/cr.pdf"
			(at 0 0 180)
			(layer "F.Fab")
			(hide yes)
			(effects
				(font
					(size 1.27 1.27)
					(thickness 0.15)
				)
			)
		)
		(property "MPN" "CR0402-FX-49R9GLF"
			(at 0 0 180)
			(unlocked yes)
			(layer "B.Fab")
			(hide yes)
			(effects
				(font
					(size 1 1)
					(thickness 0.15)
				)
				(justify mirror)
			)
		)
		(property "Manufacturer" "Bourns"
			(at 0 0 180)
			(unlocked yes)
			(layer "B.Fab")
			(hide yes)
			(effects
				(font
					(size 1 1)
					(thickness 0.15)
				)
				(justify mirror)
			)
		)
		(property "License" "Apache-2.0"
			(at 0 0 180)
			(unlocked yes)
			(layer "B.Fab")
			(hide yes)
			(effects
				(font
					(size 1 1)
					(thickness 0.15)
				)
				(justify mirror)
			)
		)
		(property "Author" "Antmicro"
			(at 0 0 180)
			(unlocked yes)
			(layer "B.Fab")
			(hide yes)
			(effects
				(font
					(size 1 1)
					(thickness 0.15)
				)
				(justify mirror)
			)
		)
		(property "Val" "49R9"
			(at 0 0 180)
			(unlocked yes)
			(layer "B.Fab")
			(hide yes)
			(effects
				(font
					(size 1 1)
					(thickness 0.15)
				)
				(justify mirror)
			)
		)
		(property "Tolerance" "1%"
			(at 0 0 180)
			(unlocked yes)
			(layer "B.Fab")
			(hide yes)
			(effects
				(font
					(size 1 1)
					(thickness 0.15)
				)
				(justify mirror)
			)
		)
		(sheetname "/Debug FTDI + VNA/")
		(sheetfile "debug-ftdi.kicad_sch")
		(attr smd)
		(fp_rect
			(start -0.925 0.47)
			(end 0.925 -0.47)
			(stroke
				(width 0.05)
				(type default)
			)
			(fill no)
			(layer "B.CrtYd")
		)
		(fp_rect
			(start -0.5 0.25)
			(end 0.5 -0.25)
			(stroke
				(width 0.15)
				(type solid)
			)
			(fill no)
			(layer "B.Fab")
		)
		(fp_text user "Author: Antmicro"
			(at -0.95 -4.169 0)
			(layer "B.Fab")
			(effects
				(font
					(size 0.7 0.7)
					(thickness 0.15)
				)
				(justify left bottom mirror)
			)
		)
		(fp_text user "License: Apache-2.0"
			(at -0.95 -5.169 0)
			(layer "B.Fab")
			(effects
				(font
					(size 0.7 0.7)
					(thickness 0.15)
				)
				(justify left bottom mirror)
			)
		)
		(fp_text user "${REFERENCE}"
			(at -0.95 -3.168 0)
			(layer "B.Fab")
			(effects
				(font
					(size 0.7 0.7)
					(thickness 0.15)
				)
				(justify left bottom mirror)
			)
		)
		(pad "1" smd roundrect
			(at -0.48 0 180)
			(size 0.59 0.64)
			(layers "B.Cu" "B.Mask" "B.Paste")
			(roundrect_rratio 0.25)
			(net 1 "GND")
			(pintype "passive")
		)
		(pad "2" smd roundrect
			(at 0.48 0 180)
			(size 0.59 0.64)
			(layers "B.Cu" "B.Mask" "B.Paste")
			(roundrect_rratio 0.25)
			(net 370 "Net-(J14-Pad1)")
			(pintype "passive")
		)
	)
	(footprint "antmicro-footprints:DFN-6-1EP_2x2mm_P0.65mm_EP1x1.6mm"
		(layer "B.Cu")
		(at 206.75 138.8045 180)
		(descr "6-Lead Plastic Dual Flat, No Lead Package - 2x2x0.9 mm Body")
		(tags "DFN")
		(property "Reference" "U12"
			(at -2.55 0.0125 0)
			(layer "B.SilkS")
			(effects
				(font
					(size 0.7 0.7)
					(thickness 0.15)
				)
				(justify mirror)
			)
		)
		(property "Value" "MCP4726A0T_DFN"
			(at 0 -2.1 0)
			(layer "B.Fab")
			(effects
				(font
					(size 0.7 0.7)
					(thickness 0.15)
				)
				(justify left bottom mirror)
			)
		)
		(property "Datasheet" "https://ww1.microchip.com/downloads/en/DeviceDoc/22272C.pdf"
			(at 0 0 0)
			(layer "B.Fab")
			(hide yes)
			(effects
				(font
					(size 1.27 1.27)
					(thickness 0.15)
				)
				(justify mirror)
			)
		)
		(property "MPN" "MCP4726A0T-E/MAY"
			(at 0 0 0)
			(unlocked yes)
			(layer "B.Fab")
			(hide yes)
			(effects
				(font
					(size 1 1)
					(thickness 0.15)
				)
				(justify mirror)
			)
		)
		(property "Manufacturer" "Microchip Technology"
			(at 0 0 0)
			(unlocked yes)
			(layer "B.Fab")
			(hide yes)
			(effects
				(font
					(size 1 1)
					(thickness 0.15)
				)
				(justify mirror)
			)
		)
		(property "Author" "Antmicro"
			(at 0 0 0)
			(unlocked yes)
			(layer "B.Fab")
			(hide yes)
			(effects
				(font
					(size 1 1)
					(thickness 0.15)
				)
				(justify mirror)
			)
		)
		(property "License" "Apache-2.0"
			(at 0 0 0)
			(unlocked yes)
			(layer "B.Fab")
			(hide yes)
			(effects
				(font
					(size 1 1)
					(thickness 0.15)
				)
				(justify mirror)
			)
		)
		(property ki_fp_filters "DFN6_2x2MC_MCH DFN6_2x2MC_MCH-M DFN6_2x2MC_MCH-L")
		(sheetname "/Supply/")
		(sheetfile "supply.kicad_sch")
		(attr smd)
		(fp_line
			(start 1.075 1.1)
			(end 1.075 0.925)
			(stroke
				(width 0.15)
				(type solid)
			)
			(layer "B.SilkS")
		)
		(fp_line
			(start 1.075 -0.9375)
			(end 1.075 -1.1125)
			(stroke
				(width 0.15)
				(type solid)
			)
			(layer "B.SilkS")
		)
		(fp_line
			(start -1.075 1.1)
			(end 1.075 1.1)
			(stroke
				(width 0.15)
				(type solid)
			)
			(layer "B.SilkS")
		)
		(fp_line
			(start -1.075 1.1)
			(end -1.075 0.925)
			(stroke
				(width 0.15)
				(type solid)
			)
			(layer "B.SilkS")
		)
		(fp_line
			(start -1.075 -0.9375)
			(end -1.075 -1.1125)
			(stroke
				(width 0.15)
				(type solid)
			)
			(layer "B.SilkS")
		)
		(fp_line
			(start -1.075 -1.1125)
			(end 1.075 -1.1125)
			(stroke
				(width 0.15)
				(type solid)
			)
			(layer "B.SilkS")
		)
		(fp_circle
			(center -1.325 1.04571)
			(end -1.275 1.04571)
			(stroke
				(width 0.15)
				(type solid)
			)
			(fill yes)
			(layer "B.SilkS")
		)
		(fp_rect
			(start -1.405 1.25)
			(end 1.405 -1.225)
			(stroke
				(width 0.05)
				(type solid)
			)
			(fill no)
			(layer "B.CrtYd")
		)
		(fp_line
			(start -1 0.5)
			(end -0.5 1)
			(stroke
				(width 0.15)
				(type solid)
			)
			(layer "B.Fab")
		)
		(fp_rect
			(start 1 -1)
			(end -1 1)
			(stroke
				(width 0.15)
				(type solid)
			)
			(fill no)
			(layer "B.Fab")
		)
		(fp_text user "${REFERENCE}"
			(at -1.405 -3.4 0)
			(layer "B.Fab")
			(effects
				(font
					(size 0.7 0.7)
					(thickness 0.15)
				)
				(justify left bottom mirror)
			)
		)
		(fp_text user "License: Apache-2.0"
			(at -1.405 -5.799 0)
			(layer "B.Fab")
			(effects
				(font
					(size 0.7 0.7)
					(thickness 0.15)
				)
				(justify left bottom mirror)
			)
		)
		(fp_text user "Author: Antmicro"
			(at -1.405 -4.6 0)
			(layer "B.Fab")
			(effects
				(font
					(size 0.7 0.7)
					(thickness 0.15)
				)
				(justify left bottom mirror)
			)
		)
		(pad "" smd rect
			(at 0 -0.4 180)
			(size 0.82 0.63)
			(layers "B.Paste")
		)
		(pad "" smd rect
			(at 0 0.402 180)
			(size 0.82 0.63)
			(layers "B.Paste")
		)
		(pad "1" smd rect
			(at -1.051 0.652 180)
			(size 0.65 0.35)
			(layers "B.Cu" "B.Mask" "B.Paste")
			(net 687 "VDDQ")
			(pinfunction "VREF")
			(pintype "power_in")
		)
		(pad "2" smd rect
			(at -1.051 0 180)
			(size 0.65 0.35)
			(layers "B.Cu" "B.Mask" "B.Paste")
			(net 749 "/I^{2}C + I3C/PWR.SCL")
			(pinfunction "SCL")
			(pintype "input")
		)
		(pad "3" smd rect
			(at -1.051 -0.65 180)
			(size 0.65 0.35)
			(layers "B.Cu" "B.Mask" "B.Paste")
			(net 533 "/I^{2}C + I3C/PWR.SDA")
			(pinfunction "SDA")
			(pintype "bidirectional")
		)
		(pad "4" smd rect
			(at 1.05 -0.65 180)
			(size 0.65 0.35)
			(layers "B.Cu" "B.Mask" "B.Paste")
			(net 151 "+3V3")
			(pinfunction "VDD")
			(pintype "power_in")
		)
		(pad "5" smd rect
			(at 1.05 0 180)
			(size 0.65 0.35)
			(layers "B.Cu" "B.Mask" "B.Paste")
			(net 1 "GND")
			(pinfunction "GND")
			(pintype "power_in")
		)
		(pad "6" smd rect
			(at 1.05 0.652 180)
			(size 0.65 0.35)
			(layers "B.Cu" "B.Mask" "B.Paste")
			(net 825 "DAC_VREF")
			(pinfunction "VOUT")
			(pintype "output")
		)
		(pad "7" smd rect
			(at 0 0 180)
			(size 1 1.6)
			(layers "B.Cu" "B.Mask")
			(net 1 "GND")
			(pinfunction "SH")
			(pintype "power_in")
		)
	)
	(footprint "antmicro-footprints:C_0402_1005Metric"
		(layer "B.Cu")
		(at 194.672499 193.2285 90)
		(descr "Capacitor SMD 0402")
		(tags "capacitor SMD 0402")
		(property "Reference" "C252"
			(at 0.994 0.403501 90)
			(layer "B.SilkS")
			(effects
				(font
					(size 0.7 0.7)
					(thickness 0.15)
				)
				(justify right bottom mirror)
			)
		)
		(property "Value" "C_100n_0402"
			(at -1.022927 -2.155213 90)
			(layer "B.Fab")
			(effects
				(font
					(size 0.7 0.7)
					(thickness 0.15)
				)
				(justify right bottom mirror)
			)
		)
		(property "Datasheet" "https://www.murata.com/products/productdetail?partno=GRM155R61H104KE14%23"
			(at 0 0 90)
			(layer "F.Fab")
			(hide yes)
			(effects
				(font
					(size 1.27 1.27)
					(thickness 0.15)
				)
			)
		)
		(property "Manufacturer" "Murata"
			(at 0 0 90)
			(unlocked yes)
			(layer "B.Fab")
			(hide yes)
			(effects
				(font
					(size 1 1)
					(thickness 0.15)
				)
				(justify mirror)
			)
		)
		(property "MPN" "GRM155R61H104KE14D"
			(at 0 0 90)
			(unlocked yes)
			(layer "B.Fab")
			(hide yes)
			(effects
				(font
					(size 1 1)
					(thickness 0.15)
				)
				(justify mirror)
			)
		)
		(property "Val" "100n"
			(at 0 0 90)
			(unlocked yes)
			(layer "B.Fab")
			(hide yes)
			(effects
				(font
					(size 1 1)
					(thickness 0.15)
				)
				(justify mirror)
			)
		)
		(property "License" "Apache-2.0"
			(at 0 0 90)
			(unlocked yes)
			(layer "B.Fab")
			(hide yes)
			(effects
				(font
					(size 1 1)
					(thickness 0.15)
				)
				(justify mirror)
			)
		)
		(property "Author" "Antmicro"
			(at 0 0 90)
			(unlocked yes)
			(layer "B.Fab")
			(hide yes)
			(effects
				(font
					(size 1 1)
					(thickness 0.15)
				)
				(justify mirror)
			)
		)
		(property "Voltage" "50V"
			(at 0 0 90)
			(unlocked yes)
			(layer "B.Fab")
			(hide yes)
			(effects
				(font
					(size 1 1)
					(thickness 0.15)
				)
				(justify mirror)
			)
		)
		(property "Dielectric" "X5R"
			(at 0 0 90)
			(unlocked yes)
			(layer "B.Fab")
			(hide yes)
			(effects
				(font
					(size 1 1)
					(thickness 0.15)
				)
				(justify mirror)
			)
		)
		(sheetname "/FPGA MGT Interface/")
		(sheetfile "fpga-mgt.kicad_sch")
		(attr smd)
		(fp_rect
			(start -0.925 0.47)
			(end 0.925 -0.47)
			(stroke
				(width 0.05)
				(type default)
			)
			(fill no)
			(layer "B.CrtYd")
		)
		(fp_line
			(start 0.504 -0.248)
			(end -0.494 -0.248)
			(stroke
				(width 0.15)
				(type solid)
			)
			(layer "B.Fab")
		)
		(fp_line
			(start -0.494 -0.248)
			(end -0.494 0.25)
			(stroke
				(width 0.15)
				(type solid)
			)
			(layer "B.Fab")
		)
		(fp_line
			(start 0.504 0.25)
			(end 0.504 -0.248)
			(stroke
				(width 0.15)
				(type solid)
			)
			(layer "B.Fab")
		)
		(fp_line
			(start -0.494 0.25)
			(end 0.504 0.25)
			(stroke
				(width 0.15)
				(type solid)
			)
			(layer "B.Fab")
		)
		(fp_text user "${REFERENCE}"
			(at -0.939 -4.599 270)
			(layer "B.Fab")
			(effects
				(font
					(size 0.7 0.7)
					(thickness 0.15)
				)
				(justify left bottom mirror)
			)
		)
		(fp_text user "License: Apache-2.0"
			(at -0.939 -5.799 270)
			(layer "B.Fab")
			(effects
				(font
					(size 0.7 0.7)
					(thickness 0.15)
				)
				(justify left bottom mirror)
			)
		)
		(fp_text user "Author: Antmicro"
			(at -0.939 -3.399 270)
			(layer "B.Fab")
			(effects
				(font
					(size 0.7 0.7)
					(thickness 0.15)
				)
				(justify left bottom mirror)
			)
		)
		(pad "1" smd roundrect
			(at -0.48 0 90)
			(size 0.59 0.64)
			(layers "B.Cu" "B.Mask" "B.Paste")
			(roundrect_rratio 0.25)
			(net 254 "/FPGA MGT Interface/PCIE.TXD7_N")
			(pintype "passive")
		)
		(pad "2" smd roundrect
			(at 0.48 0 90)
			(size 0.59 0.64)
			(layers "B.Cu" "B.Mask" "B.Paste")
			(roundrect_rratio 0.25)
			(net 558 "/FPGA MGT Interface/GTY_224_TX0_N")
			(pintype "passive")
		)
	)
	(footprint "antmicro-footprints:R_0402_1005Metric"
		(layer "B.Cu")
		(at 231.685 183.97)
		(descr "Resistor SMD 0402")
		(tags "resistor SMD 0402")
		(property "Reference" "R199"
			(at -1.815 -1.555 0)
			(layer "B.SilkS")
			(effects
				(font
					(size 0.7 0.7)
					(thickness 0.15)
				)
				(justify right bottom mirror)
			)
		)
		(property "Value" "R_15k_0402"
			(at -1.011843 -1.772047 0)
			(layer "B.Fab")
			(effects
				(font
					(size 0.7 0.7)
					(thickness 0.15)
				)
				(justify right bottom mirror)
			)
		)
		(property "Datasheet" "https://www.bourns.com/docs/product-datasheets/cr.pdf"
			(at 0 0 0)
			(layer "F.Fab")
			(hide yes)
			(effects
				(font
					(size 1.27 1.27)
					(thickness 0.15)
				)
			)
		)
		(property "MPN" "CR0402-FX-1502GLF"
			(at 0 0 0)
			(unlocked yes)
			(layer "B.Fab")
			(hide yes)
			(effects
				(font
					(size 1 1)
					(thickness 0.15)
				)
				(justify mirror)
			)
		)
		(property "Manufacturer" "Bourns"
			(at 0 0 0)
			(unlocked yes)
			(layer "B.Fab")
			(hide yes)
			(effects
				(font
					(size 1 1)
					(thickness 0.15)
				)
				(justify mirror)
			)
		)
		(property "License" "Apache-2.0"
			(at 0 0 0)
			(unlocked yes)
			(layer "B.Fab")
			(hide yes)
			(effects
				(font
					(size 1 1)
					(thickness 0.15)
				)
				(justify mirror)
			)
		)
		(property "Author" "Antmicro"
			(at 0 0 0)
			(unlocked yes)
			(layer "B.Fab")
			(hide yes)
			(effects
				(font
					(size 1 1)
					(thickness 0.15)
				)
				(justify mirror)
			)
		)
		(property "Val" "15k"
			(at 0 0 0)
			(unlocked yes)
			(layer "B.Fab")
			(hide yes)
			(effects
				(font
					(size 1 1)
					(thickness 0.15)
				)
				(justify mirror)
			)
		)
		(property "Tolerance" "1%"
			(at 0 0 0)
			(unlocked yes)
			(layer "B.Fab")
			(hide yes)
			(effects
				(font
					(size 1 1)
					(thickness 0.15)
				)
				(justify mirror)
			)
		)
		(sheetname "/Supply/DC-DC VCCINT/")
		(sheetfile "dc-dc-vccint.kicad_sch")
		(attr smd)
		(fp_rect
			(start -0.925 0.47)
			(end 0.925 -0.47)
			(stroke
				(width 0.05)
				(type default)
			)
			(fill no)
			(layer "B.CrtYd")
		)
		(fp_rect
			(start -0.5 0.25)
			(end 0.5 -0.25)
			(stroke
				(width 0.15)
				(type solid)
			)
			(fill no)
			(layer "B.Fab")
		)
		(fp_text user "Author: Antmicro"
			(at -0.95 -4.169 180)
			(layer "B.Fab")
			(effects
				(font
					(size 0.7 0.7)
					(thickness 0.15)
				)
				(justify left bottom mirror)
			)
		)
		(fp_text user "${REFERENCE}"
			(at -0.95 -3.168 180)
			(layer "B.Fab")
			(effects
				(font
					(size 0.7 0.7)
					(thickness 0.15)
				)
				(justify left bottom mirror)
			)
		)
		(fp_text user "License: Apache-2.0"
			(at -0.95 -5.169 180)
			(layer "B.Fab")
			(effects
				(font
					(size 0.7 0.7)
					(thickness 0.15)
				)
				(justify left bottom mirror)
			)
		)
		(pad "1" smd roundrect
			(at -0.48 0)
			(size 0.59 0.64)
			(layers "B.Cu" "B.Mask" "B.Paste")
			(roundrect_rratio 0.25)
			(net 1 "GND")
			(pintype "passive")
		)
		(pad "2" smd roundrect
			(at 0.48 0)
			(size 0.59 0.64)
			(layers "B.Cu" "B.Mask" "B.Paste")
			(roundrect_rratio 0.25)
			(net 728 "Net-(U36-ADDR)")
			(pintype "passive")
		)
	)
	(footprint "antmicro-footprints:TP_SMD_1mm"
		(layer "B.Cu")
		(at 233.35 184.725 90)
		(property "Reference" "TP26"
			(at -0.725 0.7 180)
			(layer "B.SilkS")
			(effects
				(font
					(size 0.7 0.7)
					(thickness 0.15)
				)
				(justify right bottom mirror)
			)
		)
		(property "Value" "TP_1mm_SMD"
			(at 0 -1.4 90)
			(layer "B.Fab")
			(effects
				(font
					(size 0.7 0.7)
					(thickness 0.15)
				)
				(justify right bottom mirror)
			)
		)
		(property "MPN" ""
			(at 0 0 90)
			(unlocked yes)
			(layer "B.Fab")
			(hide yes)
			(effects
				(font
					(size 1 1)
					(thickness 0.15)
				)
				(justify mirror)
			)
		)
		(property "Manufacturer" ""
			(at 0 0 90)
			(unlocked yes)
			(layer "B.Fab")
			(hide yes)
			(effects
				(font
					(size 1 1)
					(thickness 0.15)
				)
				(justify mirror)
			)
		)
		(property "Author" "Antmicro"
			(at 0 0 90)
			(unlocked yes)
			(layer "B.Fab")
			(hide yes)
			(effects
				(font
					(size 1 1)
					(thickness 0.15)
				)
				(justify mirror)
			)
		)
		(property "License" "Apache-2.0"
			(at 0 0 90)
			(unlocked yes)
			(layer "B.Fab")
			(hide yes)
			(effects
				(font
					(size 1 1)
					(thickness 0.15)
				)
				(justify mirror)
			)
		)
		(sheetname "/Supply/DC-DC VCCINT/")
		(sheetfile "dc-dc-vccint.kicad_sch")
		(attr exclude_from_pos_files)
		(fp_circle
			(center 0 0)
			(end 0.6 0)
			(stroke
				(width 0.05)
				(type default)
			)
			(fill no)
			(layer "B.CrtYd")
		)
		(fp_text user "License: Apache-2.0"
			(at -0.5 -5.2 270)
			(layer "B.Fab")
			(effects
				(font
					(size 0.7 0.7)
					(thickness 0.15)
				)
				(justify left bottom mirror)
			)
		)
		(fp_text user "Author: Antmicro"
			(at -0.5 -4 270)
			(layer "B.Fab")
			(effects
				(font
					(size 0.7 0.7)
					(thickness 0.15)
				)
				(justify left bottom mirror)
			)
		)
		(fp_text user "${REFERENCE}"
			(at -0.5 -2.8 270)
			(layer "B.Fab")
			(effects
				(font
					(size 0.7 0.7)
					(thickness 0.15)
				)
				(justify left bottom mirror)
			)
		)
		(pad "1" smd circle
			(at 0 0 90)
			(size 1 1)
			(layers "B.Cu" "B.Mask")
			(net 777 "/Supply/DC-DC VCCINT/~{PS}")
			(pinfunction "1")
			(pintype "passive")
		)
	)
	(footprint "antmicro-footprints:R_0402_1005Metric_EIA"
		(layer "B.Cu")
		(at 193 146.5 -90)
		(descr "Resistor SMD 0402 (1005 Metric), square (rectangular) end terminal, IPC_7351 nominal, (Body size source: IPC-SM-782 page 76, https://www.pcb-3d.com/wordpress/wp-content/uploads/ipc-sm-782a_amendment_1_and_2.pdf)")
		(tags "resistor 0402")
		(property "Reference" "R130"
			(at -13.2 30.7 90)
			(layer "B.SilkS")
			(effects
				(font
					(size 0.7 0.7)
					(thickness 0.15)
				)
				(justify left bottom mirror)
			)
		)
		(property "Value" "R_1k_0402"
			(at 0 -1.169 90)
			(layer "B.Fab")
			(effects
				(font
					(size 0.7 0.7)
					(thickness 0.15)
				)
				(justify left bottom mirror)
			)
		)
		(property "Datasheet" "https://www.bourns.com/docs/product-datasheets/cr.pdf"
			(at 0 0 90)
			(layer "F.Fab")
			(hide yes)
			(effects
				(font
					(size 1.27 1.27)
					(thickness 0.15)
				)
			)
		)
		(property "MPN" "CR0402-FX-1001GLF"
			(at 0 0 270)
			(unlocked yes)
			(layer "B.Fab")
			(hide yes)
			(effects
				(font
					(size 1 1)
					(thickness 0.15)
				)
				(justify mirror)
			)
		)
		(property "Manufacturer" "Bourns"
			(at 0 0 270)
			(unlocked yes)
			(layer "B.Fab")
			(hide yes)
			(effects
				(font
					(size 1 1)
					(thickness 0.15)
				)
				(justify mirror)
			)
		)
		(property "License" "Apache-2.0"
			(at 0 0 270)
			(unlocked yes)
			(layer "B.Fab")
			(hide yes)
			(effects
				(font
					(size 1 1)
					(thickness 0.15)
				)
				(justify mirror)
			)
		)
		(property "Author" "Antmicro"
			(at 0 0 270)
			(unlocked yes)
			(layer "B.Fab")
			(hide yes)
			(effects
				(font
					(size 1 1)
					(thickness 0.15)
				)
				(justify mirror)
			)
		)
		(property "Val" "1k"
			(at 0 0 270)
			(unlocked yes)
			(layer "B.Fab")
			(hide yes)
			(effects
				(font
					(size 1 1)
					(thickness 0.15)
				)
				(justify mirror)
			)
		)
		(property "Tolerance" "1%"
			(at 0 0 270)
			(unlocked yes)
			(layer "B.Fab")
			(hide yes)
			(effects
				(font
					(size 1 1)
					(thickness 0.15)
				)
				(justify mirror)
			)
		)
		(sheetname "/FPGA banks HP/")
		(sheetfile "fpga-hp-banks.kicad_sch")
		(attr smd exclude_from_bom dnp)
		(fp_rect
			(start -0.95 0.45)
			(end 0.95 -0.45)
			(stroke
				(width 0.05)
				(type default)
			)
			(fill no)
			(layer "B.CrtYd")
		)
		(fp_line
			(start -0.5 0.25)
			(end 0.499 0.25)
			(stroke
				(width 0.15)
				(type solid)
			)
			(layer "B.Fab")
		)
		(fp_line
			(start 0.499 0.25)
			(end 0.499 -0.249)
			(stroke
				(width 0.15)
				(type solid)
			)
			(layer "B.Fab")
		)
		(fp_line
			(start -0.5 -0.249)
			(end -0.5 0.25)
			(stroke
				(width 0.15)
				(type solid)
			)
			(layer "B.Fab")
		)
		(fp_line
			(start 0.499 -0.249)
			(end -0.5 -0.249)
			(stroke
				(width 0.15)
				(type solid)
			)
			(layer "B.Fab")
		)
		(fp_text user "License: Apache-2.0"
			(at -0.95 -4.369 90)
			(layer "B.Fab")
			(effects
				(font
					(size 0.7 0.7)
					(thickness 0.15)
				)
				(justify left bottom mirror)
			)
		)
		(fp_text user "Author: Antmicro"
			(at -0.95 -5.569 90)
			(layer "B.Fab")
			(effects
				(font
					(size 0.7 0.7)
					(thickness 0.15)
				)
				(justify left bottom mirror)
			)
		)
		(fp_text user "${REFERENCE}"
			(at -0.95 -3.169 90)
			(layer "B.Fab")
			(effects
				(font
					(size 0.7 0.7)
					(thickness 0.15)
				)
				(justify left bottom mirror)
			)
		)
		(pad "1" smd roundrect
			(at -0.5 0 180)
			(size 0.6 0.6)
			(layers "B.Cu" "B.Mask" "B.Paste")
			(roundrect_rratio 0.25)
			(net 1 "GND")
			(pintype "passive")
		)
		(pad "2" smd roundrect
			(at 0.499 0 270)
			(size 0.6 0.6)
			(layers "B.Cu" "B.Mask" "B.Paste")
			(roundrect_rratio 0.25)
			(net 536 "/FPGA banks HP/VREF_65")
			(pintype "passive")
		)
	)
	(footprint "antmicro-footprints:R_0402_1005Metric"
		(layer "B.Cu")
		(at 244.86 122.225)
		(descr "Resistor SMD 0402")
		(tags "resistor SMD 0402")
		(property "Reference" "R250"
			(at -1.68 1.425 0)
			(layer "B.SilkS")
			(effects
				(font
					(size 0.7 0.7)
					(thickness 0.15)
				)
				(justify right bottom mirror)
			)
		)
		(property "Value" "R_47k_0402"
			(at -1.011843 -1.772047 0)
			(layer "B.Fab")
			(effects
				(font
					(size 0.7 0.7)
					(thickness 0.15)
				)
				(justify right bottom mirror)
			)
		)
		(property "Datasheet" "https://www.bourns.com/docs/product-datasheets/cr.pdf"
			(at 0 0 0)
			(layer "F.Fab")
			(hide yes)
			(effects
				(font
					(size 1.27 1.27)
					(thickness 0.15)
				)
			)
		)
		(property "MPN" "CR0402-FX-4702GLF"
			(at 0 0 0)
			(unlocked yes)
			(layer "B.Fab")
			(hide yes)
			(effects
				(font
					(size 1 1)
					(thickness 0.15)
				)
				(justify mirror)
			)
		)
		(property "Manufacturer" "Bourns"
			(at 0 0 0)
			(unlocked yes)
			(layer "B.Fab")
			(hide yes)
			(effects
				(font
					(size 1 1)
					(thickness 0.15)
				)
				(justify mirror)
			)
		)
		(property "License" "Apache-2.0"
			(at 0 0 0)
			(unlocked yes)
			(layer "B.Fab")
			(hide yes)
			(effects
				(font
					(size 1 1)
					(thickness 0.15)
				)
				(justify mirror)
			)
		)
		(property "Author" "Antmicro"
			(at 0 0 0)
			(unlocked yes)
			(layer "B.Fab")
			(hide yes)
			(effects
				(font
					(size 1 1)
					(thickness 0.15)
				)
				(justify mirror)
			)
		)
		(property "Val" "47k"
			(at 0 0 0)
			(unlocked yes)
			(layer "B.Fab")
			(hide yes)
			(effects
				(font
					(size 1 1)
					(thickness 0.15)
				)
				(justify mirror)
			)
		)
		(property "Tolerance" "1%"
			(at 0 0 0)
			(unlocked yes)
			(layer "B.Fab")
			(hide yes)
			(effects
				(font
					(size 1 1)
					(thickness 0.15)
				)
				(justify mirror)
			)
		)
		(sheetname "/Supply/")
		(sheetfile "supply.kicad_sch")
		(attr smd)
		(fp_rect
			(start -0.925 0.47)
			(end 0.925 -0.47)
			(stroke
				(width 0.05)
				(type default)
			)
			(fill no)
			(layer "B.CrtYd")
		)
		(fp_rect
			(start -0.5 0.25)
			(end 0.5 -0.25)
			(stroke
				(width 0.15)
				(type solid)
			)
			(fill no)
			(layer "B.Fab")
		)
		(fp_text user "License: Apache-2.0"
			(at -0.95 -5.169 180)
			(layer "B.Fab")
			(effects
				(font
					(size 0.7 0.7)
					(thickness 0.15)
				)
				(justify left bottom mirror)
			)
		)
		(fp_text user "Author: Antmicro"
			(at -0.95 -4.169 180)
			(layer "B.Fab")
			(effects
				(font
					(size 0.7 0.7)
					(thickness 0.15)
				)
				(justify left bottom mirror)
			)
		)
		(fp_text user "${REFERENCE}"
			(at -0.95 -3.168 180)
			(layer "B.Fab")
			(effects
				(font
					(size 0.7 0.7)
					(thickness 0.15)
				)
				(justify left bottom mirror)
			)
		)
		(pad "1" smd roundrect
			(at -0.48 0)
			(size 0.59 0.64)
			(layers "B.Cu" "B.Mask" "B.Paste")
			(roundrect_rratio 0.25)
			(net 1 "GND")
			(pintype "passive")
		)
		(pad "2" smd roundrect
			(at 0.48 0)
			(size 0.59 0.64)
			(layers "B.Cu" "B.Mask" "B.Paste")
			(roundrect_rratio 0.25)
			(net 812 "Heater_PWM")
			(pintype "passive")
		)
	)
	(footprint "antmicro-footprints:Coax_Conn_U.FL"
		(layer "B.Cu")
		(at 136.9 102.67 -90)
		(descr "https://media.digikey.com/pdf/Data%20Sheets/Hirose%20PDFs/UFL%20Series.pdf")
		(property "Reference" "J16"
			(at 3.38 -0.15 180)
			(layer "B.SilkS")
			(hide yes)
			(effects
				(font
					(size 0.7 0.7)
					(thickness 0.15)
				)
				(justify left bottom mirror)
			)
		)
		(property "Value" "U_FL-R-SMT-1"
			(at -4.13 -2.52 90)
			(layer "B.Fab")
			(effects
				(font
					(size 0.7 0.7)
					(thickness 0.15)
				)
				(justify left bottom mirror)
			)
		)
		(property "Datasheet" "https://media.digikey.com/pdf/Data%20Sheets/Hirose%20PDFs/UFL%20Series.pdf"
			(at 0 0 270)
			(layer "F.Fab")
			(hide yes)
			(effects
				(font
					(size 1.27 1.27)
					(thickness 0.15)
				)
			)
		)
		(property "MPN" "U.FL-R-SMT-1(10)"
			(at 0 0 270)
			(unlocked yes)
			(layer "B.Fab")
			(hide yes)
			(effects
				(font
					(size 1 1)
					(thickness 0.15)
				)
				(justify mirror)
			)
		)
		(property "Manufacturer" "Hirose Electric"
			(at 0 0 270)
			(unlocked yes)
			(layer "B.Fab")
			(hide yes)
			(effects
				(font
					(size 1 1)
					(thickness 0.15)
				)
				(justify mirror)
			)
		)
		(property "Author" "Antmicro"
			(at 0 0 270)
			(unlocked yes)
			(layer "B.Fab")
			(hide yes)
			(effects
				(font
					(size 1 1)
					(thickness 0.15)
				)
				(justify mirror)
			)
		)
		(property "License" "Apache-2.0"
			(at 0 0 270)
			(unlocked yes)
			(layer "B.Fab")
			(hide yes)
			(effects
				(font
					(size 1 1)
					(thickness 0.15)
				)
				(justify mirror)
			)
		)
		(sheetname "/Debug FTDI + VNA/")
		(sheetfile "debug-ftdi.kicad_sch")
		(attr smd)
		(fp_line
			(start -1.613 1.651)
			(end -1.113 1.651)
			(stroke
				(width 0.15)
				(type solid)
			)
			(layer "B.SilkS")
		)
		(fp_line
			(start -1.613 1.651)
			(end -1.613 1.325)
			(stroke
				(width 0.15)
				(type solid)
			)
			(layer "B.SilkS")
		)
		(fp_line
			(start 1.588 1.651)
			(end 1.088 1.651)
			(stroke
				(width 0.15)
				(type solid)
			)
			(layer "B.SilkS")
		)
		(fp_line
			(start 1.588 1.651)
			(end 1.588 1.325)
			(stroke
				(width 0.15)
				(type solid)
			)
			(layer "B.SilkS")
		)
		(fp_line
			(start -1.613 -1.648)
			(end -1.613 -1.325)
			(stroke
				(width 0.15)
				(type solid)
			)
			(layer "B.SilkS")
		)
		(fp_line
			(start -1.613 -1.648)
			(end -1.113 -1.648)
			(stroke
				(width 0.15)
				(type solid)
			)
			(layer "B.SilkS")
		)
		(fp_line
			(start 1.588 -1.648)
			(end 1.588 -1.325)
			(stroke
				(width 0.15)
				(type solid)
			)
			(layer "B.SilkS")
		)
		(fp_line
			(start 1.588 -1.648)
			(end 1.088 -1.648)
			(stroke
				(width 0.15)
				(type solid)
			)
			(layer "B.SilkS")
		)
		(fp_rect
			(start -2 2.051)
			(end 1.999 -2.05)
			(stroke
				(width 0.05)
				(type solid)
			)
			(fill no)
			(layer "B.CrtYd")
		)
		(fp_line
			(start -1.512 1.551)
			(end 1.487 1.551)
			(stroke
				(width 0.15)
				(type solid)
			)
			(layer "B.Fab")
		)
		(fp_line
			(start -1.512 -1.55)
			(end -1.512 1.551)
			(stroke
				(width 0.15)
				(type solid)
			)
			(layer "B.Fab")
		)
		(fp_line
			(start -1.512 -1.55)
			(end 1.487 -1.55)
			(stroke
				(width 0.15)
				(type solid)
			)
			(layer "B.Fab")
		)
		(fp_line
			(start 1.487 -1.55)
			(end 1.487 1.551)
			(stroke
				(width 0.15)
				(type solid)
			)
			(layer "B.Fab")
		)
		(fp_text user "Author: Antmicro"
			(at -4.13 -4.52 90)
			(layer "B.Fab")
			(effects
				(font
					(size 0.7 0.7)
					(thickness 0.15)
				)
				(justify left bottom mirror)
			)
		)
		(fp_text user "${REFERENCE}"
			(at -4.13 -6.92 90)
			(layer "B.Fab")
			(effects
				(font
					(size 0.7 0.7)
					(thickness 0.15)
				)
				(justify left bottom mirror)
			)
		)
		(fp_text user "License: Apache-2.0"
			(at -4.13 -5.72 90)
			(layer "B.Fab")
			(effects
				(font
					(size 0.7 0.7)
					(thickness 0.15)
				)
				(justify left bottom mirror)
			)
		)
		(pad "1" smd rect
			(at -0.012 -1.499 270)
			(size 1 1.05)
			(layers "B.Cu" "B.Mask" "B.Paste")
			(net 371 "Net-(J15-Pad1)")
			(pintype "passive")
		)
		(pad "SH1" smd rect
			(at 1.463 0 270)
			(size 1.05 2.2)
			(layers "B.Cu" "B.Mask" "B.Paste")
			(net 1 "GND")
			(pintype "passive")
		)
		(pad "SH2" smd rect
			(at -1.488 0 270)
			(size 1.05 2.2)
			(layers "B.Cu" "B.Mask" "B.Paste")
			(net 1 "GND")
			(pintype "passive")
		)
		(zone
			(net 0)
			(net_name "")
			(layer "B.Cu")
			(hatch edge 0.508)
			(connect_pads
				(clearance 0)
			)
			(min_thickness 0.254)
			(filled_areas_thickness no)
			(keepout
				(tracks not_allowed)
				(vias not_allowed)
				(pads not_allowed)
				(copperpour not_allowed)
				(footprints not_allowed)
			)
			(placement
				(enabled no)
				(sheetname "")
			)
			(fill
				(thermal_gap 0.508)
				(thermal_bridge_width 0.508)
			)
			(polygon
				(pts
					(xy 137.86 103.6) (xy 137.86 101.72) (xy 135.8 101.72) (xy 135.8 103.6)
				)
			)
		)
	)
	(footprint "antmicro-footprints:C_0402_1005Metric_EIA"
		(layer "B.Cu")
		(at 183 147.501 -90)
		(descr "Capacitor SMD 0402 (1005 Metric), square (rectangular) end terminal, IPC_7351 nominal, (Body size source: IPC-SM-782 page 76, https://www.pcb-3d.com/wordpress/wp-content/uploads/ipc-sm-782a_amendment_1_and_2.pdf)")
		(tags "capacitor 0402")
		(property "Reference" "C335"
			(at -12.601 30.7 90)
			(layer "B.SilkS")
			(effects
				(font
					(size 0.7 0.7)
					(thickness 0.15)
				)
				(justify left bottom mirror)
			)
		)
		(property "Value" "C_100n_0402"
			(at 0 -1.169 90)
			(layer "B.Fab")
			(effects
				(font
					(size 0.7 0.7)
					(thickness 0.15)
				)
				(justify left bottom mirror)
			)
		)
		(property "Manufacturer" "Murata"
			(at 0 0 270)
			(unlocked yes)
			(layer "B.Fab")
			(hide yes)
			(effects
				(font
					(size 1 1)
					(thickness 0.15)
				)
				(justify mirror)
			)
		)
		(property "MPN" "GRM155R61H104KE14D"
			(at 0 0 270)
			(unlocked yes)
			(layer "B.Fab")
			(hide yes)
			(effects
				(font
					(size 1 1)
					(thickness 0.15)
				)
				(justify mirror)
			)
		)
		(property "Val" "100n"
			(at 0 0 270)
			(unlocked yes)
			(layer "B.Fab")
			(hide yes)
			(effects
				(font
					(size 1 1)
					(thickness 0.15)
				)
				(justify mirror)
			)
		)
		(property "License" "Apache-2.0"
			(at 0 0 270)
			(unlocked yes)
			(layer "B.Fab")
			(hide yes)
			(effects
				(font
					(size 1 1)
					(thickness 0.15)
				)
				(justify mirror)
			)
		)
		(property "Author" "Antmicro"
			(at 0 0 270)
			(unlocked yes)
			(layer "B.Fab")
			(hide yes)
			(effects
				(font
					(size 1 1)
					(thickness 0.15)
				)
				(justify mirror)
			)
		)
		(property "Voltage" "50V"
			(at 0 0 270)
			(unlocked yes)
			(layer "B.Fab")
			(hide yes)
			(effects
				(font
					(size 1 1)
					(thickness 0.15)
				)
				(justify mirror)
			)
		)
		(property "Dielectric" "X5R"
			(at 0 0 270)
			(unlocked yes)
			(layer "B.Fab")
			(hide yes)
			(effects
				(font
					(size 1 1)
					(thickness 0.15)
				)
				(justify mirror)
			)
		)
		(sheetname "/FPGA banks HP/")
		(sheetfile "fpga-hp-banks.kicad_sch")
		(attr smd)
		(fp_rect
			(start -0.95 0.45)
			(end 0.95 -0.45)
			(stroke
				(width 0.05)
				(type default)
			)
			(fill no)
			(layer "B.CrtYd")
		)
		(fp_line
			(start -0.5 0.25)
			(end 0.498 0.25)
			(stroke
				(width 0.15)
				(type solid)
			)
			(layer "B.Fab")
		)
		(fp_line
			(start 0.498 0.25)
			(end 0.498 -0.248)
			(stroke
				(width 0.15)
				(type solid)
			)
			(layer "B.Fab")
		)
		(fp_line
			(start -0.5 -0.248)
			(end -0.5 0.25)
			(stroke
				(width 0.15)
				(type solid)
			)
			(layer "B.Fab")
		)
		(fp_line
			(start 0.498 -0.248)
			(end -0.5 -0.248)
			(stroke
				(width 0.15)
				(type solid)
			)
			(layer "B.Fab")
		)
		(fp_text user "License: Apache-2.0"
			(at -0.9656 -4.369 90)
			(layer "B.Fab")
			(effects
				(font
					(size 0.7 0.7)
					(thickness 0.15)
				)
				(justify left bottom mirror)
			)
		)
		(fp_text user "Author: Antmicro"
			(at -0.9656 -5.569 90)
			(layer "B.Fab")
			(effects
				(font
					(size 0.7 0.7)
					(thickness 0.15)
				)
				(justify left bottom mirror)
			)
		)
		(fp_text user "${REFERENCE}"
			(at -0.9656 -3.169 90)
			(layer "B.Fab")
			(effects
				(font
					(size 0.7 0.7)
					(thickness 0.15)
				)
				(justify left bottom mirror)
			)
		)
		(pad "1" smd roundrect
			(at -0.5 0 180)
			(size 0.6 0.6)
			(layers "B.Cu" "B.Mask" "B.Paste")
			(roundrect_rratio 0.25)
			(net 545 "/FPGA banks HP/VREF_66")
			(pintype "passive")
		)
		(pad "2" smd roundrect
			(at 0.498 0 270)
			(size 0.6 0.6)
			(layers "B.Cu" "B.Mask" "B.Paste")
			(roundrect_rratio 0.25)
			(net 1 "GND")
			(pintype "passive")
		)
	)
	(footprint "antmicro-footprints:C_0603_1608Metric"
		(layer "B.Cu")
		(at 221.02 172.06 90)
		(descr "Capacitor SMD 0603")
		(tags "capacitor 0603")
		(property "Reference" "C259"
			(at -4.04 0.39 90)
			(layer "B.SilkS")
			(effects
				(font
					(size 0.7 0.7)
					(thickness 0.15)
				)
				(justify right bottom mirror)
			)
		)
		(property "Value" "C_22u_0603"
			(at -1.42757 -1.770288 90)
			(layer "B.Fab")
			(effects
				(font
					(size 0.7 0.7)
					(thickness 0.15)
				)
				(justify right bottom mirror)
			)
		)
		(property "Datasheet" "https://www.murata.com/products/productdetail?partno=GRM188R60J226MEA0%23"
			(at 0 0 90)
			(layer "F.Fab")
			(hide yes)
			(effects
				(font
					(size 1.27 1.27)
					(thickness 0.15)
				)
			)
		)
		(property "Manufacturer" "Murata"
			(at 0 0 90)
			(unlocked yes)
			(layer "B.Fab")
			(hide yes)
			(effects
				(font
					(size 1 1)
					(thickness 0.15)
				)
				(justify mirror)
			)
		)
		(property "MPN" "GRM188R60J226MEA0D"
			(at 0 0 90)
			(unlocked yes)
			(layer "B.Fab")
			(hide yes)
			(effects
				(font
					(size 1 1)
					(thickness 0.15)
				)
				(justify mirror)
			)
		)
		(property "Val" "22u"
			(at 0 0 90)
			(unlocked yes)
			(layer "B.Fab")
			(hide yes)
			(effects
				(font
					(size 1 1)
					(thickness 0.15)
				)
				(justify mirror)
			)
		)
		(property "License" "Apache-2.0"
			(at 0 0 90)
			(unlocked yes)
			(layer "B.Fab")
			(hide yes)
			(effects
				(font
					(size 1 1)
					(thickness 0.15)
				)
				(justify mirror)
			)
		)
		(property "Author" "Antmicro"
			(at 0 0 90)
			(unlocked yes)
			(layer "B.Fab")
			(hide yes)
			(effects
				(font
					(size 1 1)
					(thickness 0.15)
				)
				(justify mirror)
			)
		)
		(property "Voltage" ""
			(at 0 0 90)
			(unlocked yes)
			(layer "B.Fab")
			(hide yes)
			(effects
				(font
					(size 1 1)
					(thickness 0.15)
				)
				(justify mirror)
			)
		)
		(property "Dielectric" ""
			(at 0 0 90)
			(unlocked yes)
			(layer "B.Fab")
			(hide yes)
			(effects
				(font
					(size 1 1)
					(thickness 0.15)
				)
				(justify mirror)
			)
		)
		(sheetname "/Supply/DC-DC VCCINT/")
		(sheetfile "dc-dc-vccint.kicad_sch")
		(attr smd)
		(fp_line
			(start -0.15 -0.4)
			(end 0.15 -0.4)
			(stroke
				(width 0.15)
				(type solid)
			)
			(layer "B.SilkS")
		)
		(fp_line
			(start -0.15 0.4)
			(end 0.15 0.4)
			(stroke
				(width 0.15)
				(type solid)
			)
			(layer "B.SilkS")
		)
		(fp_rect
			(start -1.25 0.65)
			(end 1.25 -0.65)
			(stroke
				(width 0.05)
				(type solid)
			)
			(fill no)
			(layer "B.CrtYd")
		)
		(fp_rect
			(start -0.8 0.4)
			(end 0.8 -0.4)
			(stroke
				(width 0.15)
				(type solid)
			)
			(fill no)
			(layer "B.Fab")
		)
		(fp_text user "License: Apache-2.0"
			(at -1.682 -5.895 270)
			(layer "B.Fab")
			(effects
				(font
					(size 0.7 0.7)
					(thickness 0.15)
				)
				(justify left bottom mirror)
			)
		)
		(fp_text user "${REFERENCE}"
			(at -1.682 -3.895 270)
			(layer "B.Fab")
			(effects
				(font
					(size 0.7 0.7)
					(thickness 0.15)
				)
				(justify left bottom mirror)
			)
		)
		(fp_text user "Author: Antmicro"
			(at -1.682 -4.894 270)
			(layer "B.Fab")
			(effects
				(font
					(size 0.7 0.7)
					(thickness 0.15)
				)
				(justify left bottom mirror)
			)
		)
		(pad "1" smd roundrect
			(at -0.7 0 90)
			(size 0.8 1)
			(layers "B.Cu" "B.Mask" "B.Paste")
			(roundrect_rratio 0.2)
			(net 1 "GND")
			(pintype "passive")
		)
		(pad "2" smd roundrect
			(at 0.7 0 90)
			(size 0.8 1)
			(layers "B.Cu" "B.Mask" "B.Paste")
			(roundrect_rratio 0.2)
			(net 223 "/Supply/DC-DC VCCINT/0V85_REG0")
			(pintype "passive")
		)
	)
	(gr_line
		(start 100 100)
		(end 100 198.25)
		(stroke
			(width 0.12)
			(type solid)
		)
		(layer "Edge.Cuts")
	)
	(gr_line
		(start 100 100)
		(end 265 100)
		(stroke
			(width 0.12)
			(type solid)
		)
		(layer "Edge.Cuts")
	)
	(gr_line
		(start 100 198.25)
		(end 115 198.25)
		(stroke
			(width 0.12)
			(type solid)
		)
		(layer "Edge.Cuts")
	)
	(gr_line
		(start 115 190)
		(end 133.35 190)
		(stroke
			(width 0.12)
			(type solid)
		)
		(layer "Edge.Cuts")
	)
	(gr_line
		(start 115 198.25)
		(end 115 190)
		(stroke
			(width 0.12)
			(type solid)
		)
		(layer "Edge.Cuts")
	)
	(gr_line
		(start 133.35 190)
		(end 133.35 198.25)
		(stroke
			(width 0.12)
			(type solid)
		)
		(layer "Edge.Cuts")
	)
	(gr_line
		(start 133.35 198.25)
		(end 141.35 198.25)
		(stroke
			(width 0.12)
			(type solid)
		)
		(layer "Edge.Cuts")
	)
	(gr_arc
		(start 141.35 191.825)
		(mid 143.175 190)
		(end 145 191.825)
		(stroke
			(width 0.12)
			(type solid)
		)
		(layer "Edge.Cuts")
	)
	(gr_line
		(start 141.35 198.25)
		(end 141.35 191.825)
		(stroke
			(width 0.12)
			(type solid)
		)
		(layer "Edge.Cuts")
	)
	(gr_line
		(start 145 194.3)
		(end 145 191.825)
		(stroke
			(width 0.12)
			(type solid)
		)
		(layer "Edge.Cuts")
	)
	(gr_line
		(start 196.3 189.95)
		(end 196.3 194.3)
		(stroke
			(width 0.12)
			(type solid)
		)
		(layer "Edge.Cuts")
	)
	(gr_line
		(start 264.9973 100)
		(end 265 190)
		(stroke
			(width 0.12)
			(type solid)
		)
		(layer "Edge.Cuts")
	)
	(gr_line
		(start 265 190)
		(end 196.3 189.95)
		(stroke
			(width 0.12)
			(type solid)
		)
		(layer "Edge.Cuts")
	)
	(gr_text "RDIMM DDR5 Tester"
		(at 149.425 123.575003 0)
		(layer "F.Cu")
		(effects
			(font
				(size 0.7 0.7)
				(thickness 0.15)
			)
			(justify left)
		)
	)
	(gr_text "Rev. 2.2.0"
		(at 149.425 124.625001 0)
		(layer "F.Cu")
		(effects
			(font
				(size 0.7 0.7)
				(thickness 0.15)
			)
			(justify left)
		)
	)
	(gr_text "05/2026"
		(at 149.425 125.725 0)
		(layer "F.Cu")
		(effects
			(font
				(size 0.7 0.7)
				(thickness 0.15)
			)
			(justify left)
		)
	)
	(segment
		(start 129.616328 139.632859)
		(end 129.616328 139.072157)
		(width 0.2)
		(layer "F.Cu")
		(net 1)
	)
	(segment
		(start 129.616328 143.002859)
		(end 128.516328 143.002859)
		(width 0.2)
		(layer "F.Cu")
		(net 1)
	)
	(segment
		(start 143.316328 140.167859)
		(end 143.316328 138.972157)
		(width 0.2)
		(layer "F.Cu")
		(net 1)
	)
	(segment
		(start 141.525 139.322851)
		(end 141.525 138.662149)
		(width 0.2)
		(layer "F.Cu")
		(net 1)
	)
	(segment
		(start 182 164)
		(end 181.5005 164.4995)
		(width 0.256)
		(layer "F.Cu")
		(net 1)
	)
	(segment
		(start 157.81 164.614999)
		(end 157.81 165.249999)
		(width 0.256)
		(layer "F.Cu")
		(net 1)
	)
	(segment
		(start 183.9995 160.0005)
		(end 183.5 160.5)
		(width 0.256)
		(layer "F.Cu")
		(net 1)
	)
	(segment
		(start 155.6 106)
		(end 155.6 104.848)
		(width 0.38)
		(layer "F.Cu")
		(net 1)
	)
	(segment
		(start 136.050843 154.300843)
		(end 136.050843 154.096157)
		(width 0.15)
		(layer "F.Cu")
		(net 1)
	)
	(segment
		(start 144.502149 138.607851)
		(end 144.105 139.005)
		(width 0.256)
		(layer "F.Cu")
		(net 1)
	)
	(segment
		(start 124.076 179.477)
		(end 124.326 179.727)
		(width 0.201)
		(layer "F.Cu")
		(net 1)
	)
	(segment
		(start 244.85 110.598)
		(end 244.85 109.446)
		(width 0.38)
		(layer "F.Cu")
		(net 1)
	)
	(segment
		(start 158.31 163.299999)
		(end 159.81 161.799999)
		(width 0.177)
		(layer "F.Cu")
		(net 1)
	)
	(segment
		(start 191.0005 162.0005)
		(end 191.500001 162.5)
		(width 0.256)
		(layer "F.Cu")
		(net 1)
	)
	(segment
		(start 188 153)
		(end 187.5005 153.4995)
		(width 0.256)
		(layer "F.Cu")
		(net 1)
	)
	(segment
		(start 109.324498 149.049)
		(end 110.209499 149.049)
		(width 0.4)
		(layer "F.Cu")
		(net 1)
	)
	(segment
		(start 146.276499 169.884)
		(end 145.859499 169.884)
		(width 0.15)
		(layer "F.Cu")
		(net 1)
	)
	(segment
		(start 178.9995 161.0005)
		(end 178.5 161.5)
		(width 0.256)
		(layer "F.Cu")
		(net 1)
	)
	(segment
		(start 261.375 140.375)
		(end 261.375 139.523)
		(width 0.4)
		(layer "F.Cu")
		(net 1)
	)
	(segment
		(start 248.169499 135.679)
		(end 249.054499 135.679)
		(width 0.201)
		(layer "F.Cu")
		(net 1)
	)
	(segment
		(start 205.752 110.598)
		(end 205.752 109.446)
		(width 0.38)
		(layer "F.Cu")
		(net 1)
	)
	(segment
		(start 190.0005 150.999501)
		(end 190.5 150.5)
		(width 0.256)
		(layer "F.Cu")
		(net 1)
	)
	(segment
		(start 161.31 165.359999)
		(end 161.31 164.614999)
		(width 0.256)
		(layer "F.Cu")
		(net 1)
	)
	(segment
		(start 195.65 196.88)
		(end 195.65 199.25)
		(width 0.22)
		(layer "F.Cu")
		(net 1)
	)
	(segment
		(start 160.81 164.614999)
		(end 160.81 165.519999)
		(width 0.256)
		(layer "F.Cu")
		(net 1)
	)
	(segment
		(start 252.999499 134.674)
		(end 252.999499 135.326)
		(width 0.256)
		(layer "F.Cu")
		(net 1)
	)
	(segment
		(start 190 163)
		(end 190.4995 163.4995)
		(width 0.256)
		(layer "F.Cu")
		(net 1)
	)
	(segment
		(start 191.0005 163.0005)
		(end 191.5 163.5)
		(width 0.256)
		(layer "F.Cu")
		(net 1)
	)
	(segment
		(start 177.9995 160.0005)
		(end 177.5 160.5)
		(width 0.256)
		(layer "F.Cu")
		(net 1)
	)
	(segment
		(start 210.002 106)
		(end 210.002 104.848)
		(width 0.38)
		(layer "F.Cu")
		(net 1)
	)
	(segment
		(start 201 158)
		(end 201.4995 158.4995)
		(width 0.256)
		(layer "F.Cu")
		(net 1)
	)
	(segment
		(start 191.1995 194.849501)
		(end 190.65 195.399001)
		(width 0.22)
		(layer "F.Cu")
		(net 1)
	)
	(segment
		(start 178.9995 163.000499)
		(end 178.5 163.5)
		(width 0.256)
		(layer "F.Cu")
		(net 1)
	)
	(segment
		(start 184.9995 158.0005)
		(end 184.5 158.5)
		(width 0.256)
		(layer "F.Cu")
		(net 1)
	)
	(segment
		(start 176.9995 162.0005)
		(end 176.5 162.5)
		(width 0.256)
		(layer "F.Cu")
		(net 1)
	)
	(segment
		(start 215.95 106)
		(end 215.95 104.848)
		(width 0.38)
		(layer "F.Cu")
		(net 1)
	)
	(segment
		(start 128.402 110.598)
		(end 128.402 109.446)
		(width 0.38)
		(layer "F.Cu")
		(net 1)
	)
	(segment
		(start 148.65 195.9)
		(end 151.45 195.9)
		(width 0.4)
		(layer "F.Cu")
		(net 1)
	)
	(segment
		(start 118.75 117.200499)
		(end 118.75 116.151)
		(width 0.15)
		(layer "F.Cu")
		(net 1)
	)
	(segment
		(start 185.5005 160.4995)
		(end 186 160)
		(width 0.256)
		(layer "F.Cu")
		(net 1)
	)
	(segment
		(start 112.185 152.765)
		(end 112.113 152.765)
		(width 0.4)
		(layer "F.Cu")
		(net 1)
	)
	(segment
		(start 228.5265 161.840501)
		(end 229.542501 161.840501)
		(width 0.4)
		(layer "F.Cu")
		(net 1)
	)
	(segment
		(start 244.001 106)
		(end 244.001 104.848)
		(width 0.38)
		(layer "F.Cu")
		(net 1)
	)
	(segment
		(start 181.9995 158.0005)
		(end 181.5 158.5)
		(width 0.256)
		(layer "F.Cu")
		(net 1)
	)
	(segment
		(start 179.9995 160.0005)
		(end 179.5 160.5)
		(width 0.256)
		(layer "F.Cu")
		(net 1)
	)
	(segment
		(start 142.971843 155.507328)
		(end 142.902672 155.507328)
		(width 0.256)
		(layer "F.Cu")
		(net 1)
	)
	(segment
		(start 194.0005 160.000501)
		(end 194.499999 160.5)
		(width 0.256)
		(layer "F.Cu")
		(net 1)
	)
	(segment
		(start 227.25 163.15)
		(end 226.258999 163.15)
		(width 0.4)
		(layer "F.Cu")
		(net 1)
	)
	(segment
		(start 143.725 145.925)
		(end 143.725 145.391851)
		(width 0.256)
		(layer "F.Cu")
		(net 1)
	)
	(segment
		(start 247.401 106)
		(end 247.401 104.848)
		(width 0.38)
		(layer "F.Cu")
		(net 1)
	)
	(segment
		(start 192.0005 160.0005)
		(end 192.5 160.5)
		(width 0.256)
		(layer "F.Cu")
		(net 1)
	)
	(segment
		(start 165.125 194.874501)
		(end 164.65 195.349501)
		(width 0.22)
		(layer "F.Cu")
		(net 1)
	)
	(segment
		(start 175.9995 158.0005)
		(end 175.5 158.5)
		(width 0.256)
		(layer "F.Cu")
		(net 1)
	)
	(segment
		(start 122.5 181.053)
		(end 122.75 181.303)
		(width 0.201)
		(layer "F.Cu")
		(net 1)
	)
	(segment
		(start 259.774499 145.445)
		(end 259.774499 146.297)
		(width 0.4)
		(layer "F.Cu")
		(net 1)
	)
	(segment
		(start 157.301 106)
		(end 157.301 104.848)
		(width 0.38)
		(layer "F.Cu")
		(net 1)
	)
	(segment
		(start 235.501 110.598)
		(end 235.501 109.446)
		(width 0.38)
		(layer "F.Cu")
		(net 1)
	)
	(segment
		(start 182 165)
		(end 181.5005 165.4995)
		(width 0.256)
		(layer "F.Cu")
		(net 1)
	)
	(segment
		(start 136.124499 178.933)
		(end 136.124499 178.949)
		(width 0.201)
		(layer "F.Cu")
		(net 1)
	)
	(segment
		(start 201 163)
		(end 201.4995 163.4995)
		(width 0.256)
		(layer "F.Cu")
		(net 1)
	)
	(segment
		(start 241.695 123.905)
		(end 241.695 123.918841)
		(width 0.256)
		(layer "F.Cu")
		(net 1)
	)
	(segment
		(start 160.44 165.519999)
		(end 160.81 165.519999)
		(width 0.256)
		(layer "F.Cu")
		(net 1)
	)
	(segment
		(start 177.9995 164.0005)
		(end 177.5 164.5)
		(width 0.256)
		(layer "F.Cu")
		(net 1)
	)
	(segment
		(start 161.81 159.799999)
		(end 159.81 161.799999)
		(width 0.177)
		(layer "F.Cu")
		(net 1)
	)
	(segment
		(start 230.401 106)
		(end 230.401 104.848)
		(width 0.38)
		(layer "F.Cu")
		(net 1)
	)
	(segment
		(start 142.6 145.95)
		(end 142.625 145.925)
		(width 0.256)
		(layer "F.Cu")
		(net 1)
	)
	(segment
		(start 147.525499 169.884)
		(end 147.775499 170.134)
		(width 0.15)
		(layer "F.Cu")
		(net 1)
	)
	(segment
		(start 240.766099 129.356099)
		(end 240.765 129.355)
		(width 0.256)
		(layer "F.Cu")
		(net 1)
	)
	(segment
		(start 134.35 110.598)
		(end 134.35 109.446)
		(width 0.38)
		(layer "F.Cu")
		(net 1)
	)
	(segment
		(start 207.49 154.94)
		(end 207.29 155.14)
		(width 0.201)
		(layer "F.Cu")
		(net 1)
	)
	(segment
		(start 237.902499 187.256)
		(end 237.135499 187.256)
		(width 0.177)
		(layer "F.Cu")
		(net 1)
	)
	(segment
		(start 175.125 194.849501)
		(end 175.65 195.374501)
		(width 0.22)
		(layer "F.Cu")
		(net 1)
	)
	(segment
		(start 194 165)
		(end 193.5005 165.4995)
		(width 0.256)
		(layer "F.Cu")
		(net 1)
	)
	(segment
		(start 142.625 145.925)
		(end 142.625 145.391851)
		(width 0.256)
		(layer "F.Cu")
		(net 1)
	)
	(segment
		(start 251.09 187.404)
		(end 250.615 186.929)
		(width 0.182)
		(layer "F.Cu")
		(net 1)
	)
	(segment
		(start 158.31 164.614999)
		(end 158.31 163.299999)
		(width 0.177)
		(layer "F.Cu")
		(net 1)
	)
	(segment
		(start 241.774499 173.79)
		(end 242.389499 173.79)
		(width 0.256)
		(layer "F.Cu")
		(net 1)
	)
	(segment
		(start 133.815 164.969)
		(end 133.815 165.531)
		(width 0.256)
		(layer "F.Cu")
		(net 1)
	)
	(segment
		(start 186 165)
		(end 185.5005 165.4995)
		(width 0.256)
		(layer "F.Cu")
		(net 1)
	)
	(segment
		(start 187.9995 145.9995)
		(end 187.500001 145.5)
		(width 0.256)
		(layer "F.Cu")
		(net 1)
	)
	(segment
		(start 145.012149 143.407851)
		(end 145.035 143.385)
		(width 0.256)
		(layer "F.Cu")
		(net 1)
	)
	(segment
		(start 256.423998 132.663)
		(end 255.378499 132.663)
		(width 0.182)
		(layer "F.Cu")
		(net 1)
	)
	(segment
		(start 241.541499 155.0615)
		(end 241.774499 154.8285)
		(width 0.256)
		(layer "F.Cu")
		(net 1)
	)
	(segment
		(start 216.801 110.598)
		(end 216.801 109.446)
		(width 0.38)
		(layer "F.Cu")
		(net 1)
	)
	(segment
		(start 187.9995 140.9995)
		(end 187.500001 140.5)
		(width 0.256)
		(layer "F.Cu")
		(net 1)
	)
	(segment
		(start 191.0005 154.0005)
		(end 191.5 154.5)
		(width 0.256)
		(layer "F.Cu")
		(net 1)
	)
	(segment
		(start 118.749499 117.201)
		(end 118.75 117.200499)
		(width 0.15)
		(layer "F.Cu")
		(net 1)
	)
	(segment
		(start 113.917499 179.551)
		(end 114.632499 179.551)
		(width 0.201)
		(layer "F.Cu")
		(net 1)
	)
	(segment
		(start 109.375 178.7695)
		(end 111.11 178.7695)
		(width 0.201)
		(layer "F.Cu")
		(net 1)
	)
	(segment
		(start 181.952 106)
		(end 181.952 104.848)
		(width 0.38)
		(layer "F.Cu")
		(net 1)
	)
	(segment
		(start 240.624499 163.449)
		(end 241.303499 163.449)
		(width 0.256)
		(layer "F.Cu")
		(net 1)
	)
	(segment
		(start 180.9995 155.0005)
		(end 180.5 155.5)
		(width 0.256)
		(layer "F.Cu")
		(net 1)
	)
	(segment
		(start 193.0005 163.0005)
		(end 193.5 163.5)
		(width 0.256)
		(layer "F.Cu")
		(net 1)
	)
	(segment
		(start 193.0005 145.9995)
		(end 193.5 145.5)
		(width 0.256)
		(layer "F.Cu")
		(net 1)
	)
	(segment
		(start 196.000501 163.0005)
		(end 196.5 163.5)
		(width 0.256)
		(layer "F.Cu")
		(net 1)
	)
	(segment
		(start 181.9995 160.0005)
		(end 181.5 160.499999)
		(width 0.256)
		(layer "F.Cu")
		(net 1)
	)
	(segment
		(start 193.0005 162.0005)
		(end 193.5 162.5)
		(width 0.256)
		(layer "F.Cu")
		(net 1)
	)
	(segment
		(start 170.42 159.07)
		(end 170.725 159.375)
		(width 0.256)
		(layer "F.Cu")
		(net 1)
	)
	(segment
		(start 131.802 106)
		(end 131.802 104.848)
		(width 0.38)
		(layer "F.Cu")
		(net 1)
	)
	(segment
		(start 140.79 155.9)
		(end 141.15 155.9)
		(width 0.256)
		(layer "F.Cu")
		(net 1)
	)
	(segment
		(start 155.975001 158.674999)
		(end 155.67 158.674999)
		(width 0.256)
		(layer "F.Cu")
		(net 1)
	)
	(segment
		(start 229.222 142.851)
		(end 227.6 142.851)
		(width 0.4)
		(layer "F.Cu")
		(net 1)
	)
	(segment
		(start 215.101 110.598)
		(end 215.101 109.446)
		(width 0.38)
		(layer "F.Cu")
		(net 1)
	)
	(segment
		(start 132.648 155.522)
		(end 132.648 155.109)
		(width 0.198)
		(layer "F.Cu")
		(net 1)
	)
	(segment
		(start 106.733 147.073)
		(end 106.733 146.965)
		(width 0.2)
		(layer "F.Cu")
		(net 1)
	)
	(segment
		(start 199.0005 148.9995)
		(end 199.5 148.5)
		(width 0.256)
		(layer "F.Cu")
		(net 1)
	)
	(segment
		(start 228.7 106)
		(end 228.7 104.848)
		(width 0.38)
		(layer "F.Cu")
		(net 1)
	)
	(segment
		(start 257.05 182.175)
		(end 255.935 182.175)
		(width 0.4)
		(layer "F.Cu")
		(net 1)
	)
	(segment
		(start 240.738499 155.0615)
		(end 241.541499 155.0615)
		(width 0.256)
		(layer "F.Cu")
		(net 1)
	)
	(segment
		(start 146.474 160.81)
		(end 147.504499 160.81)
		(width 0.15)
		(layer "F.Cu")
		(net 1)
	)
	(segment
		(start 163.251 106)
		(end 163.251 104.848)
		(width 0.38)
		(layer "F.Cu")
		(net 1)
	)
	(segment
		(start 141.525 145.391851)
		(end 141.961851 145.391851)
		(width 0.256)
		(layer "F.Cu")
		(net 1)
	)
	(segment
		(start 135.824499 186.298)
		(end 135.074499 186.298)
		(width 0.201)
		(layer "F.Cu")
		(net 1)
	)
	(segment
		(start 113.736 171.0505)
		(end 113.026 171.0505)
		(width 0.4)
		(layer "F.Cu")
		(net 1)
	)
	(segment
		(start 184.9995 163.0005)
		(end 184.5 163.5)
		(width 0.256)
		(layer "F.Cu")
		(net 1)
	)
	(segment
		(start 126.306 174.912)
		(end 126.306 175.542)
		(width 0.256)
		(layer "F.Cu")
		(net 1)
	)
	(segment
		(start 257.05 187.775)
		(end 255.935 187.775)
		(width 0.4)
		(layer "F.Cu")
		(net 1)
	)
	(segment
		(start 157.81 165.249999)
		(end 158.06 165.499999)
		(width 0.256)
		(layer "F.Cu")
		(net 1)
	)
	(segment
		(start 143.701 110.598)
		(end 143.701 109.446)
		(width 0.38)
		(layer "F.Cu")
		(net 1)
	)
	(segment
		(start 203.2 110.598)
		(end 203.2 109.446)
		(width 0.38)
		(layer "F.Cu")
		(net 1)
	)
	(segment
		(start 123.056 174.4575)
		(end 123.056 173.832)
		(width 0.4)
		(layer "F.Cu")
		(net 1)
	)
	(segment
		(start 252.999499 135.326)
		(end 253.175999 135.5025)
		(width 0.256)
		(layer "F.Cu")
		(net 1)
	)
	(segment
		(start 261.373 132.601499)
		(end 261.372999 133.6235)
		(width 0.4)
		(layer "F.Cu")
		(net 1)
	)
	(segment
		(start 133.815 165.531)
		(end 133.808 165.538)
		(width 0.256)
		(layer "F.Cu")
		(net 1)
	)
	(segment
		(start 246.903 142.099)
		(end 247.904 142.099)
		(width 0.256)
		(layer "F.Cu")
		(net 1)
	)
	(segment
		(start 133.927 146.734)
		(end 133.927 148.073)
		(width 0.256)
		(layer "F.Cu")
		(net 1)
	)
	(segment
		(start 144.054515 155.51)
		(end 145.96 155.51)
		(width 0.256)
		(layer "F.Cu")
		(net 1)
	)
	(segment
		(start 201 162)
		(end 201.4995 162.4995)
		(width 0.256)
		(layer "F.Cu")
		(net 1)
	)
	(segment
		(start 193 110.598)
		(end 193 109.446)
		(width 0.38)
		(layer "F.Cu")
		(net 1)
	)
	(segment
		(start 139.699499 171.633)
		(end 140.333499 171.633)
		(width 0.15)
		(layer "F.Cu")
		(net 1)
	)
	(segment
		(start 222.751 106)
		(end 222.751 104.848)
		(width 0.38)
		(layer "F.Cu")
		(net 1)
	)
	(segment
		(start 179.9995 163.0005)
		(end 179.5 163.5)
		(width 0.256)
		(layer "F.Cu")
		(net 1)
	)
	(segment
		(start 135.174499 169.899)
		(end 134.874499 169.599)
		(width 0.256)
		(layer "F.Cu")
		(net 1)
	)
	(segment
		(start 162.625 159.799999)
		(end 163.51 159.799999)
		(width 0.256)
		(layer "F.Cu")
		(net 1)
	)
	(segment
		(start 237.277501 171.198002)
		(end 237.276998 171.197501)
		(width 0.256)
		(layer "F.Cu")
		(net 1)
	)
	(segment
		(start 134.8135 158.8015)
		(end 134.8135 159.5)
		(width 0.256)
		(layer "F.Cu")
		(net 1)
	)
	(segment
		(start 255.935 182.175)
		(end 255.93 182.17)
		(width 0.4)
		(layer "F.Cu")
		(net 1)
	)
	(segment
		(start 249.054499 135.679)
		(end 249.174499 135.799)
		(width 0.201)
		(layer "F.Cu")
		(net 1)
	)
	(segment
		(start 170.42 158.43)
		(end 170.42 159.07)
		(width 0.256)
		(layer "F.Cu")
		(net 1)
	)
	(segment
		(start 105.545 152.685)
		(end 105.216 153.014)
		(width 0.4)
		(layer "F.Cu")
		(net 1)
	)
	(segment
		(start 139.425499 186.298)
		(end 138.675499 186.298)
		(width 0.201)
		(layer "F.Cu")
		(net 1)
	)
	(segment
		(start 229.222 150.85)
		(end 227.6 150.849999)
		(width 0.4)
		(layer "F.Cu")
		(net 1)
	)
	(segment
		(start 196 165)
		(end 195.5005 165.4995)
		(width 0.256)
		(layer "F.Cu")
		(net 1)
	)
	(segment
		(start 160.1 156.125)
		(end 159.95 155.975)
		(width 0.256)
		(layer "F.Cu")
		(net 1)
	)
	(segment
		(start 209.15 110.598)
		(end 209.15 109.446)
		(width 0.38)
		(layer "F.Cu")
		(net 1)
	)
	(segment
		(start 200.500001 156.5)
		(end 200.0005 156.0005)
		(width 0.256)
		(layer "F.Cu")
		(net 1)
	)
	(segment
		(start 261.372999 133.6235)
		(end 261.374498 133.625)
		(width 0.4)
		(layer "F.Cu")
		(net 1)
	)
	(segment
		(start 237.849499 176.748)
		(end 237.277501 176.748002)
		(width 0.256)
		(layer "F.Cu")
		(net 1)
	)
	(segment
		(start 168.35 110.598)
		(end 168.35 109.446)
		(width 0.38)
		(layer "F.Cu")
		(net 1)
	)
	(segment
		(start 199.4995 161.5005)
		(end 199 162)
		(width 0.256)
		(layer "F.Cu")
		(net 1)
	)
	(segment
		(start 170.051 110.598)
		(end 170.051 109.446)
		(width 0.38)
		(layer "F.Cu")
		(net 1)
	)
	(segment
		(start 142.625 145.391851)
		(end 143.725 145.391851)
		(width 0.256)
		(layer "F.Cu")
		(net 1)
	)
	(segment
		(start 251.117123 185.699)
		(end 251.085744 185.667621)
		(width 0.182)
		(layer "F.Cu")
		(net 1)
	)
	(segment
		(start 174.3 110.598)
		(end 174.3 109.446)
		(width 0.38)
		(layer "F.Cu")
		(net 1)
	)
	(segment
		(start 185.125 194.849501)
		(end 185.65 195.374501)
		(width 0.22)
		(layer "F.Cu")
		(net 1)
	)
	(segment
		(start 109.375 180.2695)
		(end 111.11 180.2695)
		(width 0.201)
		(layer "F.Cu")
		(net 1)
	)
	(segment
		(start 246.551 110.598)
		(end 246.551 109.446)
		(width 0.38)
		(layer "F.Cu")
		(net 1)
	)
	(segment
		(start 176.9995 153.0005)
		(end 176.5 153.5)
		(width 0.256)
		(layer "F.Cu")
		(net 1)
	)
	(segment
		(start 149.075843 165.716328)
		(end 149.075843 166.321329)
		(width 0.256)
		(layer "F.Cu")
		(net 1)
	)
	(segment
		(start 250.615 186.929)
		(end 249.8 186.929)
		(width 0.182)
		(layer "F.Cu")
		(net 1)
	)
	(segment
		(start 254.525 183.475)
		(end 255.64 183.475)
		(width 0.4)
		(layer "F.Cu")
		(net 1)
	)
	(segment
		(start 113.026 170.3235)
		(end 113.026 171.0505)
		(width 0.4)
		(layer "F.Cu")
		(net 1)
	)
	(segment
		(start 134.8135 164.968)
		(end 134.8135 165.5175)
		(width 0.256)
		(layer "F.Cu")
		(net 1)
	)
	(segment
		(start 237.2 110.598)
		(end 237.2 109.446)
		(width 0.38)
		(layer "F.Cu")
		(net 1)
	)
	(segment
		(start 193.851 106)
		(end 193.851 104.848)
		(width 0.38)
		(layer "F.Cu")
		(net 1)
	)
	(segment
		(start 177.701 110.598)
		(end 177.701 109.446)
		(width 0.38)
		(layer "F.Cu")
		(net 1)
	)
	(segment
		(start 188 164)
		(end 187.5 163.5)
		(width 0.256)
		(layer "F.Cu")
		(net 1)
	)
	(segment
		(start 142.49975 148.7445)
		(end 142.509 148.73525)
		(width 0.256)
		(layer "F.Cu")
		(net 1)
	)
	(segment
		(start 195.551 106)
		(end 195.551 104.848)
		(width 0.38)
		(layer "F.Cu")
		(net 1)
	)
	(segment
		(start 112.466 175.7685)
		(end 113.145499 175.7685)
		(width 0.201)
		(layer "F.Cu")
		(net 1)
	)
	(segment
		(start 251.377998 129.049)
		(end 251.487998 128.939)
		(width 0.4)
		(layer "F.Cu")
		(net 1)
	)
	(segment
		(start 145.624 142.824)
		(end 145.635 142.835)
		(width 0.256)
		(layer "F.Cu")
		(net 1)
	)
	(segment
		(start 248.773499 144.4)
		(end 249.223499 143.95)
		(width 0.177)
		(layer "F.Cu")
		(net 1)
	)
	(segment
		(start 140.333499 171.633)
		(end 140.349499 171.649)
		(width 0.15)
		(layer "F.Cu")
		(net 1)
	)
	(segment
		(start 165.101 154.499)
		(end 164.6 155)
		(width 0.4)
		(layer "F.Cu")
		(net 1)
	)
	(segment
		(start 187.9995 148.999501)
		(end 187.5 148.5)
		(width 0.256)
		(layer "F.Cu")
		(net 1)
	)
	(segment
		(start 182.9995 162.000501)
		(end 182.5 162.5)
		(width 0.256)
		(layer "F.Cu")
		(net 1)
	)
	(segment
		(start 148.2755 168.884)
		(end 148.275499 168.034)
		(width 0.15)
		(layer "F.Cu")
		(net 1)
	)
	(segment
		(start 169.202 106)
		(end 169.202 104.848)
		(width 0.38)
		(layer "F.Cu")
		(net 1)
	)
	(segment
		(start 166.65 106)
		(end 166.65 104.848)
		(width 0.38)
		(layer "F.Cu")
		(net 1)
	)
	(segment
		(start 115.4 158.277)
		(end 114.738 157.615)
		(width 0.256)
		(layer "F.Cu")
		(net 1)
	)
	(segment
		(start 197.000499 163.0005)
		(end 197.5 163.5)
		(width 0.256)
		(layer "F.Cu")
		(net 1)
	)
	(segment
		(start 172.65 195.399001)
		(end 172.65 199.25)
		(width 0.22)
		(layer "F.Cu")
		(net 1)
	)
	(segment
		(start 198.95 106)
		(end 198.95 104.848)
		(width 0.38)
		(layer "F.Cu")
		(net 1)
	)
	(segment
		(start 111.11 180.2695)
		(end 111.111 180.2685)
		(width 0.201)
		(layer "F.Cu")
		(net 1)
	)
	(segment
		(start 229.222 144.851)
		(end 227.6 144.851)
		(width 0.4)
		(layer "F.Cu")
		(net 1)
	)
	(segment
		(start 247.904 141.101)
		(end 248.301 141.101)
		(width 0.177)
		(layer "F.Cu")
		(net 1)
	)
	(segment
		(start 136.675499 186.298)
		(end 136.624499 186.349)
		(width 0.201)
		(layer "F.Cu")
		(net 1)
	)
	(segment
		(start 242.389499 168.23)
		(end 242.399499 168.24)
		(width 0.256)
		(layer "F.Cu")
		(net 1)
	)
	(segment
		(start 145.724499 169.599)
		(end 145.924499 169.399)
		(width 0.15)
		(layer "F.Cu")
		(net 1)
	)
	(segment
		(start 248.55 146.65)
		(end 247.9975 146.0975)
		(width 0.177)
		(layer "F.Cu")
		(net 1)
	)
	(segment
		(start 160.81 165.519999)
		(end 161.15 165.519999)
		(width 0.256)
		(layer "F.Cu")
		(net 1)
	)
	(segment
		(start 239.524499 153.8475)
		(end 239.524499 155.0585)
		(width 0.256)
		(layer "F.Cu")
		(net 1)
	)
	(segment
		(start 158.31 164.614999)
		(end 158.31 165.249999)
		(width 0.256)
		(layer "F.Cu")
		(net 1)
	)
	(segment
		(start 247.904 145.096)
		(end 248.6 144.4)
		(width 0.177)
		(layer "F.Cu")
		(net 1)
	)
	(segment
		(start 226.258999 163.15)
		(end 226.2495 163.140501)
		(width 0.4)
		(layer "F.Cu")
		(net 1)
	)
	(segment
		(start 177.9995 158.0005)
		(end 177.5 158.5)
		(width 0.256)
		(layer "F.Cu")
		(net 1)
	)
	(segment
		(start 164.94 160.674999)
		(end 164.94 160.049999)
		(width 0.256)
		(layer "F.Cu")
		(net 1)
	)
	(segment
		(start 207.45 110.598)
		(end 207.45 109.446)
		(width 0.38)
		(layer "F.Cu")
		(net 1)
	)
	(segment
		(start 175.9995 161.0005)
		(end 175.5 161.5)
		(width 0.256)
		(layer "F.Cu")
		(net 1)
	)
	(segment
		(start 231.251 110.598)
		(end 231.251 109.446)
		(width 0.38)
		(layer "F.Cu")
		(net 1)
	)
	(segment
		(start 243.458998 131.84)
		(end 242.98 131.84)
		(width 0.4)
		(layer "F.Cu")
		(net 1)
	)
	(segment
		(start 177.9995 161.0005)
		(end 177.5 161.5)
		(width 0.256)
		(layer "F.Cu")
		(net 1)
	)
	(segment
		(start 194.0005 158.0005)
		(end 194.5 158.5)
		(width 0.256)
		(layer "F.Cu")
		(net 1)
	)
	(segment
		(start 167.65 195.374501)
		(end 167.65 199.25)
		(width 0.22)
		(layer "F.Cu")
		(net 1)
	)
	(segment
		(start 184.999501 151.9995)
		(end 184.5 151.5)
		(width 0.256)
		(layer "F.Cu")
		(net 1)
	)
	(segment
		(start 120.77 164.48)
		(end 120.75 164.5)
		(width 0.1)
		(layer "F.Cu")
		(net 1)
	)
	(segment
		(start 160.31 164.614999)
		(end 160.31 165.389999)
		(width 0.256)
		(layer "F.Cu")
		(net 1)
	)
	(segment
		(start 199.8 110.598)
		(end 199.8 109.446)
		(width 0.38)
		(layer "F.Cu")
		(net 1)
	)
	(segment
		(start 109.309499 145.796)
		(end 109.93 145.796)
		(width 0.201)
		(layer "F.Cu")
		(net 1)
	)
	(segment
		(start 150.934499 168.633)
		(end 150.950499 168.649)
		(width 0.15)
		(layer "F.Cu")
		(net 1)
	)
	(segment
		(start 186 164)
		(end 185.5005 164.4995)
		(width 0.256)
		(layer "F.Cu")
		(net 1)
	)
	(segment
		(start 144.051843 155.507328)
		(end 144.054515 155.51)
		(width 0.256)
		(layer "F.Cu")
		(net 1)
	)
	(segment
		(start 227.85 110.598)
		(end 227.85 109.446)
		(width 0.38)
		(layer "F.Cu")
		(net 1)
	)
	(segment
		(start 149.076843 162.216328)
		(end 149.076843 161.611328)
		(width 0.256)
		(layer "F.Cu")
		(net 1)
	)
	(segment
		(start 141.024499 169.533)
		(end 140.940499 169.533)
		(width 0.256)
		(layer "F.Cu")
		(net 1)
	)
	(segment
		(start 198.499501 160.4995)
		(end 198 160)
		(width 0.256)
		(layer "F.Cu")
		(net 1)
	)
	(segment
		(start 239.274499 175.75)
		(end 239.274499 176.425501)
		(width 0.177)
		(layer "F.Cu")
		(net 1)
	)
	(segment
		(start 190.0005 158.0005)
		(end 190.5 158.5)
		(width 0.256)
		(layer "F.Cu")
		(net 1)
	)
	(segment
		(start 124.756 187.0675)
		(end 124.756 187.702)
		(width 0.256)
		(layer "F.Cu")
		(net 1)
	)
	(segment
		(start 133.691843 161.831328)
		(end 133.006843 161.831328)
		(width 0.256)
		(layer "F.Cu")
		(net 1)
	)
	(segment
		(start 112.037258 170.3535)
		(end 112.037258 171.0485)
		(width 0.4)
		(layer "F.Cu")
		(net 1)
	)
	(segment
		(start 175.15 106)
		(end 175.15 104.848)
		(width 0.38)
		(layer "F.Cu")
		(net 1)
	)
	(segment
		(start 147.199 179.101)
		(end 147.199 178.501)
		(width 0.198)
		(layer "F.Cu")
		(net 1)
	)
	(segment
		(start 241.303499 163.449)
		(end 241.774499 163.92)
		(width 0.256)
		(layer "F.Cu")
		(net 1)
	)
	(segment
		(start 167.125 194.849501)
		(end 167.65 195.374501)
		(width 0.22)
		(layer "F.Cu")
		(net 1)
	)
	(segment
		(start 193.65 195.374501)
		(end 193.65 199.25)
		(width 0.22)
		(layer "F.Cu")
		(net 1)
	)
	(segment
		(start 180.9995 144.9995)
		(end 180.5 144.5)
		(width 0.256)
		(layer "F.Cu")
		(net 1)
	)
	(segment
		(start 109.273499 140.6)
		(end 109.273499 139.999)
		(width 0.4)
		(layer "F.Cu")
		(net 1)
	)
	(segment
		(start 237.135499 187.256)
		(end 237.129499 187.262)
		(width 0.177)
		(layer "F.Cu")
		(net 1)
	)
	(segment
		(start 123.576 182.917)
		(end 123.538 182.879)
		(width 0.201)
		(layer "F.Cu")
		(net 1)
	)
	(segment
		(start 197.5 158.5)
		(end 197.000499 158.0005)
		(width 0.256)
		(layer "F.Cu")
		(net 1)
	)
	(segment
		(start 196.5 158.5)
		(end 196.000501 158.0005)
		(width 0.256)
		(layer "F.Cu")
		(net 1)
	)
	(segment
		(start 184.999501 141.9995)
		(end 184.5 141.5)
		(width 0.256)
		(layer "F.Cu")
		(net 1)
	)
	(segment
		(start 130.008 173.113)
		(end 130.758 172.363)
		(width 0.201)
		(layer "F.Cu")
		(net 1)
	)
	(segment
		(start 176.002 110.598)
		(end 176.002 109.446)
		(width 0.38)
		(layer "F.Cu")
		(net 1)
	)
	(segment
		(start 217.899 150.595)
		(end 216.913501 150.595)
		(width 0.256)
		(layer "F.Cu")
		(net 1)
	)
	(segment
		(start 129.307 172.612)
		(end 128.706 172.612)
		(width 0.201)
		(layer "F.Cu")
		(net 1)
	)
	(segment
		(start 233.801 110.598)
		(end 233.801 109.446)
		(width 0.38)
		(layer "F.Cu")
		(net 1)
	)
	(segment
		(start 175.9995 164.0005)
		(end 175.5 164.5)
		(width 0.256)
		(layer "F.Cu")
		(net 1)
	)
	(segment
		(start 192.000499 158.0005)
		(end 192.5 158.5)
		(width 0.256)
		(layer "F.Cu")
		(net 1)
	)
	(segment
		(start 239.524499 153.8475)
		(end 239.524499 153.275501)
		(width 0.256)
		(layer "F.Cu")
		(net 1)
	)
	(segment
		(start 255.935 187.775)
		(end 255.93 187.77)
		(width 0.4)
		(layer "F.Cu")
		(net 1)
	)
	(segment
		(start 179.9995 164.0005)
		(end 179.5 164.5)
		(width 0.256)
		(layer "F.Cu")
		(net 1)
	)
	(segment
		(start 139.020499 181.447)
		(end 139.020499 181.645)
		(width 0.201)
		(layer "F.Cu")
		(net 1)
	)
	(segment
		(start 241.775 154.827999)
		(end 241.774499 154.8285)
		(width 0.4)
		(layer "F.Cu")
		(net 1)
	)
	(segment
		(start 127.552 106)
		(end 127.552 104.848)
		(width 0.38)
		(layer "F.Cu")
		(net 1)
	)
	(segment
		(start 162.625 162.299999)
		(end 163.67 162.299999)
		(width 0.256)
		(layer "F.Cu")
		(net 1)
	)
	(segment
		(start 146.276499 169.884)
		(end 147.525499 169.884)
		(width 0.15)
		(layer "F.Cu")
		(net 1)
	)
	(segment
		(start 150.901 183.749)
		(end 150.9 183.75)
		(width 0.1)
		(layer "F.Cu")
		(net 1)
	)
	(segment
		(start 124.076 177.828)
		(end 124.076 179.477)
		(width 0.201)
		(layer "F.Cu")
		(net 1)
	)
	(segment
		(start 198.0005 145.9995)
		(end 198.5 145.5)
		(width 0.256)
		(layer "F.Cu")
		(net 1)
	)
	(segment
		(start 145.638515 160.083)
		(end 146.238 160.083)
		(width 0.15)
		(layer "F.Cu")
		(net 1)
	)
	(segment
		(start 229.222 140.852)
		(end 227.6 140.852)
		(width 0.4)
		(layer "F.Cu")
		(net 1)
	)
	(segment
		(start 157.202276 155.095638)
		(end 156.511138 155.786776)
		(width 0.256)
		(layer "F.Cu")
		(net 1)
	)
	(segment
		(start 173.1995 194.849501)
		(end 172.65 195.399001)
		(width 0.22)
		(layer "F.Cu")
		(net 1)
	)
	(segment
		(start 185.9995 139.9995)
		(end 185.5 139.5)
		(width 0.256)
		(layer "F.Cu")
		(net 1)
	)
	(segment
		(start 113.847537 168.265)
		(end 112.113 168.265)
		(width 0.4)
		(layer "F.Cu")
		(net 1)
	)
	(segment
		(start 147.504499 164.51)
		(end 147.343499 164.51)
		(width 0.15)
		(layer "F.Cu")
		(net 1)
	)
	(segment
		(start 140.302 110.598)
		(end 140.302 109.446)
		(width 0.38)
		(layer "F.Cu")
		(net 1)
	)
	(segment
		(start 177.9995 150.9995)
		(end 177.5 150.5)
		(width 0.256)
		(layer "F.Cu")
		(net 1)
	)
	(segment
		(start 256.338998 140.25)
		(end 255.292499 140.25)
		(width 0.198)
		(layer "F.Cu")
		(net 1)
	)
	(segment
		(start 259.774499 141.347)
		(end 259.774499 142.199)
		(width 0.4)
		(layer "F.Cu")
		(net 1)
	)
	(segment
		(start 141.5 145.95)
		(end 141.525 145.925)
		(width 0.256)
		(layer "F.Cu")
		(net 1)
	)
	(segment
		(start 146.45 160.834)
		(end 146.474 160.81)
		(width 0.15)
		(layer "F.Cu")
		(net 1)
	)
	(segment
		(start 121.7 117.15)
		(end 121.7 116.487461)
		(width 0.15)
		(layer "F.Cu")
		(net 1)
	)
	(segment
		(start 114.755499 139.549)
		(end 110.773499 139.549)
		(width 0.4)
		(layer "F.Cu")
		(net 1)
	)
	(segment
		(start 190.65 195.399001)
		(end 190.65 199.25)
		(width 0.22)
		(layer "F.Cu")
		(net 1)
	)
	(segment
		(start 242.389499 173.79)
		(end 242.399499 173.8)
		(width 0.256)
		(layer "F.Cu")
		(net 1)
	)
	(segment
		(start 261.373 128.503499)
		(end 261.372999 127.481498)
		(width 0.4)
		(layer "F.Cu")
		(net 1)
	)
	(segment
		(start 115.75 117.1)
		(end 115.75 116.151)
		(width 0.15)
		(layer "F.Cu")
		(net 1)
	)
	(segment
		(start 120.851 181.053)
		(end 122.5 181.053)
		(width 0.201)
		(layer "F.Cu")
		(net 1)
	)
	(segment
		(start 171.751 110.598)
		(end 171.751 109.446)
		(width 0.38)
		(layer "F.Cu")
		(net 1)
	)
	(segment
		(start 249.218499 133.044)
		(end 249.073499 132.899)
		(width 0.256)
		(layer "F.Cu")
		(net 1)
	)
	(segment
		(start 248.301 141.101)
		(end 248.45 141.25)
		(width 0.177)
		(layer "F.Cu")
		(net 1)
	)
	(segment
		(start 143.933 158.2825)
		(end 143.661 158.0105)
		(width 0.15)
		(layer "F.Cu")
		(net 1)
	)
	(segment
		(start 181.9995 153.0005)
		(end 181.5 153.5)
		(width 0.256)
		(layer "F.Cu")
		(net 1)
	)
	(segment
		(start 125.85 106)
		(end 125.85 104.848)
		(width 0.38)
		(layer "F.Cu")
		(net 1)
	)
	(segment
		(start 257.8 138.126)
		(end 257.8 137.7)
		(width 0.4)
		(layer "F.Cu")
		(net 1)
	)
	(segment
		(start 179.9995 165.0005)
		(end 179.5 165.5)
		(width 0.256)
		(layer "F.Cu")
		(net 1)
	)
	(segment
		(start 178.1025 194.849501)
		(end 178.65 195.397001)
		(width 0.22)
		(layer "F.Cu")
		(net 1)
	)
	(segment
		(start 192.0005 155.0005)
		(end 192.5 155.5)
		(width 0.256)
		(layer "F.Cu")
		(net 1)
	)
	(segment
		(start 187.999499 158.0005)
		(end 187.5 158.5)
		(width 0.256)
		(layer "F.Cu")
		(net 1)
	)
	(segment
		(start 141.525 145.391851)
		(end 142.625 145.391851)
		(width 0.256)
		(layer "F.Cu")
		(net 1)
	)
	(segment
		(start 142.625 145.391851)
		(end 142.198149 145.391851)
		(width 0.256)
		(layer "F.Cu")
		(net 1)
	)
	(segment
		(start 160.81 162.799999)
		(end 159.81 161.799999)
		(width 0.177)
		(layer "F.Cu")
		(net 1)
	)
	(segment
		(start 159.001 110.598)
		(end 159.001 109.446)
		(width 0.38)
		(layer "F.Cu")
		(net 1)
	)
	(segment
		(start 162.625 159.799999)
		(end 161.81 159.799999)
		(width 0.177)
		(layer "F.Cu")
		(net 1)
	)
	(segment
		(start 167.1 150.5)
		(end 166.6 150)
		(width 0.4)
		(layer "F.Cu")
		(net 1)
	)
	(segment
		(start 158.31 158.984999)
		(end 158.31 158.1)
		(width 0.256)
		(layer "F.Cu")
		(net 1)
	)
	(segment
		(start 219.351 106)
		(end 219.351 104.848)
		(width 0.38)
		(layer "F.Cu")
		(net 1)
	)
	(segment
		(start 183.9995 148.9995)
		(end 183.5 148.5)
		(width 0.256)
		(layer "F.Cu")
		(net 1)
	)
	(segment
		(start 248.234499 132.899)
		(end 248.169499 132.834)
		(width 0.256)
		(layer "F.Cu")
		(net 1)
	)
	(segment
		(start 176.9995 147.9995)
		(end 176.5 147.499999)
		(width 0.256)
		(layer "F.Cu")
		(net 1)
	)
	(segment
		(start 114.773499 139.567)
		(end 114.773499 140.1)
		(width 0.4)
		(layer "F.Cu")
		(net 1)
	)
	(segment
		(start 223.49 181.215)
		(end 222.745001 181.215)
		(width 0.4)
		(layer "F.Cu")
		(net 1)
	)
	(segment
		(start 109.273499 139.999)
		(end 109.723499 139.549)
		(width 0.4)
		(layer "F.Cu")
		(net 1)
	)
	(segment
		(start 248.6 144.4)
		(end 248.773499 144.4)
		(width 0.177)
		(layer "F.Cu")
		(net 1)
	)
	(segment
		(start 192.0005 148.999501)
		(end 192.5 148.5)
		(width 0.256)
		(layer "F.Cu")
		(net 1)
	)
	(segment
		(start 134.811 158.799)
		(end 134.8135 158.8015)
		(width 0.256)
		(layer "F.Cu")
		(net 1)
	)
	(segment
		(start 185.9995 155.0005)
		(end 185.500001 155.5)
		(width 0.256)
		(layer "F.Cu")
		(net 1)
	)
	(segment
		(start 189.000501 156.0005)
		(end 189.5 156.5)
		(width 0.256)
		(layer "F.Cu")
		(net 1)
	)
	(segment
		(start 201 161)
		(end 201.4995 161.4995)
		(width 0.256)
		(layer "F.Cu")
		(net 1)
	)
	(segment
		(start 189.0005 162.0005)
		(end 189.5 162.5)
		(width 0.256)
		(layer "F.Cu")
		(net 1)
	)
	(segment
		(start 183.9995 158.0005)
		(end 183.5 158.5)
		(width 0.256)
		(layer "F.Cu")
		(net 1)
	)
	(segment
		(start 197.000499 153.0005)
		(end 197.5 153.5)
		(width 0.256)
		(layer "F.Cu")
		(net 1)
	)
	(segment
		(start 159.95 155.972947)
		(end 159.409568 155.432515)
		(width 0.256)
		(layer "F.Cu")
		(net 1)
	)
	(segment
		(start 201.0005 149.999499)
		(end 201.5 149.5)
		(width 0.256)
		(layer "F.Cu")
		(net 1)
	)
	(segment
		(start 223.51 181.235)
		(end 223.49 181.215)
		(width 0.4)
		(layer "F.Cu")
		(net 1)
	)
	(segment
		(start 152.201 106)
		(end 152.201 104.848)
		(width 0.38)
		(layer "F.Cu")
		(net 1)
	)
	(segment
		(start 197.251 106)
		(end 197.251 104.848)
		(width 0.38)
		(layer "F.Cu")
		(net 1)
	)
	(segment
		(start 109.309499 141.734)
		(end 109.824499 142.249)
		(width 0.15)
		(layer "F.Cu")
		(net 1)
	)
	(segment
		(start 255.292499 140.25)
		(end 255.239499 140.303)
		(width 0.198)
		(layer "F.Cu")
		(net 1)
	)
	(segment
		(start 226.151 110.598)
		(end 226.151 109.446)
		(width 0.38)
		(layer "F.Cu")
		(net 1)
	)
	(segment
		(start 135.525499 169.899)
		(end 136.774499 169.899)
		(width 0.256)
		(layer "F.Cu")
		(net 1)
	)
	(segment
		(start 109.211499 143.749)
		(end 109.824499 143.749)
		(width 0.201)
		(layer "F.Cu")
		(net 1)
	)
	(segment
		(start 159.85 106)
		(end 159.85 104.848)
		(width 0.38)
		(layer "F.Cu")
		(net 1)
	)
	(segment
		(start 248.079499 135.614)
		(end 248.144499 135.679)
		(width 0.256)
		(layer "F.Cu")
		(net 1)
	)
	(segment
		(start 247.9975 146.0975)
		(end 247.1245 146.0975)
		(width 0.177)
		(layer "F.Cu")
		(net 1)
	)
	(segment
		(start 255.64 183.475)
		(end 255.645 183.48)
		(width 0.4)
		(layer "F.Cu")
		(net 1)
	)
	(segment
		(start 159.65 195.374501)
		(end 159.65 199.25)
		(width 0.22)
		(layer "F.Cu")
		(net 1)
	)
	(segment
		(start 186.9995 162.0005)
		(end 186.5 162.5)
		(width 0.256)
		(layer "F.Cu")
		(net 1)
	)
	(segment
		(start 198.5 157.5)
		(end 198.0005 157.0005)
		(width 0.256)
		(layer "F.Cu")
		(net 1)
	)
	(segment
		(start 239.524499 153.275501)
		(end 239.525 153.275)
		(width 0.256)
		(layer "F.Cu")
		(net 1)
	)
	(segment
		(start 240.781 146.099)
		(end 240.7795 146.1005)
		(width 0.4)
		(layer "F.Cu")
		(net 1)
	)
	(segment
		(start 235.57 131.361001)
		(end 235.57 131.84)
		(width 0.4)
		(layer "F.Cu")
		(net 1)
	)
	(segment
		(start 194.0005 143.9995)
		(end 194.5 143.5)
		(width 0.256)
		(layer "F.Cu")
		(net 1)
	)
	(segment
		(start 178.9995 143.9995)
		(end 178.5 143.5)
		(width 0.256)
		(layer "F.Cu")
		(net 1)
	)
	(segment
		(start 235.57 131.361001)
		(end 235.57 131.84)
		(width 0.4)
		(layer "F.Cu")
		(net 1)
	)
	(segment
		(start 187.9995 160.0005)
		(end 187.5 160.5)
		(width 0.256)
		(layer "F.Cu")
		(net 1)
	)
	(segment
		(start 160.31 165.389999)
		(end 160.44 165.519999)
		(width 0.256)
		(layer "F.Cu")
		(net 1)
	)
	(segment
		(start 159.95 155.975)
		(end 159.95 155.972947)
		(width 0.256)
		(layer "F.Cu")
		(net 1)
	)
	(segment
		(start 131.246 170.552)
		(end 130.656 170.552)
		(width 0.201)
		(layer "F.Cu")
		(net 1)
	)
	(segment
		(start 145.624 141.956851)
		(end 145.624 142.824)
		(width 0.256)
		(layer "F.Cu")
		(net 1)
	)
	(segment
		(start 207.2905 152.1)
		(end 207.2905 151.4595)
		(width 0.4)
		(layer "F.Cu")
		(net 1)
	)
	(segment
		(start 114.738 157.615)
		(end 113.164 157.615)
		(width 0.256)
		(layer "F.Cu")
		(net 1)
	)
	(segment
		(start 152.15 179.75)
		(end 152.25 179.75)
		(width 0.198)
		(layer "F.Cu")
		(net 1)
	)
	(segment
		(start 235 167.251)
		(end 235 166.7)
		(width 0.4)
		(layer "F.Cu")
		(net 1)
	)
	(segment
		(start 109.375 175.7685)
		(end 111.11 175.7685)
		(width 0.201)
		(layer "F.Cu")
		(net 1)
	)
	(segment
		(start 201.0005 155.0005)
		(end 201.5 155.5)
		(width 0.256)
		(layer "F.Cu")
		(net 1)
	)
	(segment
		(start 178.65 195.397001)
		(end 178.65 199.25)
		(width 0.22)
		(layer "F.Cu")
		(net 1)
	)
	(segment
		(start 189.0005 154.0005)
		(end 189.5 154.5)
		(width 0.256)
		(layer "F.Cu")
		(net 1)
	)
	(segment
		(start 245.7 106)
		(end 245.7 104.848)
		(width 0.38)
		(layer "F.Cu")
		(net 1)
	)
	(segment
		(start 190 164)
		(end 189.5005 164.4995)
		(width 0.256)
		(layer "F.Cu")
		(net 1)
	)
	(segment
		(start 113.25 151.7)
		(end 112.185 152.765)
		(width 0.4)
		(layer "F.Cu")
		(net 1)
	)
	(segment
		(start 113.917499 175.867)
		(end 114.586 175.867)
		(width 0.201)
		(layer "F.Cu")
		(net 1)
	)
	(segment
		(start 248.169499 132.834)
		(end 247.414499 132.834)
		(width 0.256)
		(layer "F.Cu")
		(net 1)
	)
	(segment
		(start 154.75 110.598)
		(end 154.75 109.446)
		(width 0.38)
		(layer "F.Cu")
		(net 1)
	)
	(segment
		(start 192.0005 150.9995)
		(end 192.5 150.5)
		(width 0.256)
		(layer "F.Cu")
		(net 1)
	)
	(segment
		(start 241.774499 180.865)
		(end 241.140499 180.865)
		(width 0.256)
		(layer "F.Cu")
		(net 1)
	)
	(segment
		(start 137.425499 186.298)
		(end 136.675499 186.298)
		(width 0.201)
		(layer "F.Cu")
		(net 1)
	)
	(segment
		(start 195.0005 163.0005)
		(end 195.5 163.5)
		(width 0.256)
		(layer "F.Cu")
		(net 1)
	)
	(segment
		(start 109.375 183.2695)
		(end 111.11 183.2695)
		(width 0.201)
		(layer "F.Cu")
		(net 1)
	)
	(segment
		(start 129.307 172.113)
		(end 128.506 172.113)
		(width 0.201)
		(layer "F.Cu")
		(net 1)
	)
	(segment
		(start 153.902 106)
		(end 153.902 104.848)
		(width 0.38)
		(layer "F.Cu")
		(net 1)
	)
	(segment
		(start 252.943 181.575)
		(end 252.92 181.598)
		(width 0.256)
		(layer "F.Cu")
		(net 1)
	)
	(segment
		(start 141.025499 186.298)
		(end 140.275499 186.298)
		(width 0.201)
		(layer "F.Cu")
		(net 1)
	)
	(segment
		(start 176.999499 142.9995)
		(end 176.5 142.500001)
		(width 0.256)
		(layer "F.Cu")
		(net 1)
	)
	(segment
		(start 239.751 106)
		(end 239.751 107.152)
		(width 0.38)
		(layer "F.Cu")
		(net 1)
	)
	(segment
		(start 191.0005 139.9995)
		(end 191.5 139.5)
		(width 0.256)
		(layer "F.Cu")
		(net 1)
	)
	(segment
		(start 249.073499 132.899)
		(end 248.234499 132.899)
		(width 0.256)
		(layer "F.Cu")
		(net 1)
	)
	(segment
		(start 229.222 148.85)
		(end 227.6 148.85)
		(width 0.4)
		(layer "F.Cu")
		(net 1)
	)
	(segment
		(start 141.15 106)
		(end 141.15 104.848)
		(width 0.38)
		(layer "F.Cu")
		(net 1)
	)
	(segment
		(start 137.746 164.084)
		(end 136.945 164.084)
		(width 0.15)
		(layer "F.Cu")
		(net 1)
	)
	(segment
		(start 253.55 181.575)
		(end 252.943 181.575)
		(width 0.256)
		(layer "F.Cu")
		(net 1)
	)
	(segment
		(start 137.184328 155.219672)
		(end 137.184328 155.512157)
		(width 0.256)
		(layer "F.Cu")
		(net 1)
	)
	(segment
		(start 133.815 159.501)
		(end 133.815 159.058499)
		(width 0.256)
		(layer "F.Cu")
		(net 1)
	)
	(segment
		(start 198.101 110.598)
		(end 198.101 109.446)
		(width 0.38)
		(layer "F.Cu")
		(net 1)
	)
	(segment
		(start 184.9995 162.0005)
		(end 184.5 162.5)
		(width 0.256)
		(layer "F.Cu")
		(net 1)
	)
	(segment
		(start 162.625 162.299999)
		(end 160.31 162.299999)
		(width 0.177)
		(layer "F.Cu")
		(net 1)
	)
	(segment
		(start 122.7005 164.7495)
		(end 122.7 164.75)
		(width 0.1)
		(layer "F.Cu")
		(net 1)
	)
	(segment
		(start 187.9995 150.9995)
		(end 187.5 150.5)
		(width 0.256)
		(layer "F.Cu")
		(net 1)
	)
	(segment
		(start 199 163)
		(end 198.5005 163.4995)
		(width 0.256)
		(layer "F.Cu")
		(net 1)
	)
	(segment
		(start 117.08 146.61)
		(end 117.71 146.61)
		(width 0.201)
		(layer "F.Cu")
		(net 1)
	)
	(segment
		(start 176.9995 161.0005)
		(end 176.5 161.5)
		(width 0.256)
		(layer "F.Cu")
		(net 1)
	)
	(segment
		(start 185.9995 163.0005)
		(end 185.5 163.5)
		(width 0.256)
		(layer "F.Cu")
		(net 1)
	)
	(segment
		(start 198 164)
		(end 197.5005 164.4995)
		(width 0.256)
		(layer "F.Cu")
		(net 1)
	)
	(segment
		(start 220.2 110.598)
		(end 220.2 109.446)
		(width 0.38)
		(layer "F.Cu")
		(net 1)
	)
	(segment
		(start 247.123 137.101)
		(end 247.124498 137.0995)
		(width 0.4)
		(layer "F.Cu")
		(net 1)
	)
	(segment
		(start 190.45 106)
		(end 190.45 104.848)
		(width 0.38)
		(layer "F.Cu")
		(net 1)
	)
	(segment
		(start 136.774499 169.899)
		(end 137.024499 170.149)
		(width 0.256)
		(layer "F.Cu")
		(net 1)
	)
	(segment
		(start 196.0005 157.0005)
		(end 196.5 157.500001)
		(width 0.256)
		(layer "F.Cu")
		(net 1)
	)
	(segment
		(start 238.952 176.748)
		(end 237.849499 176.748)
		(width 0.177)
		(layer "F.Cu")
		(net 1)
	)
	(segment
		(start 175.9995 155.0005)
		(end 175.5 155.5)
		(width 0.256)
		(layer "F.Cu")
		(net 1)
	)
	(segment
		(start 191.301 110.598)
		(end 191.301 109.446)
		(width 0.38)
		(layer "F.Cu")
		(net 1)
	)
	(segment
		(start 185.9995 153.0005)
		(end 185.5 153.5)
		(width 0.256)
		(layer "F.Cu")
		(net 1)
	)
	(segment
		(start 127.681 168.7925)
		(end 121.681 168.7925)
		(width 0.201)
		(layer "F.Cu")
		(net 1)
	)
	(segment
		(start 164.125 194.824501)
		(end 164.65 195.349501)
		(width 0.22)
		(layer "F.Cu")
		(net 1)
	)
	(segment
		(start 129.67 146.559)
		(end 129.625 146.514)
		(width 0.4)
		(layer "F.Cu")
		(net 1)
	)
	(segment
		(start 194.0005 155.0005)
		(end 194.499999 155.5)
		(width 0.256)
		(layer "F.Cu")
		(net 1)
	)
	(segment
		(start 158.31 158.984999)
		(end 158.31 160.299999)
		(width 0.177)
		(layer "F.Cu")
		(net 1)
	)
	(segment
		(start 186.9995 154.0005)
		(end 186.5 154.5)
		(width 0.256)
		(layer "F.Cu")
		(net 1)
	)
	(segment
		(start 189.0005 163.0005)
		(end 189.5 163.5)
		(width 0.256)
		(layer "F.Cu")
		(net 1)
	)
	(segment
		(start 114.773499 140.1)
		(end 114.724499 140.149)
		(width 0.4)
		(layer "F.Cu")
		(net 1)
	)
	(segment
		(start 186.9995 151.9995)
		(end 186.5 151.5)
		(width 0.256)
		(layer "F.Cu")
		(net 1)
	)
	(segment
		(start 196 164)
		(end 195.5005 164.4995)
		(width 0.256)
		(layer "F.Cu")
		(net 1)
	)
	(segment
		(start 221.244001 148.098)
		(end 220.472001 148.098)
		(width 0.15)
		(layer "F.Cu")
		(net 1)
	)
	(segment
		(start 151.034499 171.651)
		(end 151.050499 171.667)
		(width 0.15)
		(layer "F.Cu")
		(net 1)
	)
	(segment
		(start 241.775 154.35)
		(end 241.775 154.827999)
		(width 0.4)
		(layer "F.Cu")
		(net 1)
	)
	(segment
		(start 121.0365 168.7925)
		(end 121.036 168.792)
		(width 0.201)
		(layer "F.Cu")
		(net 1)
	)
	(segment
		(start 198.4995 163.4995)
		(end 198 163)
		(width 0.256)
		(layer "F.Cu")
		(net 1)
	)
	(segment
		(start 130.508 172.113)
		(end 130.758 172.363)
		(width 0.201)
		(layer "F.Cu")
		(net 1)
	)
	(segment
		(start 229.222 152.85)
		(end 227.6 152.85)
		(width 0.4)
		(layer "F.Cu")
		(net 1)
	)
	(segment
		(start 237.135499 183.506)
		(end 237.129499 183.512)
		(width 0.177)
		(layer "F.Cu")
		(net 1)
	)
	(segment
		(start 107.234 140.563)
		(end 107.848 139.949)
		(width 0.4)
		(layer "F.Cu")
		(net 1)
	)
	(segment
		(start 136.902 106)
		(end 136.902 104.848)
		(width 0.38)
		(layer "F.Cu")
		(net 1)
	)
	(segment
		(start 144.641 138.607851)
		(end 144.502149 138.607851)
		(width 0.256)
		(layer "F.Cu")
		(net 1)
	)
	(segment
		(start 168.65 195.374501)
		(end 168.65 199.25)
		(width 0.22)
		(layer "F.Cu")
		(net 1)
	)
	(segment
		(start 226.4 157.142001)
		(end 226.0015 157.540501)
		(width 0.4)
		(layer "F.Cu")
		(net 1)
	)
	(segment
		(start 193.0005 156.0005)
		(end 193.5 156.5)
		(width 0.256)
		(layer "F.Cu")
		(net 1)
	)
	(segment
		(start 147.214499 164.639)
		(end 147.214499 164.999)
		(width 0.15)
		(layer "F.Cu")
		(net 1)
	)
	(segment
		(start 241.774499 184.615)
		(end 241.140499 184.615)
		(width 0.256)
		(layer "F.Cu")
		(net 1)
	)
	(segment
		(start 190.000499 146.9995)
		(end 190.5 146.5)
		(width 0.256)
		(layer "F.Cu")
		(net 1)
	)
	(segment
		(start 132.206 172.113)
		(end 132.926 172.113)
		(width 0.201)
		(layer "F.Cu")
		(net 1)
	)
	(segment
		(start 162.4 110.598)
		(end 162.4 109.446)
		(width 0.38)
		(layer "F.Cu")
		(net 1)
	)
	(segment
		(start 151.35 110.598)
		(end 151.35 109.446)
		(width 0.38)
		(layer "F.Cu")
		(net 1)
	)
	(segment
		(start 151.65 199.25)
		(end 151.65 196.1)
		(width 0.4)
		(layer "F.Cu")
		(net 1)
	)
	(segment
		(start 109.309499 141.649)
		(end 109.309499 141.734)
		(width 0.15)
		(layer "F.Cu")
		(net 1)
	)
	(segment
		(start 113.145499 179.5525)
		(end 112.430499 179.5525)
		(width 0.256)
		(layer "F.Cu")
		(net 1)
	)
	(segment
		(start 257.79 145.966001)
		(end 257.79 146.701001)
		(width 0.256)
		(layer "F.Cu")
		(net 1)
	)
	(segment
		(start 135.201 106)
		(end 135.201 104.848)
		(width 0.38)
		(layer "F.Cu")
		(net 1)
	)
	(segment
		(start 137.75 110.598)
		(end 137.75 109.446)
		(width 0.38)
		(layer "F.Cu")
		(net 1)
	)
	(segment
		(start 247.489499 135.614)
		(end 248.079499 135.614)
		(width 0.256)
		(layer "F.Cu")
		(net 1)
	)
	(segment
		(start 193.0005 151.9995)
		(end 193.500001 151.5)
		(width 0.256)
		(layer "F.Cu")
		(net 1)
	)
	(segment
		(start 261.375 135.424999)
		(end 262.397 135.424999)
		(width 0.4)
		(layer "F.Cu")
		(net 1)
	)
	(segment
		(start 249.223499 141.25)
		(end 248.45 141.25)
		(width 0.177)
		(layer "F.Cu")
		(net 1)
	)
	(segment
		(start 128.306 175.542)
		(end 128.306 174.912)
		(width 0.256)
		(layer "F.Cu")
		(net 1)
	)
	(segment
		(start 254.189 128.939)
		(end 254.45 129.2)
		(width 0.4)
		(layer "F.Cu")
		(net 1)
	)
	(segment
		(start 189.0005 158.0005)
		(end 189.5 158.5)
		(width 0.256)
		(layer "F.Cu")
		(net 1)
	)
	(segment
		(start 198.0005 156.0005)
		(end 198.5 156.5)
		(width 0.256)
		(layer "F.Cu")
		(net 1)
	)
	(segment
		(start 195.1975 196.4275)
		(end 195.65 196.88)
		(width 0.22)
		(layer "F.Cu")
		(net 1)
	)
	(segment
		(start 229.222 146.85)
		(end 227.6 146.85)
		(width 0.4)
		(layer "F.Cu")
		(net 1)
	)
	(segment
		(start 175.65 195.374501)
		(end 175.65 199.25)
		(width 0.22)
		(layer "F.Cu")
		(net 1)
	)
	(segment
		(start 157.202276 155.073553)
		(end 157.202276 155.095638)
		(width 0.256)
		(layer "F.Cu")
		(net 1)
	)
	(segment
		(start 238.901 110.598)
		(end 238.901 111.75)
		(width 0.38)
		(layer "F.Cu")
		(net 1)
	)
	(segment
		(start 123.766 187.702)
		(end 124.756 187.702)
		(width 0.256)
		(layer "F.Cu")
		(net 1)
	)
	(segment
		(start 195.1975 194.849501)
		(end 195.1975 196.4275)
		(width 0.22)
		(layer "F.Cu")
		(net 1)
	)
	(segment
		(start 119.623 157.652)
		(end 119.625 157.65)
		(width 0.182)
		(layer "F.Cu")
		(net 1)
	)
	(segment
		(start 229.551 110.598)
		(end 229.551 109.446)
		(width 0.38)
		(layer "F.Cu")
		(net 1)
	)
	(segment
		(start 208.301 106)
		(end 208.301 104.848)
		(width 0.38)
		(layer "F.Cu")
		(net 1)
	)
	(segment
		(start 114.05 152.5)
		(end 115.051 152.5)
		(width 0.256)
		(layer "F.Cu")
		(net 1)
	)
	(segment
		(start 180.9995 158.0005)
		(end 180.5 158.5)
		(width 0.256)
		(layer "F.Cu")
		(net 1)
	)
	(segment
		(start 198.4995 158.4995)
		(end 198 158)
		(width 0.256)
		(layer "F.Cu")
		(net 1)
	)
	(segment
		(start 186.9995 149.9995)
		(end 186.5 149.5)
		(width 0.256)
		(layer "F.Cu")
		(net 1)
	)
	(segment
		(start 199.0005 156.000499)
		(end 199.5 156.5)
		(width 0.256)
		(layer "F.Cu")
		(net 1)
	)
	(segment
		(start 138.6 106)
		(end 138.6 104.848)
		(width 0.38)
		(layer "F.Cu")
		(net 1)
	)
	(segment
		(start 239.274499 170.875501)
		(end 238.95 171.2)
		(width 0.256)
		(layer "F.Cu")
		(net 1)
	)
	(segment
		(start 240.781 137.101)
		(end 240.7795 137.102499)
		(width 0.4)
		(layer "F.Cu")
		(net 1)
	)
	(segment
		(start 190 165)
		(end 189.5005 165.4995)
		(width 0.256)
		(layer "F.Cu")
		(net 1)
	)
	(segment
		(start 239.521499 155.0615)
		(end 240.738499 155.0615)
		(width 0.256)
		(layer "F.Cu")
		(net 1)
	)
	(segment
		(start 136.124499 178.949)
		(end 135.624499 179.449)
		(width 0.201)
		(layer "F.Cu")
		(net 1)
	)
	(segment
		(start 129.25 106)
		(end 129.25 104.848)
		(width 0.38)
		(layer "F.Cu")
		(net 1)
	)
	(segment
		(start 196.5 160.5)
		(end 196.0005 160.0005)
		(width 0.256)
		(layer "F.Cu")
		(net 1)
	)
	(segment
		(start 171.65 195.324501)
		(end 171.65 199.25)
		(width 0.22)
		(layer "F.Cu")
		(net 1)
	)
	(segment
		(start 238.95 171.2)
		(end 238.948 171.198)
		(width 0.256)
		(layer "F.Cu")
		(net 1)
	)
	(segment
		(start 106.655 140.563)
		(end 107.234 140.563)
		(width 0.4)
		(layer "F.Cu")
		(net 1)
	)
	(segment
		(start 191.0005 156.0005)
		(end 191.5 156.5)
		(width 0.256)
		(layer "F.Cu")
		(net 1)
	)
	(segment
		(start 197.5 162.5)
		(end 197.0005 162.000501)
		(width 0.256)
		(layer "F.Cu")
		(net 1)
	)
	(segment
		(start 132.47 155.7)
		(end 132.648 155.522)
		(width 0.198)
		(layer "F.Cu")
		(net 1)
	)
	(segment
		(start 251.487998 128.939)
		(end 252.937998 128.939)
		(width 0.4)
		(layer "F.Cu")
		(net 1)
	)
	(segment
		(start 241.774499 163.92)
		(end 242.389499 163.92)
		(width 0.256)
		(layer "F.Cu")
		(net 1)
	)
	(segment
		(start 113.25 151.7)
		(end 114.05 152.5)
		(width 0.256)
		(layer "F.Cu")
		(net 1)
	)
	(segment
		(start 192.0005 147.9995)
		(end 192.5 147.5)
		(width 0.256)
		(layer "F.Cu")
		(net 1)
	)
	(segment
		(start 227.001 106)
		(end 227.001 104.848)
		(width 0.38)
		(layer "F.Cu")
		(net 1)
	)
	(segment
		(start 213.4 106)
		(end 213.4 104.848)
		(width 0.38)
		(layer "F.Cu")
		(net 1)
	)
	(segment
		(start 181.9995 142.9995)
		(end 181.499999 142.5)
		(width 0.256)
		(layer "F.Cu")
		(net 1)
	)
	(segment
		(start 200.5 151.5)
		(end 200.0005 151.9995)
		(width 0.256)
		(layer "F.Cu")
		(net 1)
	)
	(segment
		(start 237.277501 176.748002)
		(end 237.276998 176.747501)
		(width 0.256)
		(layer "F.Cu")
		(net 1)
	)
	(segment
		(start 249.48 186.929)
		(end 249.8 186.929)
		(width 0.182)
		(layer "F.Cu")
		(net 1)
	)
	(segment
		(start 218.502 110.598)
		(end 218.502 109.446)
		(width 0.38)
		(layer "F.Cu")
		(net 1)
	)
	(segment
		(start 140.396843 155.517328)
		(end 140.407328 155.517328)
		(width 0.256)
		(layer "F.Cu")
		(net 1)
	)
	(segment
		(start 160.1 156.719999)
		(end 160.1 156.125)
		(width 0.256)
		(layer "F.Cu")
		(net 1)
	)
	(segment
		(start 184 164)
		(end 183.5005 164.4995)
		(width 0.256)
		(layer "F.Cu")
		(net 1)
	)
	(segment
		(start 128.506 173.113)
		(end 129.307 173.113)
		(width 0.201)
		(layer "F.Cu")
		(net 1)
	)
	(segment
		(start 132.206 172.113)
		(end 131.008 172.113)
		(width 0.201)
		(layer "F.Cu")
		(net 1)
	)
	(segment
		(start 234.651 106)
		(end 234.651 104.848)
		(width 0.38)
		(layer "F.Cu")
		(net 1)
	)
	(segment
		(start 169.175 194.849501)
		(end 168.65 195.374501)
		(width 0.22)
		(layer "F.Cu")
		(net 1)
	)
	(segment
		(start 151.501 183.749)
		(end 150.901 183.749)
		(width 0.201)
		(layer "F.Cu")
		(net 1)
	)
	(segment
		(start 256.825 129.986002)
		(end 256.837998 129.999)
		(width 0.256)
		(layer "F.Cu")
		(net 1)
	)
	(segment
		(start 185.65 195.374501)
		(end 185.65 199.25)
		(width 0.22)
		(layer "F.Cu")
		(net 1)
	)
	(segment
		(start 195.0005 146.9995)
		(end 195.5 146.5)
		(width 0.256)
		(layer "F.Cu")
		(net 1)
	)
	(segment
		(start 248.8 186.249)
		(end 249.48 186.929)
		(width 0.182)
		(layer "F.Cu")
		(net 1)
	)
	(segment
		(start 188.75 110.598)
		(end 188.75 109.446)
		(width 0.38)
		(layer "F.Cu")
		(net 1)
	)
	(segment
		(start 120.096 174.922)
		(end 120.096 175.552)
		(width 0.4)
		(layer "F.Cu")
		(net 1)
	)
	(segment
		(start 225.301 106)
		(end 225.301 104.848)
		(width 0.38)
		(layer "F.Cu")
		(net 1)
	)
	(segment
		(start 246.101 137.101)
		(end 247.123 137.101)
		(width 0.4)
		(layer "F.Cu")
		(net 1)
	)
	(segment
		(start 177.9995 165.0005)
		(end 177.5 165.5)
		(width 0.256)
		(layer "F.Cu")
		(net 1)
	)
	(segment
		(start 143.7 145.95)
		(end 143.725 145.925)
		(width 0.256)
		(layer "F.Cu")
		(net 1)
	)
	(segment
		(start 200.651 106)
		(end 200.651 104.848)
		(width 0.38)
		(layer "F.Cu")
		(net 1)
	)
	(segment
		(start 190.0005 141.999501)
		(end 190.5 141.5)
		(width 0.256)
		(layer "F.Cu")
		(net 1)
	)
	(segment
		(start 249.174499 138.574)
		(end 248.519499 138.574)
		(width 0.201)
		(layer "F.Cu")
		(net 1)
	)
	(segment
		(start 133.5 106)
		(end 133.5 104.848)
		(width 0.38)
		(layer "F.Cu")
		(net 1)
	)
	(segment
		(start 185.9995 144.9995)
		(end 185.5 144.5)
		(width 0.256)
		(layer "F.Cu")
		(net 1)
	)
	(segment
		(start 109.723499 139.549)
		(end 110.773499 139.549)
		(width 0.4)
		(layer "F.Cu")
		(net 1)
	)
	(segment
		(start 109.349499 149.724)
		(end 109.349499 149.05)
		(width 0.4)
		(layer "F.Cu")
		(net 1)
	)
	(segment
		(start 117.52 139.563)
		(end 118.087 139.563)
		(width 0.4)
		(layer "F.Cu")
		(net 1)
	)
	(segment
		(start 178.55 106)
		(end 178.55 104.848)
		(width 0.38)
		(layer "F.Cu")
		(net 1)
	)
	(segment
		(start 165.125 194.824501)
		(end 165.125 194.874501)
		(width 0.22)
		(layer "F.Cu")
		(net 1)
	)
	(segment
		(start 251.813 185.699)
		(end 252.585 185.699)
		(width 0.182)
		(layer "F.Cu")
		(net 1)
	)
	(segment
		(start 122.7005 163.989)
		(end 122.7005 164.7495)
		(width 0.1)
		(layer "F.Cu")
		(net 1)
	)
	(segment
		(start 238.948 171.198)
		(end 237.849499 171.198)
		(width 0.256)
		(layer "F.Cu")
		(net 1)
	)
	(segment
		(start 109.375 181.7695)
		(end 111.11 181.7695)
		(width 0.201)
		(layer "F.Cu")
		(net 1)
	)
	(segment
		(start 150.300499 168.633)
		(end 150.934499 168.633)
		(width 0.15)
		(layer "F.Cu")
		(net 1)
	)
	(segment
		(start 142.902672 155.507328)
		(end 142.51 155.9)
		(width 0.256)
		(layer "F.Cu")
		(net 1)
	)
	(segment
		(start 243.151 110.598)
		(end 243.151 109.446)
		(width 0.38)
		(layer "F.Cu")
		(net 1)
	)
	(segment
		(start 251.813 185.699)
		(end 251.117123 185.699)
		(width 0.182)
		(layer "F.Cu")
		(net 1)
	)
	(segment
		(start 158.06 165.834999)
		(end 157.77 166.124999)
		(width 0.256)
		(layer "F.Cu")
		(net 1)
	)
	(segment
		(start 247.904 145.1)
		(end 247.904 145.096)
		(width 0.177)
		(layer "F.Cu")
		(net 1)
	)
	(segment
		(start 145.96 155.51)
		(end 146.4 155.95)
		(width 0.256)
		(layer "F.Cu")
		(net 1)
	)
	(segment
		(start 239.274499 155.3085)
		(end 239.521499 155.0615)
		(width 0.256)
		(layer "F.Cu")
		(net 1)
	)
	(segment
		(start 230.075 161.848)
		(end 229.55 161.848)
		(width 0.4)
		(layer "F.Cu")
		(net 1)
	)
	(segment
		(start 126.701 110.598)
		(end 126.701 109.446)
		(width 0.38)
		(layer "F.Cu")
		(net 1)
	)
	(segment
		(start 117.71 145.61)
		(end 117.08 145.61)
		(width 0.201)
		(layer "F.Cu")
		(net 1)
	)
	(segment
		(start 142.51 155.9)
		(end 142.25 155.9)
		(width 0.256)
		(layer "F.Cu")
		(net 1)
	)
	(segment
		(start 125 110.598)
		(end 125 109.446)
		(width 0.38)
		(layer "F.Cu")
		(net 1)
	)
	(segment
		(start 128.706 172.612)
		(end 128.506 172.412)
		(width 0.201)
		(layer "F.Cu")
		(net 1)
	)
	(segment
		(start 105.724 168.714)
		(end 102.614 168.714)
		(width 0.4)
		(layer "F.Cu")
		(net 1)
	)
	(segment
		(start 187.9995 163.000499)
		(end 187.5 163.5)
		(width 0.256)
		(layer "F.Cu")
		(net 1)
	)
	(segment
		(start 226.4 156.441001)
		(end 226.4 157.142001)
		(width 0.4)
		(layer "F.Cu")
		(net 1)
	)
	(segment
		(start 237.849499 171.198)
		(end 237.277501 171.198002)
		(width 0.256)
		(layer "F.Cu")
		(net 1)
	)
	(segment
		(start 189.0005 149.9995)
		(end 189.5 149.5)
		(width 0.256)
		(layer "F.Cu")
		(net 1)
	)
	(segment
		(start 151.45 195.9)
		(end 151.65 196.1)
		(width 0.4)
		(layer "F.Cu")
		(net 1)
	)
	(segment
		(start 179.4 110.598)
		(end 179.4 109.446)
		(width 0.38)
		(layer "F.Cu")
		(net 1)
	)
	(segment
		(start 138.35 154.95)
		(end 138.35 155.470485)
		(width 0.256)
		(layer "F.Cu")
		(net 1)
	)
	(segment
		(start 241.140499 180.865)
		(end 241.124499 180.849)
		(width 0.256)
		(layer "F.Cu")
		(net 1)
	)
	(segment
		(start 207.2905 151.4595)
		(end 207.3 151.45)
		(width 0.4)
		(layer "F.Cu")
		(net 1)
	)
	(segment
		(start 121.086 174.922)
		(end 121.086 175.552)
		(width 0.4)
		(layer "F.Cu")
		(net 1)
	)
	(segment
		(start 176.9995 163.0005)
		(end 176.5 163.5)
		(width 0.256)
		(layer "F.Cu")
		(net 1)
	)
	(segment
		(start 240.6 110.598)
		(end 240.6 109.446)
		(width 0.38)
		(layer "F.Cu")
		(net 1)
	)
	(segment
		(start 179.9995 146.9995)
		(end 179.5 146.5)
		(width 0.256)
		(layer "F.Cu")
		(net 1)
	)
	(segment
		(start 133.815 159.058499)
		(end 134.124499 158.749)
		(width 0.256)
		(layer "F.Cu")
		(net 1)
	)
	(segment
		(start 149.652 110.598)
		(end 149.652 109.446)
		(width 0.38)
		(layer "F.Cu")
		(net 1)
	)
	(segment
		(start 109.211499 143.749)
		(end 108.439499 143.749)
		(width 0.182)
		(layer "F.Cu")
		(net 1)
	)
	(segment
		(start 224.45 110.598)
		(end 224.45 109.446)
		(width 0.38)
		(layer "F.Cu")
		(net 1)
	)
	(segment
		(start 179.9995 158.0005)
		(end 179.5 158.5)
		(width 0.256)
		(layer "F.Cu")
		(net 1)
	)
	(segment
		(start 147.343499 164.51)
		(end 147.214499 164.639)
		(width 0.15)
		(layer "F.Cu")
		(net 1)
	)
	(segment
		(start 182.65 195.374501)
		(end 182.65 199.25)
		(width 0.22)
		(layer "F.Cu")
		(net 1)
	)
	(segment
		(start 196.000501 139.9995)
		(end 196.5 139.5)
		(width 0.256)
		(layer "F.Cu")
		(net 1)
	)
	(segment
		(start 171.175 194.849501)
		(end 171.65 195.324501)
		(width 0.22)
		(layer "F.Cu")
		(net 1)
	)
	(segment
		(start 140.940499 169.533)
		(end 140.424499 170.049)
		(width 0.256)
		(layer "F.Cu")
		(net 1)
	)
	(segment
		(start 183.175 194.849501)
		(end 182.65 195.374501)
		(width 0.22)
		(layer "F.Cu")
		(net 1)
	)
	(segment
		(start 236.35 106)
		(end 236.35 104.848)
		(width 0.38)
		(layer "F.Cu")
		(net 1)
	)
	(segment
		(start 194.0005 163.0005)
		(end 194.5 163.5)
		(width 0.256)
		(layer "F.Cu")
		(net 1)
	)
	(segment
		(start 160.702 110.598)
		(end 160.702 109.446)
		(width 0.38)
		(layer "F.Cu")
		(net 1)
	)
	(segment
		(start 242.389499 163.92)
		(end 242.399499 163.93)
		(width 0.256)
		(layer "F.Cu")
		(net 1)
	)
	(segment
		(start 201.0005 139.999501)
		(end 201.5 139.5)
		(width 0.256)
		(layer "F.Cu")
		(net 1)
	)
	(segment
		(start 147.1 110.598)
		(end 147.1 109.446)
		(width 0.38)
		(layer "F.Cu")
		(net 1)
	)
	(segment
		(start 193.0005 149.9995)
		(end 193.5 149.5)
		(width 0.256)
		(layer "F.Cu")
		(net 1)
	)
	(segment
		(start 162.125 194.849501)
		(end 162.65 195.374501)
		(width 0.22)
		(layer "F.Cu")
		(net 1)
	)
	(segment
		(start 204.05 106)
		(end 204.05 104.848)
		(width 0.38)
		(layer "F.Cu")
		(net 1)
	)
	(segment
		(start 113.917499 179.551)
		(end 114.632499 179.551)
		(width 0.256)
		(layer "F.Cu")
		(net 1)
	)
	(segment
		(start 175.9995 149.9995)
		(end 175.5 149.5)
		(width 0.256)
		(layer "F.Cu")
		(net 1)
	)
	(segment
		(start 187.9995 155.0005)
		(end 187.5 155.5)
		(width 0.256)
		(layer "F.Cu")
		(net 1)
	)
	(segment
		(start 206.601 106)
		(end 206.601 104.848)
		(width 0.38)
		(layer "F.Cu")
		(net 1)
	)
	(segment
		(start 164.65 199.25)
		(end 164.65 195.349501)
		(width 0.44)
		(layer "F.Cu")
		(net 1)
	)
	(segment
		(start 194 164)
		(end 193.5005 164.4995)
		(width 0.256)
		(layer "F.Cu")
		(net 1)
	)
	(segment
		(start 177.9995 156.0005)
		(end 177.5 156.5)
		(width 0.256)
		(layer "F.Cu")
		(net 1)
	)
	(segment
		(start 181.125 194.849501)
		(end 181.65 195.374501)
		(width 0.22)
		(layer "F.Cu")
		(net 1)
	)
	(segment
		(start 141.434 166.772)
		(end 141.434 167.640499)
		(width 0.15)
		(layer "F.Cu")
		(net 1)
	)
	(segment
		(start 148.65 199.25)
		(end 148.65 195.9)
		(width 0.4)
		(layer "F.Cu")
		(net 1)
	)
	(segment
		(start 135.525499 169.899)
		(end 135.174499 169.899)
		(width 0.256)
		(layer "F.Cu")
		(net 1)
	)
	(segment
		(start 237.126499 134.757)
		(end 237.767 134.757)
		(width 0.4)
		(layer "F.Cu")
		(net 1)
	)
	(segment
		(start 147.199 178.501)
		(end 147.2 178.5)
		(width 0.198)
		(layer "F.Cu")
		(net 1)
	)
	(segment
		(start 178.999499 158.0005)
		(end 178.5 158.5)
		(width 0.256)
		(layer "F.Cu")
		(net 1)
	)
	(segment
		(start 237.767 134.757)
		(end 238.03 135.02)
		(width 0.4)
		(layer "F.Cu")
		(net 1)
	)
	(segment
		(start 145.724499 169.749)
		(end 145.724499 169.599)
		(width 0.15)
		(layer "F.Cu")
		(net 1)
	)
	(segment
		(start 118.087 139.563)
		(end 118.1 139.55)
		(width 0.198)
		(layer "F.Cu")
		(net 1)
	)
	(segment
		(start 189.000501 151.9995)
		(end 189.5 151.500001)
		(width 0.256)
		(layer "F.Cu")
		(net 1)
	)
	(segment
		(start 150.400499 171.651)
		(end 151.034499 171.651)
		(width 0.15)
		(layer "F.Cu")
		(net 1)
	)
	(segment
		(start 238.03 135.02)
		(end 238.03 135.65)
		(width 0.4)
		(layer "F.Cu")
		(net 1)
	)
	(segment
		(start 122.076 174.922)
		(end 122.076 175.552)
		(width 0.4)
		(layer "F.Cu")
		(net 1)
	)
	(segment
		(start 178.9995 154.000499)
		(end 178.5 154.5)
		(width 0.256)
		(layer "F.Cu")
		(net 1)
	)
	(segment
		(start 181.101 110.598)
		(end 181.101 109.446)
		(width 0.38)
		(layer "F.Cu")
		(net 1)
	)
	(segment
		(start 261.372999 127.481498)
		(end 261.3715 127.479999)
		(width 0.4)
		(layer "F.Cu")
		(net 1)
	)
	(segment
		(start 237.923499 164.4)
		(end 237.026499 164.400001)
		(width 0.256)
		(layer "F.Cu")
		(net 1)
	)
	(segment
		(start 192.0005 153.000501)
		(end 192.5 153.5)
		(width 0.256)
		(layer "F.Cu")
		(net 1)
	)
	(segment
		(start 177.9995 140.9995)
		(end 177.5 140.5)
		(width 0.256)
		(layer "F.Cu")
		(net 1)
	)
	(segment
		(start 200.499501 161.4995)
		(end 200 161)
		(width 0.256)
		(layer "F.Cu")
		(net 1)
	)
	(segment
		(start 238.051 106)
		(end 238.051 104.848)
		(width 0.38)
		(layer "F.Cu")
		(net 1)
	)
	(segment
		(start 239.274499 176.425501)
		(end 238.952 176.748)
		(width 0.177)
		(layer "F.Cu")
		(net 1)
	)
	(segment
		(start 121.681 168.7925)
		(end 121.0365 168.7925)
		(width 0.201)
		(layer "F.Cu")
		(net 1)
	)
	(segment
		(start 239.274499 170.2)
		(end 239.274499 170.875501)
		(width 0.256)
		(layer "F.Cu")
		(net 1)
	)
	(segment
		(start 255.378499 132.663)
		(end 255.324499 132.717)
		(width 0.182)
		(layer "F.Cu")
		(net 1)
	)
	(segment
		(start 180.9995 163.0005)
		(end 180.5 163.5)
		(width 0.256)
		(layer "F.Cu")
		(net 1)
	)
	(segment
		(start 185.9995 148.9995)
		(end 185.5 148.5)
		(width 0.256)
		(layer "F.Cu")
		(net 1)
	)
	(segment
		(start 246.903 145.1)
		(end 247.904 145.1)
		(width 0.256)
		(layer "F.Cu")
		(net 1)
	)
	(segment
		(start 108.324499 149.049)
		(end 109.324498 149.049)
		(width 0.4)
		(layer "F.Cu")
		(net 1)
	)
	(segment
		(start 139.224499 181.849)
		(end 140.224499 181.849)
		(width 0.201)
		(layer "F.Cu")
		(net 1)
	)
	(segment
		(start 156.25 158.4)
		(end 155.975001 158.674999)
		(width 0.256)
		(layer "F.Cu")
		(net 1)
	)
	(segment
		(start 142.85 106)
		(end 142.85 104.848)
		(width 0.38)
		(layer "F.Cu")
		(net 1)
	)
	(segment
		(start 229.542501 161.840501)
		(end 229.55 161.848)
		(width 0.4)
		(layer "F.Cu")
		(net 1)
	)
	(segment
		(start 200.0005 146.9995)
		(end 200.5 146.5)
		(width 0.256)
		(layer "F.Cu")
		(net 1)
	)
	(segment
		(start 160.31 162.299999)
		(end 159.81 161.799999)
		(width 0.177)
		(layer "F.Cu")
		(net 1)
	)
	(segment
		(start 180.9995 149.9995)
		(end 180.5 149.5)
		(width 0.256)
		(layer "F.Cu")
		(net 1)
	)
	(segment
		(start 249.223499 146.65)
		(end 248.55 146.65)
		(width 0.177)
		(layer "F.Cu")
		(net 1)
	)
	(segment
		(start 180.9995 162.0005)
		(end 180.5 162.5)
		(width 0.256)
		(layer "F.Cu")
		(net 1)
	)
	(segment
		(start 156.452 110.598)
		(end 156.452 109.446)
		(width 0.38)
		(layer "F.Cu")
		(net 1)
	)
	(segment
		(start 200 164)
		(end 200.4995 163.5005)
		(width 0.256)
		(layer "F.Cu")
		(net 1)
	)
	(segment
		(start 241.803 146.099)
		(end 240.781 146.099)
		(width 0.4)
		(layer "F.Cu")
		(net 1)
	)
	(segment
		(start 200 165)
		(end 200 165.7064)
		(width 0.256)
		(layer "F.Cu")
		(net 1)
	)
	(segment
		(start 130.951 110.598)
		(end 130.951 109.446)
		(width 0.38)
		(layer "F.Cu")
		(net 1)
	)
	(segment
		(start 200.0005 141.9995)
		(end 200.5 141.5)
		(width 0.256)
		(layer "F.Cu")
		(net 1)
	)
	(segment
		(start 186.9995 142.9995)
		(end 186.5 142.5)
		(width 0.256)
		(layer "F.Cu")
		(net 1)
	)
	(segment
		(start 135.074499 186.298)
		(end 135.023499 186.349)
		(width 0.201)
		(layer "F.Cu")
		(net 1)
	)
	(segment
		(start 138.35 155.470485)
		(end 138.396843 155.517328)
		(width 0.256)
		(layer "F.Cu")
		(net 1)
	)
	(segment
		(start 201.0005 157.0005)
		(end 201.5 157.5)
		(width 0.256)
		(layer "F.Cu")
		(net 1)
	)
	(segment
		(start 241.140499 184.615)
		(end 241.124499 184.599)
		(width 0.256)
		(layer "F.Cu")
		(net 1)
	)
	(segment
		(start 128.506 171.792)
		(end 128.506 172.113)
		(width 0.201)
		(layer "F.Cu")
		(net 1)
	)
	(segment
		(start 195.0005 158.0005)
		(end 195.5 158.5)
		(width 0.256)
		(layer "F.Cu")
		(net 1)
	)
	(segment
		(start 244.25 186.829)
		(end 244.25 187.404)
		(width 0.182)
		(layer "F.Cu")
		(net 1)
	)
	(segment
		(start 193.0005 158.0005)
		(end 193.5 158.5)
		(width 0.256)
		(layer "F.Cu")
		(net 1)
	)
	(segment
		(start 184.9995 149.9995)
		(end 184.5 149.5)
		(width 0.256)
		(layer "F.Cu")
		(net 1)
	)
	(segment
		(start 126.152 181.053)
		(end 125.902 181.303)
		(width 0.201)
		(layer "F.Cu")
		(net 1)
	)
	(segment
		(start 193.0005 154.0005)
		(end 193.5 154.5)
		(width 0.256)
		(layer "F.Cu")
		(net 1)
	)
	(segment
		(start 172.602 106)
		(end 172.602 104.848)
		(width 0.38)
		(layer "F.Cu")
		(net 1)
	)
	(segment
		(start 133.927 148.073)
		(end 133.925 148.075)
		(width 0.256)
		(layer "F.Cu")
		(net 1)
	)
	(segment
		(start 129.307 173.113)
		(end 130.008 173.113)
		(width 0.201)
		(layer "F.Cu")
		(net 1)
	)
	(segment
		(start 192.151 106)
		(end 192.151 104.848)
		(width 0.38)
		(layer "F.Cu")
		(net 1)
	)
	(segment
		(start 142 110.598)
		(end 142 109.446)
		(width 0.38)
		(layer "F.Cu")
		(net 1)
	)
	(segment
		(start 127.745626 143.002859)
		(end 127.716328 143.032157)
		(width 0.2)
		(layer "F.Cu")
		(net 1)
	)
	(segment
		(start 106.275 169.265)
		(end 105.724 168.714)
		(width 0.4)
		(layer "F.Cu")
		(net 1)
	)
	(segment
		(start 197.0005 142.9995)
		(end 197.5 142.5)
		(width 0.256)
		(layer "F.Cu")
		(net 1)
	)
	(segment
		(start 201.499501 156.4995)
		(end 201 156)
		(width 0.256)
		(layer "F.Cu")
		(net 1)
	)
	(segment
		(start 145.402 110.598)
		(end 145.402 109.446)
		(width 0.38)
		(layer "F.Cu")
		(net 1)
	)
	(segment
		(start 129.307 171.614)
		(end 128.684 171.614)
		(width 0.201)
		(layer "F.Cu")
		(net 1)
	)
	(segment
		(start 190.0005 155.0005)
		(end 190.5 155.5)
		(width 0.256)
		(layer "F.Cu")
		(net 1)
	)
	(segment
		(start 192 164)
		(end 191.5005 164.4995)
		(width 0.256)
		(layer "F.Cu")
		(net 1)
	)
	(segment
		(start 237.902499 183.506)
		(end 237.135499 183.506)
		(width 0.177)
		(layer "F.Cu")
		(net 1)
	)
	(segment
		(start 201.0005 144.999499)
		(end 201.5 144.5)
		(width 0.256)
		(layer "F.Cu")
		(net 1)
	)
	(segment
		(start 164.952 106)
		(end 164.952 104.848)
		(width 0.38)
		(layer "F.Cu")
		(net 1)
	)
	(segment
		(start 210.851 110.598)
		(end 210.851 109.446)
		(width 0.38)
		(layer "F.Cu")
		(net 1)
	)
	(segment
		(start 134.173 156.474)
		(end 134.173 157.599)
		(width 0.15)
		(layer "F.Cu")
		(net 1)
	)
	(segment
		(start 189.65 195.324501)
		(end 189.65 199.25)
		(width 0.22)
		(layer "F.Cu")
		(net 1)
	)
	(segment
		(start 186.9995 158.0005)
		(end 186.5 158.5)
		(width 0.256)
		(layer "F.Cu")
		(net 1)
	)
	(segment
		(start 185.9995 158.0005)
		(end 185.5 158.5)
		(width 0.256)
		(layer "F.Cu")
		(net 1)
	)
	(segment
		(start 193.0005 140.9995)
		(end 193.5 140.5)
		(width 0.256)
		(layer "F.Cu")
		(net 1)
	)
	(segment
		(start 127.801 181.053)
		(end 126.152 181.053)
		(width 0.201)
		(layer "F.Cu")
		(net 1)
	)
	(segment
		(start 151.501 179.75)
		(end 152.15 179.75)
		(width 0.198)
		(layer "F.Cu")
		(net 1)
	)
	(segment
		(start 247.123 146.099)
		(end 247.1245 146.0975)
		(width 0.4)
		(layer "F.Cu")
		(net 1)
	)
	(segment
		(start 144.409 143.407851)
		(end 145.012149 143.407851)
		(width 0.256)
		(layer "F.Cu")
		(net 1)
	)
	(segment
		(start 114.773499 139.567)
		(end 114.755499 139.549)
		(width 0.4)
		(layer "F.Cu")
		(net 1)
	)
	(segment
		(start 229.55 161.847999)
		(end 230.701501 161.848)
		(width 0.4)
		(layer "F.Cu")
		(net 1)
	)
	(segment
		(start 181.9995 163.0005)
		(end 181.5 163.5)
		(width 0.256)
		(layer "F.Cu")
		(net 1)
	)
	(segment
		(start 190.000499 160.0005)
		(end 190.5 160.5)
		(width 0.256)
		(layer "F.Cu")
		(net 1)
	)
	(segment
		(start 128.516328 143.002859)
		(end 127.745626 143.002859)
		(width 0.2)
		(layer "F.Cu")
		(net 1)
	)
	(segment
		(start 202.351 106)
		(end 202.351 104.848)
		(width 0.38)
		(layer "F.Cu")
		(net 1)
	)
	(segment
		(start 198.0005 140.9995)
		(end 198.5 140.5)
		(width 0.256)
		(layer "F.Cu")
		(net 1)
	)
	(segment
		(start 162.65 195.374501)
		(end 162.65 199.25)
		(width 0.22)
		(layer "F.Cu")
		(net 1)
	)
	(segment
		(start 226.2495 163.140501)
		(end 226.0015 163.140501)
		(width 0.4)
		(layer "F.Cu")
		(net 1)
	)
	(segment
		(start 143.933 158.897)
		(end 143.933 158.2825)
		(width 0.15)
		(layer "F.Cu")
		(net 1)
	)
	(segment
		(start 140.407328 155.517328)
		(end 140.79 155.9)
		(width 0.256)
		(layer "F.Cu")
		(net 1)
	)
	(segment
		(start 200 160)
		(end 200.4995 160.4995)
		(width 0.256)
		(layer "F.Cu")
		(net 1)
	)
	(segment
		(start 159.125 194.849501)
		(end 159.65 195.374501)
		(width 0.22)
		(layer "F.Cu")
		(net 1)
	)
	(segment
		(start 199 160.999999)
		(end 199.4995 161.4995)
		(width 0.256)
		(layer "F.Cu")
		(net 1)
	)
	(segment
		(start 251.377998 129.769)
		(end 251.377998 129.049)
		(width 0.4)
		(layer "F.Cu")
		(net 1)
	)
	(segment
		(start 132.652 110.598)
		(end 132.652 109.446)
		(width 0.38)
		(layer "F.Cu")
		(net 1)
	)
	(segment
		(start 144.552 106)
		(end 144.552 104.848)
		(width 0.38)
		(layer "F.Cu")
		(net 1)
	)
	(segment
		(start 183.9995 163.0005)
		(end 183.5 163.5)
		(width 0.256)
		(layer "F.Cu")
		(net 1)
	)
	(segment
		(start 194.7 110.598)
		(end 194.7 109.446)
		(width 0.38)
		(layer "F.Cu")
		(net 1)
	)
	(segment
		(start 192 165)
		(end 191.5005 165.4995)
		(width 0.256)
		(layer "F.Cu")
		(net 1)
	)
	(segment
		(start 140.224499 181.849)
		(end 140.524499 181.549)
		(width 0.201)
		(layer "F.Cu")
		(net 1)
	)
	(segment
		(start 239.524499 155.0585)
		(end 239.274499 155.3085)
		(width 0.256)
		(layer "F.Cu")
		(net 1)
	)
	(segment
		(start 123.576 184.778)
		(end 123.576 182.917)
		(width 0.201)
		(layer "F.Cu")
		(net 1)
	)
	(segment
		(start 176.9995 158.0005)
		(end 176.5 158.5)
		(width 0.256)
		(layer "F.Cu")
		(net 1)
	)
	(segment
		(start 115.781 174.401)
		(end 115.781 173.772)
		(width 0.201)
		(layer "F.Cu")
		(net 1)
	)
	(segment
		(start 163.95 160.674999)
		(end 163.95 160.039999)
		(width 0.256)
		(layer "F.Cu")
		(net 1)
	)
	(segment
		(start 256.825 129.409)
		(end 256.825 129.986002)
		(width 0.256)
		(layer "F.Cu")
		(net 1)
	)
	(segment
		(start 175.999501 160.0005)
		(end 175.5 160.5)
		(width 0.256)
		(layer "F.Cu")
		(net 1)
	)
	(segment
		(start 109.539 146.96)
		(end 110.08 146.96)
		(width 0.256)
		(layer "F.Cu")
		(net 1)
	)
	(segment
		(start 246.903 141.101)
		(end 247.904 141.101)
		(width 0.256)
		(layer "F.Cu")
		(net 1)
	)
	(segment
		(start 121.5 164.48)
		(end 120.77 164.48)
		(width 0.1)
		(layer "F.Cu")
		(net 1)
	)
	(segment
		(start 129.307 172.113)
		(end 130.508 172.113)
		(width 0.201)
		(layer "F.Cu")
		(net 1)
	)
	(segment
		(start 119.806 186.1375)
		(end 120.461 186.1375)
		(width 0.256)
		(layer "F.Cu")
		(net 1)
	)
	(segment
		(start 252.936998 128.939)
		(end 254.189 128.939)
		(width 0.4)
		(layer "F.Cu")
		(net 1)
	)
	(segment
		(start 190.0005 153.0005)
		(end 190.5 153.5)
		(width 0.256)
		(layer "F.Cu")
		(net 1)
	)
	(segment
		(start 161.15 165.519999)
		(end 161.31 165.359999)
		(width 0.256)
		(layer "F.Cu")
		(net 1)
	)
	(segment
		(start 128.506 172.412)
		(end 128.506 172.113)
		(width 0.201)
		(layer "F.Cu")
		(net 1)
	)
	(segment
		(start 246.903 140.101)
		(end 247.904 140.101)
		(width 0.256)
		(layer "F.Cu")
		(net 1)
	)
	(segment
		(start 184.999501 146.9995)
		(end 184.5 146.5)
		(width 0.256)
		(layer "F.Cu")
		(net 1)
	)
	(segment
		(start 175.9995 139.9995)
		(end 175.5 139.5)
		(width 0.256)
		(layer "F.Cu")
		(net 1)
	)
	(segment
		(start 221.05 106)
		(end 221.05 104.848)
		(width 0.38)
		(layer "F.Cu")
		(net 1)
	)
	(segment
		(start 186.65 195.374501)
		(end 186.65 199.25)
		(width 0.22)
		(layer "F.Cu")
		(net 1)
	)
	(segment
		(start 175.9995 144.9995)
		(end 175.5 144.5)
		(width 0.256)
		(layer "F.Cu")
		(net 1)
	)
	(segment
		(start 186.9995 163.0005)
		(end 186.5 163.5)
		(width 0.256)
		(layer "F.Cu")
		(net 1)
	)
	(segment
		(start 128.191 186.1375)
		(end 128.826 186.1375)
		(width 0.256)
		(layer "F.Cu")
		(net 1)
	)
	(segment
		(start 129.67 147.34)
		(end 129.67 146.559)
		(width 0.4)
		(layer "F.Cu")
		(net 1)
	)
	(segment
		(start 107.33 147.56)
		(end 107.22 147.56)
		(width 0.2)
		(layer "F.Cu")
		(net 1)
	)
	(segment
		(start 158.31 160.299999)
		(end 159.81 161.799999)
		(width 0.177)
		(layer "F.Cu")
		(net 1)
	)
	(segment
		(start 189.175 194.849501)
		(end 189.65 195.324501)
		(width 0.22)
		(layer "F.Cu")
		(net 1)
	)
	(segment
		(start 136.65 154.9)
		(end 136.050843 154.300843)
		(width 0.15)
		(layer "F.Cu")
		(net 1)
	)
	(segment
		(start 198 165)
		(end 197.5005 165.4995)
		(width 0.256)
		(layer "F.Cu")
		(net 1)
	)
	(segment
		(start 176.852 106)
		(end 176.852 104.848)
		(width 0.38)
		(layer "F.Cu")
		(net 1)
	)
	(segment
		(start 241.774499 168.23)
		(end 242.389499 168.23)
		(width 0.256)
		(layer "F.Cu")
		(net 1)
	)
	(segment
		(start 182.9995 145.9995)
		(end 182.5 145.5)
		(width 0.256)
		(layer "F.Cu")
		(net 1)
	)
	(segment
		(start 254.45 129.2)
		(end 256.616 129.2)
		(width 0.4)
		(layer "F.Cu")
		(net 1)
	)
	(segment
		(start 188 165)
		(end 188 165.65)
		(width 0.256)
		(layer "F.Cu")
		(net 1)
	)
	(segment
		(start 150.5 106)
		(end 150.5 104.848)
		(width 0.38)
		(layer "F.Cu")
		(net 1)
	)
	(segment
		(start 131.008 172.113)
		(end 130.758 172.363)
		(width 0.201)
		(layer "F.Cu")
		(net 1)
	)
	(segment
		(start 111.326 171.0485)
		(end 112.037258 171.0485)
		(width 0.4)
		(layer "F.Cu")
		(net 1)
	)
	(segment
		(start 140.275499 186.298)
		(end 140.224499 186.349)
		(width 0.201)
		(layer "F.Cu")
		(net 1)
	)
	(segment
		(start 164.1 110.598)
		(end 164.1 109.446)
		(width 0.38)
		(layer "F.Cu")
		(net 1)
	)
	(segment
		(start 141.525 145.925)
		(end 141.525 145.391851)
		(width 0.256)
		(layer "F.Cu")
		(net 1)
	)
	(segment
		(start 136.8 154.9)
		(end 136.65 154.9)
		(width 0.15)
		(layer "F.Cu")
		(net 1)
	)
	(segment
		(start 186.9995 156.0005)
		(end 186.5 156.5)
		(width 0.256)
		(layer "F.Cu")
		(net 1)
	)
	(segment
		(start 241.803 137.101)
		(end 240.781 137.101)
		(width 0.4)
		(layer "F.Cu")
		(net 1)
	)
	(segment
		(start 181.65 195.374501)
		(end 181.65 199.25)
		(width 0.22)
		(layer "F.Cu")
		(net 1)
	)
	(segment
		(start 185.9995 150.999501)
		(end 185.5 150.5)
		(width 0.256)
		(layer "F.Cu")
		(net 1)
	)
	(segment
		(start 139.020499 181.645)
		(end 139.224499 181.849)
		(width 0.201)
		(layer "F.Cu")
		(net 1)
	)
	(segment
		(start 180.9995 139.9995)
		(end 180.5 139.5)
		(width 0.256)
		(layer "F.Cu")
		(net 1)
	)
	(segment
		(start 194.0005 148.9995)
		(end 194.5 148.5)
		(width 0.256)
		(layer "F.Cu")
		(net 1)
	)
	(segment
		(start 147.199 179.75)
		(end 147.199 179.101)
		(width 0.198)
		(layer "F.Cu")
		(net 1)
	)
	(segment
		(start 248.519499 138.574)
		(end 248.504499 138.589)
		(width 0.201)
		(layer "F.Cu")
		(net 1)
	)
	(segment
		(start 149.075843 166.321329)
		(end 149.105843 166.351328)
		(width 0.15)
		(layer "F.Cu")
		(net 1)
	)
	(segment
		(start 140.233499 168.615)
		(end 140.249499 168.631)
		(width 0.15)
		(layer "F.Cu")
		(net 1)
	)
	(segment
		(start 201.501 110.598)
		(end 201.501 109.446)
		(width 0.38)
		(layer "F.Cu")
		(net 1)
	)
	(segment
		(start 108.439499 143.749)
		(end 107.8265 143.749)
		(width 0.201)
		(layer "F.Cu")
		(net 1)
	)
	(segment
		(start 191.0005 149.9995)
		(end 191.500001 149.5)
		(width 0.256)
		(layer "F.Cu")
		(net 1)
	)
	(segment
		(start 196.0005 149.999499)
		(end 196.499999 149.5)
		(width 0.256)
		(layer "F.Cu")
		(net 1)
	)
	(segment
		(start 136.052 110.598)
		(end 136.052 109.446)
		(width 0.38)
		(layer "F.Cu")
		(net 1)
	)
	(segment
		(start 160.81 164.614999)
		(end 160.81 162.799999)
		(width 0.177)
		(layer "F.Cu")
		(net 1)
	)
	(segment
		(start 168.1 152.5)
		(end 167.6 152)
		(width 0.4)
		(layer "F.Cu")
		(net 1)
	)
	(segment
		(start 220.472001 148.098)
		(end 219.922 148.098)
		(width 0.15)
		(layer "F.Cu")
		(net 1)
	)
	(segment
		(start 147.951 106)
		(end 147.951 104.848)
		(width 0.38)
		(layer "F.Cu")
		(net 1)
	)
	(segment
		(start 191.0005 158.0005)
		(end 191.5 158.5)
		(width 0.256)
		(layer "F.Cu")
		(net 1)
	)
	(segment
		(start 256.616 129.2)
		(end 256.825 129.409)
		(width 0.4)
		(layer "F.Cu")
		(net 1)
	)
	(segment
		(start 208.14 154.94)
		(end 207.49 154.94)
		(width 0.201)
		(layer "F.Cu")
		(net 1)
	)
	(segment
		(start 187.175 194.849501)
		(end 186.65 195.374501)
		(width 0.22)
		(layer "F.Cu")
		(net 1)
	)
	(segment
		(start 233.465001 181.205)
		(end 233.94 181.205)
		(width 0.4)
		(layer "F.Cu")
		(net 1)
	)
	(segment
		(start 170.9 106)
		(end 170.9 104.848)
		(width 0.38)
		(layer "F.Cu")
		(net 1)
	)
	(segment
		(start 246.101 146.099)
		(end 247.123 146.099)
		(width 0.4)
		(layer "F.Cu")
		(net 1)
	)
	(segment
		(start 175.999501 165.0005)
		(end 175.5 165.5)
		(width 0.256)
		(layer "F.Cu")
		(net 1)
	)
	(segment
		(start 196.4 110.598)
		(end 196.4 109.446)
		(width 0.38)
		(layer "F.Cu")
		(net 1)
	)
	(segment
		(start 165.801 110.598)
		(end 165.801 109.446)
		(width 0.38)
		(layer "F.Cu")
		(net 1)
	)
	(segment
		(start 190.0005 148.9995)
		(end 190.5 148.5)
		(width 0.256)
		(layer "F.Cu")
		(net 1)
	)
	(segment
		(start 221.901 110.598)
		(end 221.901 109.446)
		(width 0.38)
		(layer "F.Cu")
		(net 1)
	)
	(segment
		(start 195.0005 162.0005)
		(end 195.5 162.5)
		(width 0.256)
		(layer "F.Cu")
		(net 1)
	)
	(segment
		(start 110.08 146.96)
		(end 110.09 146.97)
		(width 0.256)
		(layer "F.Cu")
		(net 1)
	)
	(segment
		(start 139.599499 168.615)
		(end 140.233499 168.615)
		(width 0.15)
		(layer "F.Cu")
		(net 1)
	)
	(segment
		(start 113.917499 182.5535)
		(end 114.632499 182.5535)
		(width 0.201)
		(layer "F.Cu")
		(net 1)
	)
	(segment
		(start 211.7 106)
		(end 211.7 104.848)
		(width 0.38)
		(layer "F.Cu")
		(net 1)
	)
	(segment
		(start 128.684 171.614)
		(end 128.506 171.792)
		(width 0.201)
		(layer "F.Cu")
		(net 1)
	)
	(segment
		(start 105.216 153.014)
		(end 102.514 153.014)
		(width 0.4)
		(layer "F.Cu")
		(net 1)
	)
	(segment
		(start 127.306 174.912)
		(end 127.306 175.542)
		(width 0.256)
		(layer "F.Cu")
		(net 1)
	)
	(segment
		(start 134.8135 165.5175)
		(end 134.814 165.518)
		(width 0.256)
		(layer "F.Cu")
		(net 1)
	)
	(segment
		(start 212.551 110.598)
		(end 212.551 109.446)
		(width 0.38)
		(layer "F.Cu")
		(net 1)
	)
	(segment
		(start 138.675499 186.298)
		(end 138.624499 186.349)
		(width 0.201)
		(layer "F.Cu")
		(net 1)
	)
	(segment
		(start 161.551 106)
		(end 161.551 104.848)
		(width 0.38)
		(layer "F.Cu")
		(net 1)
	)
	(segment
		(start 113.145499 182.5525)
		(end 112.430499 182.5525)
		(width 0.256)
		(layer "F.Cu")
		(net 1)
	)
	(segment
		(start 232.1 106)
		(end 232.1 104.848)
		(width 0.38)
		(layer "F.Cu")
		(net 1)
	)
	(segment
		(start 178.9995 162.000501)
		(end 178.500001 162.5)
		(width 0.256)
		(layer "F.Cu")
		(net 1)
	)
	(segment
		(start 153.051 110.598)
		(end 153.051 109.446)
		(width 0.38)
		(layer "F.Cu")
		(net 1)
	)
	(segment
		(start 145.924499 169.399)
		(end 145.974499 169.399)
		(width 0.15)
		(layer "F.Cu")
		(net 1)
	)
	(segment
		(start 217.65 106)
		(end 217.65 104.848)
		(width 0.38)
		(layer "F.Cu")
		(net 1)
	)
	(segment
		(start 158.06 165.499999)
		(end 158.06 165.834999)
		(width 0.256)
		(layer "F.Cu")
		(net 1)
	)
	(segment
		(start 193.125 194.849501)
		(end 193.65 195.374501)
		(width 0.22)
		(layer "F.Cu")
		(net 1)
	)
	(segment
		(start 119.623 158.223)
		(end 119.623 157.652)
		(width 0.182)
		(layer "F.Cu")
		(net 1)
	)
	(segment
		(start 184 165)
		(end 183.5005 165.4995)
		(width 0.256)
		(layer "F.Cu")
		(net 1)
	)
	(segment
		(start 146.25 106)
		(end 146.25 104.848)
		(width 0.38)
		(layer "F.Cu")
		(net 1)
	)
	(segment
		(start 221.595001 183.945001)
		(end 222.14 183.945)
		(width 0.1)
		(layer "F.Cu")
		(net 1)
	)
	(segment
		(start 182.9995 163.000499)
		(end 182.5 163.5)
		(width 0.256)
		(layer "F.Cu")
		(net 1)
	)
	(segment
		(start 158.31 165.249999)
		(end 158.06 165.499999)
		(width 0.256)
		(layer "F.Cu")
		(net 1)
	)
	(segment
		(start 182.999501 158.0005)
		(end 182.5 158.5)
		(width 0.256)
		(layer "F.Cu")
		(net 1)
	)
	(segment
		(start 184.9995 154.0005)
		(end 184.5 154.5)
		(width 0.256)
		(layer "F.Cu")
		(net 1)
	)
	(segment
		(start 192.0005 163.000499)
		(end 192.5 163.5)
		(width 0.256)
		(layer "F.Cu")
		(net 1)
	)
	(segment
		(start 237.026499 164.400001)
		(end 237.025999 164.3995)
		(width 0.256)
		(layer "F.Cu")
		(net 1)
	)
	(segment
		(start 230.701501 161.848)
		(end 231.0995 162.245999)
		(width 0.4)
		(layer "F.Cu")
		(net 1)
	)
	(segment
		(start 233.94 181.205)
		(end 233.95 181.215)
		(width 0.4)
		(layer "F.Cu")
		(net 1)
	)
	(segment
		(start 107.22 147.56)
		(end 106.733 147.073)
		(width 0.2)
		(layer "F.Cu")
		(net 1)
	)
	(segment
		(start 191.0005 144.9995)
		(end 191.5 144.500001)
		(width 0.256)
		(layer "F.Cu")
		(net 1)
	)
	(segment
		(start 145.859499 169.884)
		(end 145.724499 169.749)
		(width 0.15)
		(layer "F.Cu")
		(net 1)
	)
	(segment
		(start 137.5 154.904)
		(end 137.184328 155.219672)
		(width 0.256)
		(layer "F.Cu")
		(net 1)
	)
	(segment
		(start 241.45 106)
		(end 241.45 104.848)
		(width 0.38)
		(layer "F.Cu")
		(net 1)
	)
	(segment
		(start 180.252 106)
		(end 180.252 104.848)
		(width 0.38)
		(layer "F.Cu")
		(net 1)
	)
	(segment
		(start 141.434 167.640499)
		(end 141.425499 167.649)
		(width 0.15)
		(layer "F.Cu")
		(net 1)
	)
	(via
		(at 129.616328 139.072157)
		(size 0.45)
		(drill 0.1)
		(layers "F.Cu" "B.Cu")
		(remove_unused_layers yes)
		(keep_end_layers yes)
		(zone_layer_connections "In1.Cu" "In3.Cu" "In5.Cu" "In7.Cu" "In10.Cu")
		(net 1)
	)
	(via
		(at 139.774499 144.449)
		(size 0.45)
		(drill 0.1)
		(layers "F.Cu" "B.Cu")
		(remove_unused_layers yes)
		(keep_end_layers yes)
		(zone_layer_connections "In1.Cu" "In3.Cu" "In5.Cu" "In7.Cu" "In10.Cu")
		(net 1)
	)
	(via
		(at 143.316328 138.972157)
		(size 0.45)
		(drill 0.1)
		(layers "F.Cu" "B.Cu")
		(remove_unused_layers yes)
		(keep_end_layers yes)
		(zone_layer_connections "In1.Cu" "In3.Cu" "In5.Cu" "In7.Cu" "In10.Cu")
		(net 1)
	)
	(via
		(at 141.525 138.662149)
		(size 0.45)
		(drill 0.1)
		(layers "F.Cu" "B.Cu")
		(remove_unused_layers yes)
		(keep_end_layers yes)
		(zone_layer_connections "In1.Cu" "In3.Cu" "In5.Cu" "In7.Cu" "In10.Cu")
		(net 1)
	)
	(via
		(at 117.08 145.61)
		(size 0.45)
		(drill 0.1)
		(layers "F.Cu" "B.Cu")
		(remove_unused_layers yes)
		(keep_end_layers yes)
		(zone_layer_connections "In1.Cu" "In3.Cu" "In5.Cu" "In7.Cu" "In10.Cu")
		(net 1)
	)
	(via
		(at 197.251 104.848)
		(size 0.45)
		(drill 0.1)
		(layers "F.Cu" "B.Cu")
		(remove_unused_layers yes)
		(keep_end_layers yes)
		(zone_layer_connections "In1.Cu" "In3.Cu" "In5.Cu" "In7.Cu" "In10.Cu")
		(net 1)
	)
	(via
		(at 263.924499 188.669999)
		(size 0.45)
		(drill 0.1)
		(layers "F.Cu" "B.Cu")
		(remove_unused_layers yes)
		(keep_end_layers yes)
		(zone_layer_connections "In1.Cu" "In3.Cu" "In5.Cu" "In7.Cu" "In10.Cu")
		(net 1)
	)
	(via
		(at 253.975 129.55)
		(size 0.45)
		(drill 0.1)
		(layers "F.Cu" "B.Cu")
		(remove_unused_layers yes)
		(keep_end_layers yes)
		(zone_layer_connections "In1.Cu" "In3.Cu" "In5.Cu" "In7.Cu" "In10.Cu")
		(net 1)
	)
	(via
		(at 203.2 109.446)
		(size 0.45)
		(drill 0.1)
		(layers "F.Cu" "B.Cu")
		(remove_unused_layers yes)
		(keep_end_layers yes)
		(zone_layer_connections "In1.Cu" "In3.Cu" "In5.Cu" "In7.Cu" "In10.Cu")
		(net 1)
	)
	(via
		(at 214.58 176.95)
		(size 0.45)
		(drill 0.1)
		(layers "F.Cu" "B.Cu")
		(remove_unused_layers yes)
		(keep_end_layers yes)
		(zone_layer_connections "In1.Cu" "In3.Cu" "In5.Cu" "In7.Cu" "In10.Cu")
		(net 1)
	)
	(via
		(at 208.301 104.848)
		(size 0.45)
		(drill 0.1)
		(layers "F.Cu" "B.Cu")
		(remove_unused_layers yes)
		(keep_end_layers yes)
		(zone_layer_connections "In1.Cu" "In3.Cu" "In5.Cu" "In7.Cu" "In10.Cu")
		(net 1)
	)
	(via
		(at 223.335 168.36)
		(size 0.45)
		(drill 0.1)
		(layers "F.Cu" "B.Cu")
		(remove_unused_layers yes)
		(keep_end_layers yes)
		(zone_layer_connections "In1.Cu" "In3.Cu" "In5.Cu" "In7.Cu" "In10.Cu")
		(net 1)
	)
	(via
		(at 228.7 104.848)
		(size 0.45)
		(drill 0.1)
		(layers "F.Cu" "B.Cu")
		(remove_unused_layers yes)
		(keep_end_layers yes)
		(zone_layer_connections "In1.Cu" "In3.Cu" "In5.Cu" "In7.Cu" "In10.Cu")
		(net 1)
	)
	(via
		(at 207.3 151.45)
		(size 0.45)
		(drill 0.1)
		(layers "F.Cu" "B.Cu")
		(remove_unused_layers yes)
		(keep_end_layers yes)
		(zone_layer_connections "In1.Cu" "In3.Cu" "In5.Cu" "In7.Cu" "In10.Cu")
		(net 1)
	)
	(via
		(at 181.5 153.5)
		(size 0.45)
		(drill 0.1)
		(layers "F.Cu" "B.Cu")
		(remove_unused_layers yes)
		(keep_end_layers yes)
		(zone_layer_connections "In1.Cu" "In3.Cu" "In5.Cu" "In7.Cu" "In10.Cu")
		(net 1)
	)
	(via
		(at 195.498 100.510001)
		(size 0.45)
		(drill 0.1)
		(layers "F.Cu" "B.Cu")
		(remove_unused_layers yes)
		(keep_end_layers yes)
		(zone_layer_connections "In1.Cu" "In3.Cu" "In5.Cu" "In7.Cu" "In10.Cu")
		(net 1)
	)
	(via
		(at 262.474499 157.499)
		(size 0.45)
		(drill 0.1)
		(layers "F.Cu" "B.Cu")
		(remove_unused_layers yes)
		(keep_end_layers yes)
		(zone_layer_connections "In1.Cu" "In3.Cu" "In5.Cu" "In6.Cu" "In7.Cu" "In10.Cu")
		(net 1)
	)
	(via
		(at 194.5 148.5)
		(size 0.45)
		(drill 0.1)
		(layers "F.Cu" "B.Cu")
		(remove_unused_layers yes)
		(keep_end_layers yes)
		(zone_layer_connections "In1.Cu" "In3.Cu" "In5.Cu" "In7.Cu" "In10.Cu")
		(net 1)
	)
	(via
		(at 193.851 104.848)
		(size 0.45)
		(drill 0.1)
		(layers "F.Cu" "B.Cu")
		(remove_unused_layers yes)
		(keep_end_layers yes)
		(zone_layer_connections "In1.Cu" "In3.Cu" "In5.Cu" "In7.Cu" "In10.Cu")
		(net 1)
	)
	(via
		(at 181.952 104.848)
		(size 0.45)
		(drill 0.1)
		(layers "F.Cu" "B.Cu")
		(remove_unused_layers yes)
		(keep_end_layers yes)
		(zone_layer_connections "In1.Cu" "In3.Cu" "In5.Cu" "In7.Cu" "In10.Cu")
		(net 1)
	)
	(via
		(at 223.335 170.485)
		(size 0.45)
		(drill 0.1)
		(layers "F.Cu" "B.Cu")
		(remove_unused_layers yes)
		(keep_end_layers yes)
		(zone_layer_connections "In1.Cu" "In3.Cu" "In5.Cu" "In7.Cu" "In10.Cu")
		(net 1)
	)
	(via
		(at 192.5 160.5)
		(size 0.45)
		(drill 0.1)
		(layers "F.Cu" "B.Cu")
		(remove_unused_layers yes)
		(keep_end_layers yes)
		(zone_layer_connections "In1.Cu" "In3.Cu" "In5.Cu" "In7.Cu" "In10.Cu")
		(net 1)
	)
	(via
		(at 127.306 174.912)
		(size 0.45)
		(drill 0.1)
		(layers "F.Cu" "B.Cu")
		(remove_unused_layers yes)
		(keep_end_layers yes)
		(zone_layer_connections "In1.Cu" "In3.Cu" "In5.Cu" "In7.Cu" "In10.Cu")
		(net 1)
	)
	(via
		(at 224.935 186.805)
		(size 0.45)
		(drill 0.1)
		(layers "F.Cu" "B.Cu")
		(remove_unused_layers yes)
		(keep_end_layers yes)
		(zone_layer_connections "In1.Cu" "In3.Cu" "In5.Cu" "In7.Cu" "In10.Cu")
		(net 1)
	)
	(via
		(at 175.5 158.5)
		(size 0.45)
		(drill 0.1)
		(layers "F.Cu" "B.Cu")
		(remove_unused_layers yes)
		(keep_end_layers yes)
		(zone_layer_connections "In1.Cu" "In3.Cu" "In5.Cu" "In7.Cu" "In10.Cu")
		(net 1)
	)
	(via
		(at 105.824499 150.43)
		(size 0.45)
		(drill 0.1)
		(layers "F.Cu" "B.Cu")
		(remove_unused_layers yes)
		(keep_end_layers yes)
		(zone_layer_connections "In1.Cu" "In3.Cu" "In5.Cu" "In7.Cu" "In10.Cu")
		(net 1)
	)
	(via
		(at 148.275499 168.034)
		(size 0.45)
		(drill 0.1)
		(layers "F.Cu" "B.Cu")
		(remove_unused_layers yes)
		(keep_end_layers yes)
		(zone_layer_connections "In1.Cu" "In3.Cu" "In5.Cu" "In7.Cu" "In10.Cu")
		(net 1)
	)
	(via
		(at 251.551499 171.8)
		(size 0.45)
		(drill 0.1)
		(layers "F.Cu" "B.Cu")
		(remove_unused_layers yes)
		(keep_end_layers yes)
		(zone_layer_connections "In1.Cu" "In2.Cu" "In3.Cu" "In4.Cu" "In5.Cu" "In6.Cu"
			"In7.Cu" "In10.Cu"
		)
		(net 1)
	)
	(via
		(at 149.652 109.446)
		(size 0.45)
		(drill 0.1)
		(layers "F.Cu" "B.Cu")
		(remove_unused_layers yes)
		(keep_end_layers yes)
		(zone_layer_connections "In1.Cu" "In3.Cu" "In5.Cu" "In7.Cu" "In10.Cu")
		(net 1)
	)
	(via
		(at 141.8 125.925)
		(size 0.45)
		(drill 0.1)
		(layers "F.Cu" "B.Cu")
		(remove_unused_layers yes)
		(keep_end_layers yes)
		(zone_layer_connections "In1.Cu" "In3.Cu" "In5.Cu" "In7.Cu" "In9.Cu" "In10.Cu")
		(net 1)
	)
	(via
		(at 227.85 109.446)
		(size 0.45)
		(drill 0.1)
		(layers "F.Cu" "B.Cu")
		(remove_unused_layers yes)
		(keep_end_layers yes)
		(zone_layer_connections "In1.Cu" "In3.Cu" "In5.Cu" "In7.Cu" "In10.Cu")
		(net 1)
	)
	(via
		(at 213.035 184.485)
		(size 0.45)
		(drill 0.1)
		(layers "F.Cu" "B.Cu")
		(remove_unused_layers yes)
		(keep_end_layers yes)
		(zone_layer_connections "In1.Cu" "In3.Cu" "In5.Cu" "In7.Cu" "In10.Cu")
		(net 1)
	)
	(via
		(at 105.824499 183.849)
		(size 0.45)
		(drill 0.1)
		(layers "F.Cu" "B.Cu")
		(remove_unused_layers yes)
		(keep_end_layers yes)
		(zone_layer_connections "In1.Cu" "In3.Cu" "In5.Cu" "In7.Cu" "In10.Cu")
		(net 1)
	)
	(via
		(at 220.2 109.446)
		(size 0.45)
		(drill 0.1)
		(layers "F.Cu" "B.Cu")
		(remove_unused_layers yes)
		(keep_end_layers yes)
		(zone_layer_connections "In1.Cu" "In3.Cu" "In5.Cu" "In7.Cu" "In10.Cu")
		(net 1)
	)
	(via
		(at 254.194999 153.9005)
		(size 0.45)
		(drill 0.1)
		(layers "F.Cu" "B.Cu")
		(remove_unused_layers yes)
		(keep_end_layers yes)
		(zone_layer_connections "In1.Cu" "In2.Cu" "In3.Cu" "In4.Cu" "In5.Cu" "In6.Cu"
			"In7.Cu" "In10.Cu"
		)
		(net 1)
	)
	(via
		(at 263.51 114.06)
		(size 0.45)
		(drill 0.1)
		(layers "F.Cu" "B.Cu")
		(remove_unused_layers yes)
		(keep_end_layers yes)
		(zone_layer_connections "In1.Cu" "In3.Cu" "In5.Cu" "In7.Cu" "In10.Cu")
		(net 1)
	)
	(via
		(at 131.215828 137.035)
		(size 0.45)
		(drill 0.1)
		(layers "F.Cu" "B.Cu")
		(remove_unused_layers yes)
		(keep_end_layers yes)
		(zone_layer_connections "In1.Cu" "In3.Cu" "In5.Cu" "In7.Cu" "In10.Cu")
		(net 1)
	)
	(via
		(at 156.452 109.446)
		(size 0.45)
		(drill 0.1)
		(layers "F.Cu" "B.Cu")
		(remove_unused_layers yes)
		(keep_end_layers yes)
		(zone_layer_connections "In1.Cu" "In3.Cu" "In5.Cu" "In7.Cu" "In10.Cu")
		(net 1)
	)
	(via
		(at 242.11 122.42)
		(size 0.45)
		(drill 0.1)
		(layers "F.Cu" "B.Cu")
		(remove_unused_layers yes)
		(keep_end_layers yes)
		(zone_layer_connections "In1.Cu" "In3.Cu" "In5.Cu" "In7.Cu" "In10.Cu")
		(net 1)
	)
	(via
		(at 255.645 183.48)
		(size 0.45)
		(drill 0.1)
		(layers "F.Cu" "B.Cu")
		(remove_unused_layers yes)
		(keep_end_layers yes)
		(zone_layer_connections "In1.Cu" "In3.Cu" "In5.Cu" "In7.Cu" "In10.Cu")
		(net 1)
	)
	(via
		(at 225.51 102.73)
		(size 0.45)
		(drill 0.1)
		(layers "F.Cu" "B.Cu")
		(remove_unused_layers yes)
		(keep_end_layers yes)
		(zone_layer_connections "In1.Cu" "In3.Cu" "In5.Cu" "In7.Cu" "In10.Cu")
		(net 1)
	)
	(via
		(at 173.098 100.510001)
		(size 0.45)
		(drill 0.1)
		(layers "F.Cu" "B.Cu")
		(remove_unused_layers yes)
		(keep_end_layers yes)
		(zone_layer_connections "In1.Cu" "In3.Cu" "In5.Cu" "In7.Cu" "In10.Cu")
		(net 1)
	)
	(via
		(at 253.024499 168.749)
		(size 0.45)
		(drill 0.1)
		(layers "F.Cu" "B.Cu")
		(remove_unused_layers yes)
		(keep_end_layers yes)
		(zone_layer_connections "In1.Cu" "In3.Cu" "In4.Cu" "In5.Cu" "In6.Cu" "In7.Cu"
			"In10.Cu"
		)
		(net 1)
	)
	(via
		(at 255.31 189.46)
		(size 0.45)
		(drill 0.1)
		(layers "F.Cu" "B.Cu")
		(remove_unused_layers yes)
		(keep_end_layers yes)
		(zone_layer_connections "In1.Cu" "In3.Cu" "In5.Cu" "In7.Cu" "In10.Cu")
		(net 1)
	)
	(via
		(at 193.125 194.849501)
		(size 0.45)
		(drill 0.1)
		(layers "F.Cu" "B.Cu")
		(remove_unused_layers yes)
		(keep_end_layers yes)
		(zone_layer_connections "In1.Cu" "In3.Cu" "In5.Cu" "In7.Cu" "In10.Cu")
		(net 1)
	)
	(via
		(at 109.824499 142.249)
		(size 0.45)
		(drill 0.1)
		(layers "F.Cu" "B.Cu")
		(remove_unused_layers yes)
		(keep_end_layers yes)
		(zone_layer_connections "In1.Cu" "In3.Cu" "In5.Cu" "In7.Cu" "In10.Cu")
		(net 1)
	)
	(via
		(at 143.661 158.0105)
		(size 0.45)
		(drill 0.1)
		(layers "F.Cu" "B.Cu")
		(remove_unused_layers yes)
		(keep_end_layers yes)
		(zone_layer_connections "In1.Cu" "In3.Cu" "In5.Cu" "In7.Cu" "In10.Cu")
		(net 1)
	)
	(via
		(at 125.15 126.499)
		(size 0.45)
		(drill 0.1)
		(layers "F.Cu" "B.Cu")
		(remove_unused_layers yes)
		(keep_end_layers yes)
		(zone_layer_connections "In1.Cu" "In3.Cu" "In5.Cu" "In7.Cu" "In9.Cu" "In10.Cu")
		(net 1)
	)
	(via
		(at 237.098 100.510001)
		(size 0.45)
		(drill 0.1)
		(layers "F.Cu" "B.Cu")
		(remove_unused_layers yes)
		(keep_end_layers yes)
		(zone_layer_connections "In1.Cu" "In3.Cu" "In5.Cu" "In7.Cu" "In10.Cu")
		(net 1)
	)
	(via
		(at 252.824499 159.149)
		(size 0.45)
		(drill 0.1)
		(layers "F.Cu" "B.Cu")
		(remove_unused_layers yes)
		(keep_end_layers yes)
		(zone_layer_connections "In1.Cu" "In2.Cu" "In3.Cu" "In4.Cu" "In5.Cu" "In6.Cu"
			"In7.Cu" "In10.Cu"
		)
		(net 1)
	)
	(via
		(at 247.414499 132.834)
		(size 0.45)
		(drill 0.1)
		(layers "F.Cu" "B.Cu")
		(remove_unused_layers yes)
		(keep_end_layers yes)
		(zone_layer_connections "In1.Cu" "In3.Cu" "In5.Cu" "In7.Cu" "In10.Cu")
		(net 1)
	)
	(via
		(at 129.67 147.34)
		(size 0.45)
		(drill 0.1)
		(layers "F.Cu" "B.Cu")
		(remove_unused_layers yes)
		(keep_end_layers yes)
		(zone_layer_connections "In1.Cu" "In3.Cu" "In5.Cu" "In7.Cu" "In10.Cu")
		(net 1)
	)
	(via
		(at 136.8766 100.5096)
		(size 0.45)
		(drill 0.1)
		(layers "F.Cu" "B.Cu")
		(remove_unused_layers yes)
		(keep_end_layers yes)
		(zone_layer_connections "In1.Cu" "In3.Cu" "In5.Cu" "In7.Cu" "In10.Cu")
		(net 1)
	)
	(via
		(at 212.635 168.285)
		(size 0.45)
		(drill 0.1)
		(layers "F.Cu" "B.Cu")
		(remove_unused_layers yes)
		(keep_end_layers yes)
		(zone_layer_connections "In1.Cu" "In3.Cu" "In5.Cu" "In7.Cu" "In10.Cu")
		(net 1)
	)
	(via
		(at 132.11 176.9285)
		(size 0.45)
		(drill 0.1)
		(layers "F.Cu" "B.Cu")
		(remove_unused_layers yes)
		(keep_end_layers yes)
		(zone_layer_connections "In1.Cu" "In3.Cu" "In5.Cu" "In7.Cu" "In10.Cu")
		(net 1)
	)
	(via
		(at 226.55 121.38)
		(size 0.45)
		(drill 0.1)
		(layers "F.Cu" "B.Cu")
		(remove_unused_layers yes)
		(keep_end_layers yes)
		(zone_layer_connections "In1.Cu" "In3.Cu" "In5.Cu" "In7.Cu" "In10.Cu")
		(net 1)
	)
	(via
		(at 189.5 151.500001)
		(size 0.45)
		(drill 0.1)
		(layers "F.Cu" "B.Cu")
		(remove_unused_layers yes)
		(keep_end_layers yes)
		(zone_layer_connections "In1.Cu" "In3.Cu" "In5.Cu" "In7.Cu" "In10.Cu")
		(net 1)
	)
	(via
		(at 137.5 154.904)
		(size 0.45)
		(drill 0.1)
		(layers "F.Cu" "B.Cu")
		(remove_unused_layers yes)
		(keep_end_layers yes)
		(zone_layer_connections "In1.Cu" "In3.Cu" "In5.Cu" "In7.Cu" "In10.Cu")
		(net 1)
	)
	(via
		(at 204.495 107.75)
		(size 0.45)
		(drill 0.1)
		(layers "F.Cu" "B.Cu")
		(remove_unused_layers yes)
		(keep_end_layers yes)
		(zone_layer_connections "In1.Cu" "In3.Cu" "In5.Cu" "In7.Cu" "In10.Cu")
		(net 1)
	)
	(via
		(at 251.524499 154.349)
		(size 0.45)
		(drill 0.1)
		(layers "F.Cu" "B.Cu")
		(remove_unused_layers yes)
		(keep_end_layers yes)
		(zone_layer_connections "In1.Cu" "In2.Cu" "In3.Cu" "In4.Cu" "In5.Cu" "In6.Cu"
			"In7.Cu" "In10.Cu"
		)
		(net 1)
	)
	(via
		(at 223.735 175.76)
		(size 0.45)
		(drill 0.1)
		(layers "F.Cu" "B.Cu")
		(remove_unused_layers yes)
		(keep_end_layers yes)
		(zone_layer_connections "In1.Cu" "In3.Cu" "In5.Cu" "In7.Cu" "In10.Cu")
		(net 1)
	)
	(via
		(at 261.375 140.375)
		(size 0.45)
		(drill 0.1)
		(layers "F.Cu" "B.Cu")
		(remove_unused_layers yes)
		(keep_end_layers yes)
		(zone_layer_connections "In1.Cu" "In3.Cu" "In5.Cu" "In7.Cu" "In10.Cu")
		(net 1)
	)
	(via
		(at 252.85 176.6)
		(size 0.45)
		(drill 0.1)
		(layers "F.Cu" "B.Cu")
		(remove_unused_layers yes)
		(keep_end_layers yes)
		(zone_layer_connections "In1.Cu" "In2.Cu" "In3.Cu" "In4.Cu" "In5.Cu" "In6.Cu"
			"In7.Cu" "In10.Cu"
		)
		(net 1)
	)
	(via
		(at 254.48 114.785)
		(size 0.45)
		(drill 0.1)
		(layers "F.Cu" "B.Cu")
		(remove_unused_layers yes)
		(keep_end_layers yes)
		(zone_layer_connections "In1.Cu" "In3.Cu" "In5.Cu" "In7.Cu" "In10.Cu")
		(net 1)
	)
	(via
		(at 263.36 112.76)
		(size 0.45)
		(drill 0.1)
		(layers "F.Cu" "B.Cu")
		(remove_unused_layers yes)
		(keep_end_layers yes)
		(zone_layer_connections "In1.Cu" "In3.Cu" "In5.Cu" "In7.Cu" "In10.Cu")
		(net 1)
	)
	(via
		(at 116.435 110.9)
		(size 0.45)
		(drill 0.1)
		(layers "F.Cu" "B.Cu")
		(remove_unused_layers yes)
		(keep_end_layers yes)
		(zone_layer_connections "In1.Cu" "In3.Cu" "In5.Cu" "In7.Cu" "In10.Cu")
		(net 1)
	)
	(via
		(at 235.06 170.46)
		(size 0.45)
		(drill 0.1)
		(layers "F.Cu" "B.Cu")
		(remove_unused_layers yes)
		(keep_end_layers yes)
		(zone_layer_connections "In1.Cu" "In3.Cu" "In5.Cu" "In7.Cu" "In10.Cu")
		(net 1)
	)
	(via
		(at 210.851 109.446)
		(size 0.45)
		(drill 0.1)
		(layers "F.Cu" "B.Cu")
		(remove_unused_layers yes)
		(keep_end_layers yes)
		(zone_layer_connections "In1.Cu" "In3.Cu" "In5.Cu" "In7.Cu" "In10.Cu")
		(net 1)
	)
	(via
		(at 254.7 127.55)
		(size 0.45)
		(drill 0.1)
		(layers "F.Cu" "B.Cu")
		(remove_unused_layers yes)
		(keep_end_layers yes)
		(zone_layer_connections "In1.Cu" "In3.Cu" "In5.Cu" "In7.Cu" "In10.Cu")
		(net 1)
	)
	(via
		(at 187.5 155.5)
		(size 0.45)
		(drill 0.1)
		(layers "F.Cu" "B.Cu")
		(remove_unused_layers yes)
		(keep_end_layers yes)
		(zone_layer_connections "In1.Cu" "In3.Cu" "In5.Cu" "In7.Cu" "In10.Cu")
		(net 1)
	)
	(via
		(at 110.224499 188.649)
		(size 0.45)
		(drill 0.1)
		(layers "F.Cu" "B.Cu")
		(remove_unused_layers yes)
		(keep_end_layers yes)
		(zone_layer_connections "In1.Cu" "In3.Cu" "In5.Cu" "In7.Cu" "In10.Cu")
		(net 1)
	)
	(via
		(at 263.51 114.74)
		(size 0.45)
		(drill 0.1)
		(layers "F.Cu" "B.Cu")
		(remove_unused_layers yes)
		(keep_end_layers yes)
		(zone_layer_connections "In1.Cu" "In3.Cu" "In5.Cu" "In7.Cu" "In10.Cu")
		(net 1)
	)
	(via
		(at 164.952 104.848)
		(size 0.45)
		(drill 0.1)
		(layers "F.Cu" "B.Cu")
		(remove_unused_layers yes)
		(keep_end_layers yes)
		(zone_layer_connections "In1.Cu" "In3.Cu" "In5.Cu" "In7.Cu" "In10.Cu")
		(net 1)
	)
	(via
		(at 116.624499 188.649)
		(size 0.45)
		(drill 0.1)
		(layers "F.Cu" "B.Cu")
		(remove_unused_layers yes)
		(keep_end_layers yes)
		(zone_layer_connections "In1.Cu" "In3.Cu" "In5.Cu" "In7.Cu" "In10.Cu")
		(net 1)
	)
	(via
		(at 134.811 158.799)
		(size 0.45)
		(drill 0.1)
		(layers "F.Cu" "B.Cu")
		(remove_unused_layers yes)
		(keep_end_layers yes)
		(zone_layer_connections "In1.Cu" "In3.Cu" "In5.Cu" "In7.Cu" "In10.Cu")
		(net 1)
	)
	(via
		(at 204.875 176.4)
		(size 0.45)
		(drill 0.1)
		(layers "F.Cu" "B.Cu")
		(remove_unused_layers yes)
		(keep_end_layers yes)
		(zone_layer_connections "In1.Cu" "In3.Cu" "In5.Cu" "In7.Cu" "In10.Cu")
		(net 1)
	)
	(via
		(at 177.5 150.5)
		(size 0.45)
		(drill 0.1)
		(layers "F.Cu" "B.Cu")
		(remove_unused_layers yes)
		(keep_end_layers yes)
		(zone_layer_connections "In1.Cu" "In3.Cu" "In5.Cu" "In7.Cu" "In10.Cu")
		(net 1)
	)
	(via
		(at 247.325 155.35)
		(size 0.45)
		(drill 0.1)
		(layers "F.Cu" "B.Cu")
		(remove_unused_layers yes)
		(keep_end_layers yes)
		(zone_layer_connections "In1.Cu" "In2.Cu" "In3.Cu" "In4.Cu" "In5.Cu" "In6.Cu"
			"In7.Cu" "In10.Cu"
		)
		(net 1)
	)
	(via
		(at 254.67 112.795)
		(size 0.45)
		(drill 0.1)
		(layers "F.Cu" "B.Cu")
		(remove_unused_layers yes)
		(keep_end_layers yes)
		(zone_layer_connections "In1.Cu" "In3.Cu" "In5.Cu" "In7.Cu" "In10.Cu")
		(net 1)
	)
	(via
		(at 253.098 100.510001)
		(size 0.45)
		(drill 0.1)
		(layers "F.Cu" "B.Cu")
		(remove_unused_layers yes)
		(keep_end_layers yes)
		(zone_layer_connections "In1.Cu" "In3.Cu" "In5.Cu" "In7.Cu" "In10.Cu")
		(net 1)
	)
	(via
		(at 123.8871 100.4791)
		(size 0.45)
		(drill 0.1)
		(layers "F.Cu" "B.Cu")
		(remove_unused_layers yes)
		(keep_end_layers yes)
		(zone_layer_connections "In1.Cu" "In3.Cu" "In5.Cu" "In7.Cu" "In10.Cu")
		(net 1)
	)
	(via
		(at 253.824499 159.349)
		(size 0.45)
		(drill 0.1)
		(layers "F.Cu" "B.Cu")
		(remove_unused_layers yes)
		(keep_end_layers yes)
		(zone_layer_connections "In1.Cu" "In2.Cu" "In3.Cu" "In4.Cu" "In5.Cu" "In6.Cu"
			"In7.Cu" "In10.Cu"
		)
		(net 1)
	)
	(via
		(at 188.875 107.75)
		(size 0.45)
		(drill 0.1)
		(layers "F.Cu" "B.Cu")
		(remove_unused_layers yes)
		(keep_end_layers yes)
		(zone_layer_connections "In1.Cu" "In3.Cu" "In5.Cu" "In7.Cu" "In10.Cu")
		(net 1)
	)
	(via
		(at 255.621999 174.0515)
		(size 0.45)
		(drill 0.1)
		(layers "F.Cu" "B.Cu")
		(remove_unused_layers yes)
		(keep_end_layers yes)
		(zone_layer_connections "In1.Cu" "In2.Cu" "In3.Cu" "In4.Cu" "In5.Cu" "In6.Cu"
			"In7.Cu" "In10.Cu"
		)
		(net 1)
	)
	(via
		(at 127.552 104.848)
		(size 0.45)
		(drill 0.1)
		(layers "F.Cu" "B.Cu")
		(remove_unused_layers yes)
		(keep_end_layers yes)
		(zone_layer_connections "In1.Cu" "In3.Cu" "In5.Cu" "In7.Cu" "In10.Cu")
		(net 1)
	)
	(via
		(at 254.7825 173.622)
		(size 0.45)
		(drill 0.1)
		(layers "F.Cu" "B.Cu")
		(remove_unused_layers yes)
		(keep_end_layers yes)
		(zone_layer_connections "In1.Cu" "In2.Cu" "In3.Cu" "In4.Cu" "In5.Cu" "In6.Cu"
			"In7.Cu" "In10.Cu"
		)
		(net 1)
	)
	(via
		(at 211.935 186.535)
		(size 0.45)
		(drill 0.1)
		(layers "F.Cu" "B.Cu")
		(remove_unused_layers yes)
		(keep_end_layers yes)
		(zone_layer_connections "In1.Cu" "In3.Cu" "In5.Cu" "In7.Cu" "In10.Cu")
		(net 1)
	)
	(via
		(at 116.435 113.6)
		(size 0.45)
		(drill 0.1)
		(layers "F.Cu" "B.Cu")
		(remove_unused_layers yes)
		(keep_end_layers yes)
		(zone_layer_connections "In1.Cu" "In3.Cu" "In5.Cu" "In7.Cu" "In10.Cu")
		(net 1)
	)
	(via
		(at 182.5 158.5)
		(size 0.45)
		(drill 0.1)
		(layers "F.Cu" "B.Cu")
		(remove_unused_layers yes)
		(keep_end_layers yes)
		(zone_layer_connections "In1.Cu" "In3.Cu" "In5.Cu" "In7.Cu" "In10.Cu")
		(net 1)
	)
	(via
		(at 113.424499 188.649)
		(size 0.45)
		(drill 0.1)
		(layers "F.Cu" "B.Cu")
		(remove_unused_layers yes)
		(keep_end_layers yes)
		(zone_layer_connections "In1.Cu" "In3.Cu" "In5.Cu" "In7.Cu" "In10.Cu")
		(net 1)
	)
	(via
		(at 142.85 104.848)
		(size 0.45)
		(drill 0.1)
		(layers "F.Cu" "B.Cu")
		(remove_unused_layers yes)
		(keep_end_layers yes)
		(zone_layer_connections "In1.Cu" "In3.Cu" "In5.Cu" "In7.Cu" "In10.Cu")
		(net 1)
	)
	(via
		(at 224.535 174.735)
		(size 0.45)
		(drill 0.1)
		(layers "F.Cu" "B.Cu")
		(remove_unused_layers yes)
		(keep_end_layers yes)
		(zone_layer_connections "In1.Cu" "In3.Cu" "In5.Cu" "In7.Cu" "In10.Cu")
		(net 1)
	)
	(via
		(at 185.5 144.5)
		(size 0.45)
		(drill 0.1)
		(layers "F.Cu" "B.Cu")
		(remove_unused_layers yes)
		(keep_end_layers yes)
		(zone_layer_connections "In1.Cu" "In3.Cu" "In5.Cu" "In7.Cu" "In10.Cu")
		(net 1)
	)
	(via
		(at 239.751 107.152)
		(size 0.45)
		(drill 0.1)
		(layers "F.Cu" "B.Cu")
		(remove_unused_layers yes)
		(keep_end_layers yes)
		(zone_layer_connections "In1.Cu" "In3.Cu" "In5.Cu" "In7.Cu" "In10.Cu")
		(net 1)
	)
	(via
		(at 191.5 144.500001)
		(size 0.45)
		(drill 0.1)
		(layers "F.Cu" "B.Cu")
		(remove_unused_layers yes)
		(keep_end_layers yes)
		(zone_layer_connections "In1.Cu" "In3.Cu" "In5.Cu" "In7.Cu" "In10.Cu")
		(net 1)
	)
	(via
		(at 188.5 152.5)
		(size 0.45)
		(drill 0.1)
		(layers "F.Cu" "B.Cu")
		(remove_unused_layers yes)
		(keep_end_layers yes)
		(zone_layer_connections "In1.Cu" "In3.Cu" "In5.Cu" "In7.Cu" "In10.Cu")
		(net 1)
	)
	(via
		(at 105.775 157.869)
		(size 0.45)
		(drill 0.1)
		(layers "F.Cu" "B.Cu")
		(remove_unused_layers yes)
		(keep_end_layers yes)
		(zone_layer_connections "In1.Cu" "In3.Cu" "In5.Cu" "In7.Cu" "In10.Cu")
		(net 1)
	)
	(via
		(at 214.1 182.3)
		(size 0.45)
		(drill 0.1)
		(layers "F.Cu" "B.Cu")
		(remove_unused_layers yes)
		(keep_end_layers yes)
		(zone_layer_connections "In1.Cu" "In3.Cu" "In5.Cu" "In7.Cu" "In10.Cu")
		(net 1)
	)
	(via
		(at 247.349499 172.749)
		(size 0.45)
		(drill 0.1)
		(layers "F.Cu" "B.Cu")
		(remove_unused_layers yes)
		(keep_end_layers yes)
		(zone_layer_connections "In1.Cu" "In2.Cu" "In3.Cu" "In4.Cu" "In5.Cu" "In6.Cu"
			"In7.Cu" "In10.Cu"
		)
		(net 1)
	)
	(via
		(at 208.298 100.510001)
		(size 0.45)
		(drill 0.1)
		(layers "F.Cu" "B.Cu")
		(remove_unused_layers yes)
		(keep_end_layers yes)
		(zone_layer_connections "In1.Cu" "In3.Cu" "In5.Cu" "In7.Cu" "In10.Cu")
		(net 1)
	)
	(via
		(at 136.902 104.848)
		(size 0.45)
		(drill 0.1)
		(layers "F.Cu" "B.Cu")
		(remove_unused_layers yes)
		(keep_end_layers yes)
		(zone_layer_connections "In1.Cu" "In3.Cu" "In5.Cu" "In7.Cu" "In10.Cu")
		(net 1)
	)
	(via
		(at 261.324499 175.024)
		(size 0.45)
		(drill 0.1)
		(layers "F.Cu" "B.Cu")
		(remove_unused_layers yes)
		(keep_end_layers yes)
		(zone_layer_connections "In1.Cu" "In3.Cu" "In5.Cu" "In6.Cu" "In7.Cu" "In10.Cu")
		(net 1)
	)
	(via
		(at 195.5 163.5)
		(size 0.45)
		(drill 0.1)
		(layers "F.Cu" "B.Cu")
		(remove_unused_layers yes)
		(keep_end_layers yes)
		(zone_layer_connections "In1.Cu" "In3.Cu" "In5.Cu" "In7.Cu" "In10.Cu")
		(net 1)
	)
	(via
		(at 196.5 139.5)
		(size 0.45)
		(drill 0.1)
		(layers "F.Cu" "B.Cu")
		(remove_unused_layers yes)
		(keep_end_layers yes)
		(zone_layer_connections "In1.Cu" "In3.Cu" "In5.Cu" "In7.Cu" "In10.Cu")
		(net 1)
	)
	(via
		(at 178.5 163.5)
		(size 0.45)
		(drill 0.1)
		(layers "F.Cu" "B.Cu")
		(remove_unused_layers yes)
		(keep_end_layers yes)
		(zone_layer_connections "In1.Cu" "In3.Cu" "In5.Cu" "In7.Cu" "In10.Cu")
		(net 1)
	)
	(via
		(at 115.781 173.772)
		(size 0.45)
		(drill 0.1)
		(layers "F.Cu" "B.Cu")
		(remove_unused_layers yes)
		(keep_end_layers yes)
		(zone_layer_connections "In1.Cu" "In3.Cu" "In5.Cu" "In7.Cu" "In10.Cu")
		(net 1)
	)
	(via
		(at 138.1495 101.1895)
		(size 0.45)
		(drill 0.1)
		(layers "F.Cu" "B.Cu")
		(remove_unused_layers yes)
		(keep_end_layers yes)
		(zone_layer_connections "In1.Cu" "In3.Cu" "In5.Cu" "In7.Cu" "In10.Cu")
		(net 1)
	)
	(via
		(at 227.6 185.95)
		(size 0.45)
		(drill 0.1)
		(layers "F.Cu" "B.Cu")
		(remove_unused_layers yes)
		(keep_end_layers yes)
		(zone_layer_connections "In1.Cu" "In3.Cu" "In5.Cu" "In7.Cu" "In10.Cu")
		(net 1)
	)
	(via
		(at 124.5616 147.1422)
		(size 0.45)
		(drill 0.1)
		(layers "F.Cu" "B.Cu")
		(remove_unused_layers yes)
		(keep_end_layers yes)
		(zone_layer_connections "In1.Cu" "In3.Cu" "In5.Cu" "In7.Cu" "In10.Cu")
		(net 1)
	)
	(via
		(at 183.175 194.849501)
		(size 0.45)
		(drill 0.1)
		(layers "F.Cu" "B.Cu")
		(remove_unused_layers yes)
		(keep_end_layers yes)
		(zone_layer_connections "In1.Cu" "In3.Cu" "In5.Cu" "In7.Cu" "In10.Cu")
		(net 1)
	)
	(via
		(at 138.1645 104.1255)
		(size 0.45)
		(drill 0.1)
		(layers "F.Cu" "B.Cu")
		(remove_unused_layers yes)
		(keep_end_layers yes)
		(zone_layer_connections "In1.Cu" "In3.Cu" "In5.Cu" "In7.Cu" "In10.Cu")
		(net 1)
	)
	(via
		(at 223.775 178.01)
		(size 0.45)
		(drill 0.1)
		(layers "F.Cu" "B.Cu")
		(remove_unused_layers yes)
		(keep_end_layers yes)
		(zone_layer_connections "In1.Cu" "In3.Cu" "In5.Cu" "In7.Cu" "In10.Cu")
		(net 1)
	)
	(via
		(at 164.1 109.446)
		(size 0.45)
		(drill 0.1)
		(layers "F.Cu" "B.Cu")
		(remove_unused_layers yes)
		(keep_end_layers yes)
		(zone_layer_connections "In1.Cu" "In3.Cu" "In5.Cu" "In7.Cu" "In10.Cu")
		(net 1)
	)
	(via
		(at 179.498 100.510001)
		(size 0.45)
		(drill 0.1)
		(layers "F.Cu" "B.Cu")
		(remove_unused_layers yes)
		(keep_end_layers yes)
		(zone_layer_connections "In1.Cu" "In3.Cu" "In5.Cu" "In7.Cu" "In10.Cu")
		(net 1)
	)
	(via
		(at 241.3 118.65)
		(size 0.45)
		(drill 0.1)
		(layers "F.Cu" "B.Cu")
		(remove_unused_layers yes)
		(keep_end_layers yes)
		(zone_layer_connections "In1.Cu" "In3.Cu" "In5.Cu" "In7.Cu" "In10.Cu")
		(net 1)
	)
	(via
		(at 175.5 161.5)
		(size 0.45)
		(drill 0.1)
		(layers "F.Cu" "B.Cu")
		(remove_unused_layers yes)
		(keep_end_layers yes)
		(zone_layer_connections "In1.Cu" "In3.Cu" "In5.Cu" "In7.Cu" "In10.Cu")
		(net 1)
	)
	(via
		(at 261.39 175.71)
		(size 0.45)
		(drill 0.1)
		(layers "F.Cu" "B.Cu")
		(remove_unused_layers yes)
		(keep_end_layers yes)
		(zone_layer_connections "In1.Cu" "In3.Cu" "In5.Cu" "In6.Cu" "In7.Cu" "In10.Cu")
		(net 1)
	)
	(via
		(at 263.924499 185.47)
		(size 0.45)
		(drill 0.1)
		(layers "F.Cu" "B.Cu")
		(remove_unused_layers yes)
		(keep_end_layers yes)
		(zone_layer_connections "In1.Cu" "In3.Cu" "In5.Cu" "In7.Cu" "In10.Cu")
		(net 1)
	)
	(via
		(at 242.12 121.78)
		(size 0.45)
		(drill 0.1)
		(layers "F.Cu" "B.Cu")
		(remove_unused_layers yes)
		(keep_end_layers yes)
		(zone_layer_connections "In1.Cu" "In3.Cu" "In5.Cu" "In7.Cu" "In10.Cu")
		(net 1)
	)
	(via
		(at 141.15 155.9)
		(size 0.45)
		(drill 0.1)
		(layers "F.Cu" "B.Cu")
		(remove_unused_layers yes)
		(keep_end_layers yes)
		(zone_layer_connections "In1.Cu" "In3.Cu" "In5.Cu" "In7.Cu" "In10.Cu")
		(net 1)
	)
	(via
		(at 226.151 109.446)
		(size 0.45)
		(drill 0.1)
		(layers "F.Cu" "B.Cu")
		(remove_unused_layers yes)
		(keep_end_layers yes)
		(zone_layer_connections "In1.Cu" "In3.Cu" "In5.Cu" "In7.Cu" "In10.Cu")
		(net 1)
	)
	(via
		(at 147.2 178.5)
		(size 0.45)
		(drill 0.1)
		(layers "F.Cu" "B.Cu")
		(remove_unused_layers yes)
		(keep_end_layers yes)
		(zone_layer_connections "In1.Cu" "In3.Cu" "In5.Cu" "In7.Cu" "In10.Cu")
		(net 1)
	)
	(via
		(at 179.5 158.5)
		(size 0.45)
		(drill 0.1)
		(layers "F.Cu" "B.Cu")
		(remove_unused_layers yes)
		(keep_end_layers yes)
		(zone_layer_connections "In1.Cu" "In3.Cu" "In5.Cu" "In7.Cu" "In10.Cu")
		(net 1)
	)
	(via
		(at 223.335 169.435)
		(size 0.45)
		(drill 0.1)
		(layers "F.Cu" "B.Cu")
		(remove_unused_layers yes)
		(keep_end_layers yes)
		(zone_layer_connections "In1.Cu" "In3.Cu" "In5.Cu" "In7.Cu" "In10.Cu")
		(net 1)
	)
	(via
		(at 144.105 139.005)
		(size 0.45)
		(drill 0.1)
		(layers "F.Cu" "B.Cu")
		(remove_unused_layers yes)
		(keep_end_layers yes)
		(zone_layer_connections "In1.Cu" "In3.Cu" "In5.Cu" "In7.Cu" "In10.Cu")
		(net 1)
	)
	(via
		(at 141.0866 100.498601)
		(size 0.45)
		(drill 0.1)
		(layers "F.Cu" "B.Cu")
		(remove_unused_layers yes)
		(keep_end_layers yes)
		(zone_layer_connections "In1.Cu" "In3.Cu" "In5.Cu" "In7.Cu" "In10.Cu")
		(net 1)
	)
	(via
		(at 214.7 157.025)
		(size 0.45)
		(drill 0.1)
		(layers "F.Cu" "B.Cu")
		(remove_unused_layers yes)
		(keep_end_layers yes)
		(zone_layer_connections "In1.Cu" "In3.Cu" "In5.Cu" "In7.Cu" "In10.Cu")
		(net 1)
	)
	(via
		(at 198.4995 163.4995)
		(size 0.45)
		(drill 0.1)
		(layers "F.Cu" "B.Cu")
		(remove_unused_layers yes)
		(keep_end_layers yes)
		(zone_layer_connections "In1.Cu" "In3.Cu" "In5.Cu" "In7.Cu" "In10.Cu")
		(net 1)
	)
	(via
		(at 149.105843 166.351328)
		(size 0.45)
		(drill 0.1)
		(layers "F.Cu" "B.Cu")
		(remove_unused_layers yes)
		(keep_end_layers yes)
		(zone_layer_connections "In1.Cu" "In3.Cu" "In5.Cu" "In7.Cu" "In10.Cu")
		(net 1)
	)
	(via
		(at 189.5 149.5)
		(size 0.45)
		(drill 0.1)
		(layers "F.Cu" "B.Cu")
		(remove_unused_layers yes)
		(keep_end_layers yes)
		(zone_layer_connections "In1.Cu" "In3.Cu" "In5.Cu" "In7.Cu" "In10.Cu")
		(net 1)
	)
	(via
		(at 206.599 134.973503)
		(size 0.45)
		(drill 0.1)
		(layers "F.Cu" "B.Cu")
		(net 1)
	)
	(via
		(at 134.6866 100.498601)
		(size 0.45)
		(drill 0.1)
		(layers "F.Cu" "B.Cu")
		(remove_unused_layers yes)
		(keep_end_layers yes)
		(zone_layer_connections "In1.Cu" "In3.Cu" "In5.Cu" "In7.Cu" "In10.Cu")
		(net 1)
	)
	(via
		(at 119.896537 127.030383)
		(size 0.45)
		(drill 0.1)
		(layers "F.Cu" "B.Cu")
		(remove_unused_layers yes)
		(keep_end_layers yes)
		(zone_layer_connections "In1.Cu" "In3.Cu" "In5.Cu" "In7.Cu" "In10.Cu")
		(net 1)
	)
	(via
		(at 147.951 104.848)
		(size 0.45)
		(drill 0.1)
		(layers "F.Cu" "B.Cu")
		(remove_unused_layers yes)
		(keep_end_layers yes)
		(zone_layer_connections "In1.Cu" "In3.Cu" "In5.Cu" "In7.Cu" "In10.Cu")
		(net 1)
	)
	(via
		(at 155.08 171.74)
		(size 0.45)
		(drill 0.1)
		(layers "F.Cu" "B.Cu")
		(remove_unused_layers yes)
		(keep_end_layers yes)
		(zone_layer_connections "In1.Cu" "In3.Cu" "In5.Cu" "In7.Cu" "In10.Cu")
		(net 1)
	)
	(via
		(at 223.275 157.125)
		(size 0.45)
		(drill 0.1)
		(layers "F.Cu" "B.Cu")
		(remove_unused_layers yes)
		(keep_end_layers yes)
		(zone_layer_connections "In1.Cu" "In3.Cu" "In5.Cu" "In7.Cu" "In10.Cu")
		(net 1)
	)
	(via
		(at 125.16 101.159)
		(size 0.45)
		(drill 0.1)
		(layers "F.Cu" "B.Cu")
		(remove_unused_layers yes)
		(keep_end_layers yes)
		(zone_layer_connections "In1.Cu" "In3.Cu" "In5.Cu" "In7.Cu" "In10.Cu")
		(net 1)
	)
	(via
		(at 153.051 109.446)
		(size 0.45)
		(drill 0.1)
		(layers "F.Cu" "B.Cu")
		(remove_unused_layers yes)
		(keep_end_layers yes)
		(zone_layer_connections "In1.Cu" "In3.Cu" "In5.Cu" "In7.Cu" "In10.Cu")
		(net 1)
	)
	(via
		(at 227.835 187.73)
		(size 0.45)
		(drill 0.1)
		(layers "F.Cu" "B.Cu")
		(remove_unused_layers yes)
		(keep_end_layers yes)
		(zone_layer_connections "In1.Cu" "In3.Cu" "In5.Cu" "In7.Cu" "In10.Cu")
		(net 1)
	)
	(via
		(at 263.924499 111.239998)
		(size 0.45)
		(drill 0.1)
		(layers "F.Cu" "B.Cu")
		(remove_unused_layers yes)
		(keep_end_layers yes)
		(zone_layer_connections "In1.Cu" "In3.Cu" "In5.Cu" "In7.Cu" "In10.Cu")
		(net 1)
	)
	(via
		(at 229.31 182.585)
		(size 0.45)
		(drill 0.1)
		(layers "F.Cu" "B.Cu")
		(remove_unused_layers yes)
		(keep_end_layers yes)
		(zone_layer_connections "In1.Cu" "In3.Cu" "In5.Cu" "In7.Cu" "In10.Cu")
		(net 1)
	)
	(via
		(at 263.924499 117.639998)
		(size 0.45)
		(drill 0.1)
		(layers "F.Cu" "B.Cu")
		(remove_unused_layers yes)
		(keep_end_layers yes)
		(zone_layer_connections "In1.Cu" "In3.Cu" "In5.Cu" "In7.Cu" "In10.Cu")
		(net 1)
	)
	(via
		(at 131.802 104.848)
		(size 0.45)
		(drill 0.1)
		(layers "F.Cu" "B.Cu")
		(remove_unused_layers yes)
		(keep_end_layers yes)
		(zone_layer_connections "In1.Cu" "In3.Cu" "In5.Cu" "In7.Cu" "In10.Cu")
		(net 1)
	)
	(via
		(at 239.525 153.275)
		(size 0.45)
		(drill 0.1)
		(layers "F.Cu" "B.Cu")
		(remove_unused_layers yes)
		(keep_end_layers yes)
		(zone_layer_connections "In1.Cu" "In3.Cu" "In5.Cu" "In7.Cu" "In10.Cu")
		(net 1)
	)
	(via
		(at 252.251499 169.25)
		(size 0.45)
		(drill 0.1)
		(layers "F.Cu" "B.Cu")
		(remove_unused_layers yes)
		(keep_end_layers yes)
		(zone_layer_connections "In1.Cu" "In2.Cu" "In3.Cu" "In4.Cu" "In5.Cu" "In6.Cu"
			"In7.Cu" "In10.Cu"
		)
		(net 1)
	)
	(via
		(at 187.5 160.5)
		(size 0.45)
		(drill 0.1)
		(layers "F.Cu" "B.Cu")
		(remove_unused_layers yes)
		(keep_end_layers yes)
		(zone_layer_connections "In1.Cu" "In3.Cu" "In5.Cu" "In7.Cu" "In10.Cu")
		(net 1)
	)
	(via
		(at 106.627 160.119)
		(size 0.45)
		(drill 0.1)
		(layers "F.Cu" "B.Cu")
		(remove_unused_layers yes)
		(keep_end_layers yes)
		(zone_layer_connections "In1.Cu" "In3.Cu" "In5.Cu" "In7.Cu" "In10.Cu")
		(net 1)
	)
	(via
		(at 259.699499 171.149)
		(size 0.45)
		(drill 0.1)
		(layers "F.Cu" "B.Cu")
		(remove_unused_layers yes)
		(keep_end_layers yes)
		(zone_layer_connections "In1.Cu" "In3.Cu" "In4.Cu" "In5.Cu" "In6.Cu" "In7.Cu"
			"In10.Cu"
		)
		(net 1)
	)
	(via
		(at 122.646 104.11)
		(size 0.45)
		(drill 0.1)
		(layers "F.Cu" "B.Cu")
		(remove_unused_layers yes)
		(keep_end_layers yes)
		(zone_layer_connections "In1.Cu" "In3.Cu" "In5.Cu" "In7.Cu" "In10.Cu")
		(net 1)
	)
	(via
		(at 112.024499 138.849)
		(size 0.45)
		(drill 0.1)
		(layers "F.Cu" "B.Cu")
		(remove_unused_layers yes)
		(keep_end_layers yes)
		(zone_layer_connections "In1.Cu" "In3.Cu" "In5.Cu" "In7.Cu" "In10.Cu")
		(net 1)
	)
	(via
		(at 162.125 194.849501)
		(size 0.45)
		(drill 0.1)
		(layers "F.Cu" "B.Cu")
		(remove_unused_layers yes)
		(keep_end_layers yes)
		(zone_layer_connections "In1.Cu" "In3.Cu" "In5.Cu" "In7.Cu" "In10.Cu")
		(net 1)
	)
	(via
		(at 200.499501 161.4995)
		(size 0.45)
		(drill 0.1)
		(layers "F.Cu" "B.Cu")
		(remove_unused_layers yes)
		(keep_end_layers yes)
		(zone_layer_connections "In1.Cu" "In3.Cu" "In5.Cu" "In7.Cu" "In10.Cu")
		(net 1)
	)
	(via
		(at 200.4995 163.5005)
		(size 0.45)
		(drill 0.1)
		(layers "F.Cu" "B.Cu")
		(remove_unused_layers yes)
		(keep_end_layers yes)
		(zone_layer_connections "In1.Cu" "In3.Cu" "In5.Cu" "In7.Cu" "In10.Cu")
		(net 1)
	)
	(via
		(at 215.935 187.56)
		(size 0.45)
		(drill 0.1)
		(layers "F.Cu" "B.Cu")
		(remove_unused_layers yes)
		(keep_end_layers yes)
		(zone_layer_connections "In1.Cu" "In3.Cu" "In5.Cu" "In7.Cu" "In10.Cu")
		(net 1)
	)
	(via
		(at 153.8866 100.498601)
		(size 0.45)
		(drill 0.1)
		(layers "F.Cu" "B.Cu")
		(remove_unused_layers yes)
		(keep_end_layers yes)
		(zone_layer_connections "In1.Cu" "In3.Cu" "In5.Cu" "In7.Cu" "In10.Cu")
		(net 1)
	)
	(via
		(at 255.594999 156.6005)
		(size 0.45)
		(drill 0.1)
		(layers "F.Cu" "B.Cu")
		(remove_unused_layers yes)
		(keep_end_layers yes)
		(zone_layer_connections "In1.Cu" "In2.Cu" "In3.Cu" "In4.Cu" "In5.Cu" "In6.Cu"
			"In7.Cu" "In10.Cu"
		)
		(net 1)
	)
	(via
		(at 105.775 160.869)
		(size 0.45)
		(drill 0.1)
		(layers "F.Cu" "B.Cu")
		(remove_unused_layers yes)
		(keep_end_layers yes)
		(zone_layer_connections "In1.Cu" "In3.Cu" "In5.Cu" "In7.Cu" "In10.Cu")
		(net 1)
	)
	(via
		(at 112.024499 140.049)
		(size 0.45)
		(drill 0.1)
		(layers "F.Cu" "B.Cu")
		(remove_unused_layers yes)
		(keep_end_layers yes)
		(zone_layer_connections "In1.Cu" "In3.Cu" "In5.Cu" "In7.Cu" "In10.Cu")
		(net 1)
	)
	(via
		(at 194.5 143.5)
		(size 0.45)
		(drill 0.1)
		(layers "F.Cu" "B.Cu")
		(remove_unused_layers yes)
		(keep_end_layers yes)
		(zone_layer_connections "In1.Cu" "In3.Cu" "In5.Cu" "In7.Cu" "In10.Cu")
		(net 1)
	)
	(via
		(at 255.93 182.17)
		(size 0.45)
		(drill 0.1)
		(layers "F.Cu" "B.Cu")
		(remove_unused_layers yes)
		(keep_end_layers yes)
		(zone_layer_connections "In1.Cu" "In3.Cu" "In5.Cu" "In6.Cu" "In7.Cu" "In10.Cu")
		(net 1)
	)
	(via
		(at 136.124499 152.9005)
		(size 0.45)
		(drill 0.1)
		(layers "F.Cu" "B.Cu")
		(remove_unused_layers yes)
		(keep_end_layers yes)
		(zone_layer_connections "In1.Cu" "In3.Cu" "In5.Cu" "In7.Cu" "In10.Cu")
		(net 1)
	)
	(via
		(at 238.901 111.75)
		(size 0.45)
		(drill 0.1)
		(layers "F.Cu" "B.Cu")
		(remove_unused_layers yes)
		(keep_end_layers yes)
		(zone_layer_connections "In1.Cu" "In3.Cu" "In5.Cu" "In7.Cu" "In10.Cu")
		(net 1)
	)
	(via
		(at 255.924499 176.9)
		(size 0.45)
		(drill 0.1)
		(layers "F.Cu" "B.Cu")
		(remove_unused_layers yes)
		(keep_end_layers yes)
		(zone_layer_connections "In1.Cu" "In3.Cu" "In4.Cu" "In5.Cu" "In6.Cu" "In7.Cu"
			"In10.Cu"
		)
		(net 1)
	)
	(via
		(at 230.698 100.510001)
		(size 0.45)
		(drill 0.1)
		(layers "F.Cu" "B.Cu")
		(remove_unused_layers yes)
		(keep_end_layers yes)
		(zone_layer_connections "In1.Cu" "In3.Cu" "In5.Cu" "In7.Cu" "In10.Cu")
		(net 1)
	)
	(via
		(at 204.875 172.825)
		(size 0.45)
		(drill 0.1)
		(layers "F.Cu" "B.Cu")
		(remove_unused_layers yes)
		(keep_end_layers yes)
		(zone_layer_connections "In1.Cu" "In3.Cu" "In5.Cu" "In7.Cu" "In10.Cu")
		(net 1)
	)
	(via
		(at 158.55 177.63)
		(size 0.45)
		(drill 0.1)
		(layers "F.Cu" "B.Cu")
		(remove_unused_layers yes)
		(keep_end_layers yes)
		(zone_layer_connections "In1.Cu" "In3.Cu" "In5.Cu" "In7.Cu" "In10.Cu")
		(net 1)
	)
	(via
		(at 135.6505 104.1255)
		(size 0.45)
		(drill 0.1)
		(layers "F.Cu" "B.Cu")
		(remove_unused_layers yes)
		(keep_end_layers yes)
		(zone_layer_connections "In1.Cu" "In3.Cu" "In5.Cu" "In7.Cu" "In10.Cu")
		(net 1)
	)
	(via
		(at 240.6 109.446)
		(size 0.45)
		(drill 0.1)
		(layers "F.Cu" "B.Cu")
		(remove_unused_layers yes)
		(keep_end_layers yes)
		(zone_layer_connections "In1.Cu" "In3.Cu" "In5.Cu" "In7.Cu" "In10.Cu")
		(net 1)
	)
	(via
		(at 223.835 186.68)
		(size 0.45)
		(drill 0.1)
		(layers "F.Cu" "B.Cu")
		(remove_unused_layers yes)
		(keep_end_layers yes)
		(zone_layer_connections "In1.Cu" "In3.Cu" "In5.Cu" "In7.Cu" "In10.Cu")
		(net 1)
	)
	(via
		(at 134.35 109.446)
		(size 0.45)
		(drill 0.1)
		(layers "F.Cu" "B.Cu")
		(remove_unused_layers yes)
		(keep_end_layers yes)
		(zone_layer_connections "In1.Cu" "In3.Cu" "In5.Cu" "In7.Cu" "In10.Cu")
		(net 1)
	)
	(via
		(at 125.16 119.173)
		(size 0.45)
		(drill 0.1)
		(layers "F.Cu" "B.Cu")
		(remove_unused_layers yes)
		(keep_end_layers yes)
		(zone_layer_connections "In1.Cu" "In3.Cu" "In5.Cu" "In7.Cu" "In9.Cu" "In10.Cu")
		(net 1)
	)
	(via
		(at 248.504499 138.589)
		(size 0.45)
		(drill 0.1)
		(layers "F.Cu" "B.Cu")
		(remove_unused_layers yes)
		(keep_end_layers yes)
		(zone_layer_connections "In1.Cu" "In3.Cu" "In5.Cu" "In7.Cu" "In10.Cu")
		(net 1)
	)
	(via
		(at 256.624499 151.149)
		(size 0.45)
		(drill 0.1)
		(layers "F.Cu" "B.Cu")
		(remove_unused_layers yes)
		(keep_end_layers yes)
		(zone_layer_connections "In1.Cu" "In3.Cu" "In4.Cu" "In5.Cu" "In6.Cu" "In7.Cu"
			"In10.Cu"
		)
		(net 1)
	)
	(via
		(at 238.03 135.65)
		(size 0.45)
		(drill 0.1)
		(layers "F.Cu" "B.Cu")
		(remove_unused_layers yes)
		(keep_end_layers yes)
		(zone_layer_connections "In1.Cu" "In3.Cu" "In5.Cu" "In7.Cu" "In10.Cu")
		(net 1)
	)
	(via
		(at 129.25 104.848)
		(size 0.45)
		(drill 0.1)
		(layers "F.Cu" "B.Cu")
		(remove_unused_layers yes)
		(keep_end_layers yes)
		(zone_layer_connections "In1.Cu" "In3.Cu" "In5.Cu" "In7.Cu" "In10.Cu")
		(net 1)
	)
	(via
		(at 261.374498 133.625)
		(size 0.45)
		(drill 0.1)
		(layers "F.Cu" "B.Cu")
		(remove_unused_layers yes)
		(keep_end_layers yes)
		(zone_layer_connections "In1.Cu" "In3.Cu" "In5.Cu" "In7.Cu" "In10.Cu")
		(net 1)
	)
	(via
		(at 260.62 114.74)
		(size 0.45)
		(drill 0.1)
		(layers "F.Cu" "B.Cu")
		(remove_unused_layers yes)
		(keep_end_layers yes)
		(zone_layer_connections "In1.Cu" "In3.Cu" "In5.Cu" "In7.Cu" "In10.Cu")
		(net 1)
	)
	(via
		(at 234.15 183.8)
		(size 0.45)
		(drill 0.1)
		(layers "F.Cu" "B.Cu")
		(remove_unused_layers yes)
		(keep_end_layers yes)
		(zone_layer_connections "In1.Cu" "In3.Cu" "In5.Cu" "In7.Cu" "In10.Cu")
		(net 1)
	)
	(via
		(at 219.922 148.098)
		(size 0.45)
		(drill 0.1)
		(layers "F.Cu" "B.Cu")
		(remove_unused_layers yes)
		(keep_end_layers yes)
		(zone_layer_connections "In1.Cu" "In3.Cu" "In5.Cu" "In7.Cu" "In10.Cu")
		(net 1)
	)
	(via
		(at 113.736 171.0505)
		(size 0.45)
		(drill 0.1)
		(layers "F.Cu" "B.Cu")
		(remove_unused_layers yes)
		(keep_end_layers yes)
		(zone_layer_connections "In1.Cu" "In3.Cu" "In5.Cu" "In7.Cu" "In10.Cu")
		(net 1)
	)
	(via
		(at 258.674499 181.499)
		(size 0.45)
		(drill 0.1)
		(layers "F.Cu" "B.Cu")
		(remove_unused_layers yes)
		(keep_end_layers yes)
		(zone_layer_connections "In1.Cu" "In3.Cu" "In5.Cu" "In6.Cu" "In7.Cu" "In10.Cu")
		(net 1)
	)
	(via
		(at 219.45 158.1)
		(size 0.45)
		(drill 0.1)
		(layers "F.Cu" "B.Cu")
		(remove_unused_layers yes)
		(keep_end_layers yes)
		(zone_layer_connections "In1.Cu" "In3.Cu" "In5.Cu" "In7.Cu" "In10.Cu")
		(net 1)
	)
	(via
		(at 260.79 115.34)
		(size 0.45)
		(drill 0.1)
		(layers "F.Cu" "B.Cu")
		(remove_unused_layers yes)
		(keep_end_layers yes)
		(zone_layer_connections "In1.Cu" "In3.Cu" "In5.Cu" "In7.Cu" "In10.Cu")
		(net 1)
	)
	(via
		(at 143.701 109.446)
		(size 0.45)
		(drill 0.1)
		(layers "F.Cu" "B.Cu")
		(remove_unused_layers yes)
		(keep_end_layers yes)
		(zone_layer_connections "In1.Cu" "In3.Cu" "In5.Cu" "In7.Cu" "In10.Cu")
		(net 1)
	)
	(via
		(at 210.002 104.848)
		(size 0.45)
		(drill 0.1)
		(layers "F.Cu" "B.Cu")
		(remove_unused_layers yes)
		(keep_end_layers yes)
		(zone_layer_connections "In1.Cu" "In3.Cu" "In5.Cu" "In7.Cu" "In10.Cu")
		(net 1)
	)
	(via
		(at 109.93 145.796)
		(size 0.45)
		(drill 0.1)
		(layers "F.Cu" "B.Cu")
		(remove_unused_layers yes)
		(keep_end_layers yes)
		(zone_layer_connections "In1.Cu" "In3.Cu" "In5.Cu" "In7.Cu" "In10.Cu")
		(net 1)
	)
	(via
		(at 213.585 183.435)
		(size 0.45)
		(drill 0.1)
		(layers "F.Cu" "B.Cu")
		(remove_unused_layers yes)
		(keep_end_layers yes)
		(zone_layer_connections "In1.Cu" "In3.Cu" "In5.Cu" "In7.Cu" "In10.Cu")
		(net 1)
	)
	(via
		(at 144.2866 100.498601)
		(size 0.45)
		(drill 0.1)
		(layers "F.Cu" "B.Cu")
		(remove_unused_layers yes)
		(keep_end_layers yes)
		(zone_layer_connections "In1.Cu" "In3.Cu" "In5.Cu" "In7.Cu" "In10.Cu")
		(net 1)
	)
	(via
		(at 248.55 123.73)
		(size 0.45)
		(drill 0.1)
		(layers "F.Cu" "B.Cu")
		(net 1)
	)
	(via
		(at 175.5 164.5)
		(size 0.45)
		(drill 0.1)
		(layers "F.Cu" "B.Cu")
		(remove_unused_layers yes)
		(keep_end_layers yes)
		(zone_layer_connections "In1.Cu" "In3.Cu" "In5.Cu" "In7.Cu" "In10.Cu")
		(net 1)
	)
	(via
		(at 191.500001 149.5)
		(size 0.45)
		(drill 0.1)
		(layers "F.Cu" "B.Cu")
		(remove_unused_layers yes)
		(keep_end_layers yes)
		(zone_layer_connections "In1.Cu" "In3.Cu" "In5.Cu" "In7.Cu" "In10.Cu")
		(net 1)
	)
	(via
		(at 224.685 176.935)
		(size 0.45)
		(drill 0.1)
		(layers "F.Cu" "B.Cu")
		(remove_unused_layers yes)
		(keep_end_layers yes)
		(zone_layer_connections "In1.Cu" "In3.Cu" "In5.Cu" "In7.Cu" "In10.Cu")
		(net 1)
	)
	(via
		(at 121.8866 100.498601)
		(size 0.45)
		(drill 0.1)
		(layers "F.Cu" "B.Cu")
		(remove_unused_layers yes)
		(keep_end_layers yes)
		(zone_layer_connections "In1.Cu" "In3.Cu" "In5.Cu" "In7.Cu" "In10.Cu")
		(net 1)
	)
	(via
		(at 232.06 179.81)
		(size 0.45)
		(drill 0.1)
		(layers "F.Cu" "B.Cu")
		(remove_unused_layers yes)
		(keep_end_layers yes)
		(zone_layer_connections "In1.Cu" "In3.Cu" "In5.Cu" "In7.Cu" "In10.Cu")
		(net 1)
	)
	(via
		(at 214.535 178.085)
		(size 0.45)
		(drill 0.1)
		(layers "F.Cu" "B.Cu")
		(remove_unused_layers yes)
		(keep_end_layers yes)
		(zone_layer_connections "In1.Cu" "In3.Cu" "In5.Cu" "In7.Cu" "In10.Cu")
		(net 1)
	)
	(via
		(at 105.824499 137.81)
		(size 0.45)
		(drill 0.1)
		(layers "F.Cu" "B.Cu")
		(remove_unused_layers yes)
		(keep_end_layers yes)
		(zone_layer_connections "In1.Cu" "In3.Cu" "In5.Cu" "In7.Cu" "In10.Cu")
		(net 1)
	)
	(via
		(at 224.685 179.085)
		(size 0.45)
		(drill 0.1)
		(layers "F.Cu" "B.Cu")
		(remove_unused_layers yes)
		(keep_end_layers yes)
		(zone_layer_connections "In1.Cu" "In3.Cu" "In5.Cu" "In7.Cu" "In10.Cu")
		(net 1)
	)
	(via
		(at 254.321999 172.7515)
		(size 0.45)
		(drill 0.1)
		(layers "F.Cu" "B.Cu")
		(remove_unused_layers yes)
		(keep_end_layers yes)
		(zone_layer_connections "In1.Cu" "In2.Cu" "In3.Cu" "In4.Cu" "In5.Cu" "In6.Cu"
			"In7.Cu" "In10.Cu"
		)
		(net 1)
	)
	(via
		(at 158.06 165.499999)
		(size 0.45)
		(drill 0.1)
		(layers "F.Cu" "B.Cu")
		(remove_unused_layers yes)
		(keep_end_layers yes)
		(zone_layer_connections "In1.Cu" "In3.Cu" "In5.Cu" "In7.Cu" "In10.Cu")
		(net 1)
	)
	(via
		(at 105.824499 174.249)
		(size 0.45)
		(drill 0.1)
		(layers "F.Cu" "B.Cu")
		(remove_unused_layers yes)
		(keep_end_layers yes)
		(zone_layer_connections "In1.Cu" "In3.Cu" "In5.Cu" "In7.Cu" "In10.Cu")
		(net 1)
	)
	(via
		(at 131.23 180.1985)
		(size 0.45)
		(drill 0.1)
		(layers "F.Cu" "B.Cu")
		(remove_unused_layers yes)
		(keep_end_layers yes)
		(zone_layer_connections "In1.Cu" "In3.Cu" "In5.Cu" "In7.Cu" "In10.Cu")
		(net 1)
	)
	(via
		(at 241.1 116.9)
		(size 0.45)
		(drill 0.1)
		(layers "F.Cu" "B.Cu")
		(remove_unused_layers yes)
		(keep_end_layers yes)
		(zone_layer_connections "In1.Cu" "In3.Cu" "In5.Cu" "In7.Cu" "In10.Cu")
		(net 1)
	)
	(via
		(at 178.5 166.45)
		(size 0.45)
		(drill 0.1)
		(layers "F.Cu" "B.Cu")
		(remove_unused_layers yes)
		(keep_end_layers yes)
		(zone_layer_connections "In1.Cu" "In3.Cu" "In5.Cu" "In7.Cu" "In10.Cu")
		(net 1)
	)
	(via
		(at 112.430499 179.5525)
		(size 0.45)
		(drill 0.1)
		(layers "F.Cu" "B.Cu")
		(remove_unused_layers yes)
		(keep_end_layers yes)
		(zone_layer_connections "In1.Cu" "In3.Cu" "In5.Cu" "In7.Cu" "In10.Cu")
		(net 1)
	)
	(via
		(at 133.925 148.075)
		(size 0.45)
		(drill 0.1)
		(layers "F.Cu" "B.Cu")
		(remove_unused_layers yes)
		(keep_end_layers yes)
		(zone_layer_connections "In1.Cu" "In3.Cu" "In5.Cu" "In7.Cu" "In10.Cu")
		(net 1)
	)
	(via
		(at 179.5 164.5)
		(size 0.45)
		(drill 0.1)
		(layers "F.Cu" "B.Cu")
		(remove_unused_layers yes)
		(keep_end_layers yes)
		(zone_layer_connections "In1.Cu" "In3.Cu" "In5.Cu" "In7.Cu" "In10.Cu")
		(net 1)
	)
	(via
		(at 186.5 158.5)
		(size 0.45)
		(drill 0.1)
		(layers "F.Cu" "B.Cu")
		(remove_unused_layers yes)
		(keep_end_layers yes)
		(zone_layer_connections "In1.Cu" "In3.Cu" "In5.Cu" "In7.Cu" "In10.Cu")
		(net 1)
	)
	(via
		(at 251.524499 156.249)
		(size 0.45)
		(drill 0.1)
		(layers "F.Cu" "B.Cu")
		(remove_unused_layers yes)
		(keep_end_layers yes)
		(zone_layer_connections "In1.Cu" "In2.Cu" "In3.Cu" "In4.Cu" "In5.Cu" "In6.Cu"
			"In7.Cu" "In10.Cu"
		)
		(net 1)
	)
	(via
		(at 111.53 163.66)
		(size 0.45)
		(drill 0.1)
		(layers "F.Cu" "B.Cu")
		(remove_unused_layers yes)
		(keep_end_layers yes)
		(zone_layer_connections "In1.Cu" "In3.Cu" "In5.Cu" "In7.Cu" "In10.Cu")
		(net 1)
	)
	(via
		(at 137.274499 145.449)
		(size 0.45)
		(drill 0.1)
		(layers "F.Cu" "B.Cu")
		(remove_unused_layers yes)
		(keep_end_layers yes)
		(zone_layer_connections "In1.Cu" "In3.Cu" "In5.Cu" "In7.Cu" "In10.Cu")
		(net 1)
	)
	(via
		(at 155.6 104.848)
		(size 0.45)
		(drill 0.1)
		(layers "F.Cu" "B.Cu")
		(remove_unused_layers yes)
		(keep_end_layers yes)
		(zone_layer_connections "In1.Cu" "In3.Cu" "In5.Cu" "In7.Cu" "In10.Cu")
		(net 1)
	)
	(via
		(at 214.535 169.435)
		(size 0.45)
		(drill 0.1)
		(layers "F.Cu" "B.Cu")
		(remove_unused_layers yes)
		(keep_end_layers yes)
		(zone_layer_connections "In1.Cu" "In3.Cu" "In5.Cu" "In7.Cu" "In10.Cu")
		(net 1)
	)
	(via
		(at 224.535 172.585)
		(size 0.45)
		(drill 0.1)
		(layers "F.Cu" "B.Cu")
		(remove_unused_layers yes)
		(keep_end_layers yes)
		(zone_layer_connections "In1.Cu" "In3.Cu" "In5.Cu" "In7.Cu" "In10.Cu")
		(net 1)
	)
	(via
		(at 192.5 158.5)
		(size 0.45)
		(drill 0.1)
		(layers "F.Cu" "B.Cu")
		(remove_unused_layers yes)
		(keep_end_layers yes)
		(zone_layer_connections "In1.Cu" "In3.Cu" "In5.Cu" "In7.Cu" "In10.Cu")
		(net 1)
	)
	(via
		(at 253.975 128.925)
		(size 0.45)
		(drill 0.1)
		(layers "F.Cu" "B.Cu")
		(remove_unused_layers yes)
		(keep_end_layers yes)
		(zone_layer_connections "In1.Cu" "In3.Cu" "In5.Cu" "In7.Cu" "In10.Cu")
		(net 1)
	)
	(via
		(at 247.904 140.101)
		(size 0.45)
		(drill 0.1)
		(layers "F.Cu" "B.Cu")
		(remove_unused_layers yes)
		(keep_end_layers yes)
		(zone_layer_connections "In1.Cu" "In3.Cu" "In5.Cu" "In7.Cu" "In10.Cu")
		(net 1)
	)
	(via
		(at 132.78 180.8585)
		(size 0.45)
		(drill 0.1)
		(layers "F.Cu" "B.Cu")
		(remove_unused_layers yes)
		(keep_end_layers yes)
		(zone_layer_connections "In1.Cu" "In3.Cu" "In5.Cu" "In7.Cu" "In10.Cu")
		(net 1)
	)
	(via
		(at 119.806 186.1375)
		(size 0.45)
		(drill 0.1)
		(layers "F.Cu" "B.Cu")
		(remove_unused_layers yes)
		(keep_end_layers yes)
		(zone_layer_connections "In1.Cu" "In3.Cu" "In5.Cu" "In7.Cu" "In10.Cu")
		(net 1)
	)
	(via
		(at 241.775 154.35)
		(size 0.45)
		(drill 0.1)
		(layers "F.Cu" "B.Cu")
		(remove_unused_layers yes)
		(keep_end_layers yes)
		(zone_layer_connections "In1.Cu" "In3.Cu" "In5.Cu" "In7.Cu" "In10.Cu")
		(net 1)
	)
	(via
		(at 180.252 104.848)
		(size 0.45)
		(drill 0.1)
		(layers "F.Cu" "B.Cu")
		(remove_unused_layers yes)
		(keep_end_layers yes)
		(zone_layer_connections "In1.Cu" "In3.Cu" "In5.Cu" "In7.Cu" "In10.Cu")
		(net 1)
	)
	(via
		(at 224.685 173.685)
		(size 0.45)
		(drill 0.1)
		(layers "F.Cu" "B.Cu")
		(remove_unused_layers yes)
		(keep_end_layers yes)
		(zone_layer_connections "In1.Cu" "In3.Cu" "In5.Cu" "In7.Cu" "In10.Cu")
		(net 1)
	)
	(via
		(at 254.48 114.105)
		(size 0.45)
		(drill 0.1)
		(layers "F.Cu" "B.Cu")
		(remove_unused_layers yes)
		(keep_end_layers yes)
		(zone_layer_connections "In1.Cu" "In3.Cu" "In5.Cu" "In7.Cu" "In10.Cu")
		(net 1)
	)
	(via
		(at 217.035 187.685)
		(size 0.45)
		(drill 0.1)
		(layers "F.Cu" "B.Cu")
		(remove_unused_layers yes)
		(keep_end_layers yes)
		(zone_layer_connections "In1.Cu" "In3.Cu" "In5.Cu" "In7.Cu" "In10.Cu")
		(net 1)
	)
	(via
		(at 198.698 100.510001)
		(size 0.45)
		(drill 0.1)
		(layers "F.Cu" "B.Cu")
		(remove_unused_layers yes)
		(keep_end_layers yes)
		(zone_layer_connections "In1.Cu" "In3.Cu" "In5.Cu" "In7.Cu" "In10.Cu")
		(net 1)
	)
	(via
		(at 263.424499 176.399)
		(size 0.45)
		(drill 0.1)
		(layers "F.Cu" "B.Cu")
		(remove_unused_layers yes)
		(keep_end_layers yes)
		(zone_layer_connections "In1.Cu" "In3.Cu" "In5.Cu" "In6.Cu" "In7.Cu" "In10.Cu")
		(net 1)
	)
	(via
		(at 111.111 178.7685)
		(size 0.45)
		(drill 0.1)
		(layers "F.Cu" "B.Cu")
		(remove_unused_layers yes)
		(keep_end_layers yes)
		(zone_layer_connections "In1.Cu" "In3.Cu" "In5.Cu" "In7.Cu" "In10.Cu")
		(net 1)
	)
	(via
		(at 107.8265 143.749)
		(size 0.45)
		(drill 0.1)
		(layers "F.Cu" "B.Cu")
		(remove_unused_layers yes)
		(keep_end_layers yes)
		(zone_layer_connections "In1.Cu" "In3.Cu" "In5.Cu" "In7.Cu" "In10.Cu")
		(net 1)
	)
	(via
		(at 251.55 173.7)
		(size 0.45)
		(drill 0.1)
		(layers "F.Cu" "B.Cu")
		(remove_unused_layers yes)
		(keep_end_layers yes)
		(zone_layer_connections "In1.Cu" "In2.Cu" "In3.Cu" "In4.Cu" "In5.Cu" "In6.Cu"
			"In7.Cu" "In10.Cu"
		)
		(net 1)
	)
	(via
		(at 204.875 167.575)
		(size 0.45)
		(drill 0.1)
		(layers "F.Cu" "B.Cu")
		(remove_unused_layers yes)
		(keep_end_layers yes)
		(zone_layer_connections "In1.Cu" "In3.Cu" "In5.Cu" "In7.Cu" "In10.Cu")
		(net 1)
	)
	(via
		(at 107.848 139.949)
		(size 0.45)
		(drill 0.1)
		(layers "F.Cu" "B.Cu")
		(remove_unused_layers yes)
		(keep_end_layers yes)
		(zone_layer_connections "In1.Cu" "In3.Cu" "In5.Cu" "In7.Cu" "In10.Cu")
		(net 1)
	)
	(via
		(at 235.085 172.61)
		(size 0.45)
		(drill 0.1)
		(layers "F.Cu" "B.Cu")
		(remove_unused_layers yes)
		(keep_end_layers yes)
		(zone_layer_connections "In1.Cu" "In3.Cu" "In5.Cu" "In7.Cu" "In10.Cu")
		(net 1)
	)
	(via
		(at 241.275 130.6)
		(size 0.45)
		(drill 0.1)
		(layers "F.Cu" "B.Cu")
		(remove_unused_layers yes)
		(keep_end_layers yes)
		(zone_layer_connections "In1.Cu" "In3.Cu" "In5.Cu" "In7.Cu" "In10.Cu")
		(net 1)
	)
	(via
		(at 176.5 153.5)
		(size 0.45)
		(drill 0.1)
		(layers "F.Cu" "B.Cu")
		(remove_unused_layers yes)
		(keep_end_layers yes)
		(zone_layer_connections "In1.Cu" "In3.Cu" "In5.Cu" "In7.Cu" "In10.Cu")
		(net 1)
	)
	(via
		(at 111.111 181.7685)
		(size 0.45)
		(drill 0.1)
		(layers "F.Cu" "B.Cu")
		(remove_unused_layers yes)
		(keep_end_layers yes)
		(zone_layer_connections "In1.Cu" "In3.Cu" "In5.Cu" "In7.Cu" "In10.Cu")
		(net 1)
	)
	(via
		(at 207.45 109.446)
		(size 0.45)
		(drill 0.1)
		(layers "F.Cu" "B.Cu")
		(remove_unused_layers yes)
		(keep_end_layers yes)
		(zone_layer_connections "In1.Cu" "In3.Cu" "In5.Cu" "In7.Cu" "In10.Cu")
		(net 1)
	)
	(via
		(at 125.35 164.05)
		(size 0.45)
		(drill 0.1)
		(layers "F.Cu" "B.Cu")
		(remove_unused_layers yes)
		(keep_end_layers yes)
		(zone_layer_connections "In1.Cu" "In3.Cu" "In5.Cu" "In7.Cu" "In10.Cu")
		(net 1)
	)
	(via
		(at 212.485 187.61)
		(size 0.45)
		(drill 0.1)
		(layers "F.Cu" "B.Cu")
		(remove_unused_layers yes)
		(keep_end_layers yes)
		(zone_layer_connections "In1.Cu" "In3.Cu" "In5.Cu" "In7.Cu" "In10.Cu")
		(net 1)
	)
	(via
		(at 261.3715 127.479999)
		(size 0.45)
		(drill 0.1)
		(layers "F.Cu" "B.Cu")
		(remove_unused_layers yes)
		(keep_end_layers yes)
		(zone_layer_connections "In1.Cu" "In3.Cu" "In5.Cu" "In7.Cu" "In10.Cu")
		(net 1)
	)
	(via
		(at 262.08 112.62)
		(size 0.45)
		(drill 0.1)
		(layers "F.Cu" "B.Cu")
		(remove_unused_layers yes)
		(keep_end_layers yes)
		(zone_layer_connections "In1.Cu" "In3.Cu" "In5.Cu" "In7.Cu" "In10.Cu")
		(net 1)
	)
	(via
		(at 138.624499 186.349)
		(size 0.45)
		(drill 0.1)
		(layers "F.Cu" "B.Cu")
		(remove_unused_layers yes)
		(keep_end_layers yes)
		(zone_layer_connections "In1.Cu" "In3.Cu" "In5.Cu" "In7.Cu" "In10.Cu")
		(net 1)
	)
	(via
		(at 134.814 165.518)
		(size 0.45)
		(drill 0.1)
		(layers "F.Cu" "B.Cu")
		(remove_unused_layers yes)
		(keep_end_layers yes)
		(zone_layer_connections "In1.Cu" "In3.Cu" "In5.Cu" "In7.Cu" "In10.Cu")
		(net 1)
	)
	(via
		(at 236.11 189.46)
		(size 0.45)
		(drill 0.1)
		(layers "F.Cu" "B.Cu")
		(remove_unused_layers yes)
		(keep_end_layers yes)
		(zone_layer_connections "In1.Cu" "In3.Cu" "In5.Cu" "In7.Cu" "In10.Cu")
		(net 1)
	)
	(via
		(at 254.7 129.55)
		(size 0.45)
		(drill 0.1)
		(layers "F.Cu" "B.Cu")
		(remove_unused_layers yes)
		(keep_end_layers yes)
		(zone_layer_connections "In1.Cu" "In3.Cu" "In5.Cu" "In7.Cu" "In10.Cu")
		(net 1)
	)
	(via
		(at 181.5 160.499999)
		(size 0.45)
		(drill 0.1)
		(layers "F.Cu" "B.Cu")
		(remove_unused_layers yes)
		(keep_end_layers yes)
		(zone_layer_connections "In1.Cu" "In3.Cu" "In5.Cu" "In7.Cu" "In10.Cu")
		(net 1)
	)
	(via
		(at 185.5 139.5)
		(size 0.45)
		(drill 0.1)
		(layers "F.Cu" "B.Cu")
		(remove_unused_layers yes)
		(keep_end_layers yes)
		(zone_layer_connections "In1.Cu" "In3.Cu" "In5.Cu" "In7.Cu" "In10.Cu")
		(net 1)
	)
	(via
		(at 187.5 163.5)
		(size 0.45)
		(drill 0.1)
		(layers "F.Cu" "B.Cu")
		(remove_unused_layers yes)
		(keep_end_layers yes)
		(zone_layer_connections "In1.Cu" "In3.Cu" "In5.Cu" "In7.Cu" "In10.Cu")
		(net 1)
	)
	(via
		(at 237.2 109.446)
		(size 0.45)
		(drill 0.1)
		(layers "F.Cu" "B.Cu")
		(remove_unused_layers yes)
		(keep_end_layers yes)
		(zone_layer_connections "In1.Cu" "In3.Cu" "In5.Cu" "In7.Cu" "In10.Cu")
		(net 1)
	)
	(via
		(at 218.65 183.445001)
		(size 0.45)
		(drill 0.1)
		(layers "F.Cu" "B.Cu")
		(remove_unused_layers yes)
		(keep_end_layers yes)
		(zone_layer_connections "In1.Cu" "In3.Cu" "In5.Cu" "In7.Cu" "In10.Cu")
		(net 1)
	)
	(via
		(at 150.5 104.848)
		(size 0.45)
		(drill 0.1)
		(layers "F.Cu" "B.Cu")
		(remove_unused_layers yes)
		(keep_end_layers yes)
		(zone_layer_connections "In1.Cu" "In3.Cu" "In5.Cu" "In7.Cu" "In10.Cu")
		(net 1)
	)
	(via
		(at 196.4 109.446)
		(size 0.45)
		(drill 0.1)
		(layers "F.Cu" "B.Cu")
		(remove_unused_layers yes)
		(keep_end_layers yes)
		(zone_layer_connections "In1.Cu" "In3.Cu" "In5.Cu" "In7.Cu" "In10.Cu")
		(net 1)
	)
	(via
		(at 234.651 104.848)
		(size 0.45)
		(drill 0.1)
		(layers "F.Cu" "B.Cu")
		(remove_unused_layers yes)
		(keep_end_layers yes)
		(zone_layer_connections "In1.Cu" "In3.Cu" "In5.Cu" "In7.Cu" "In10.Cu")
		(net 1)
	)
	(via
		(at 186.5 154.5)
		(size 0.45)
		(drill 0.1)
		(layers "F.Cu" "B.Cu")
		(remove_unused_layers yes)
		(keep_end_layers yes)
		(zone_layer_connections "In1.Cu" "In3.Cu" "In5.Cu" "In7.Cu" "In10.Cu")
		(net 1)
	)
	(via
		(at 211.935 184.385)
		(size 0.45)
		(drill 0.1)
		(layers "F.Cu" "B.Cu")
		(remove_unused_layers yes)
		(keep_end_layers yes)
		(zone_layer_connections "In1.Cu" "In3.Cu" "In5.Cu" "In7.Cu" "In10.Cu")
		(net 1)
	)
	(via
		(at 170.81 156.24)
		(size 0.45)
		(drill 0.1)
		(layers "F.Cu" "B.Cu")
		(remove_unused_layers yes)
		(keep_end_layers yes)
		(zone_layer_connections "In1.Cu" "In3.Cu" "In5.Cu" "In7.Cu" "In10.Cu")
		(net 1)
	)
	(via
		(at 222.14 183.945)
		(size 0.45)
		(drill 0.1)
		(layers "F.Cu" "B.Cu")
		(remove_unused_layers yes)
		(keep_end_layers yes)
		(zone_layer_connections "In1.Cu" "In3.Cu" "In5.Cu" "In7.Cu" "In10.Cu")
		(net 1)
	)
	(via
		(at 212.485 185.46)
		(size 0.45)
		(drill 0.1)
		(layers "F.Cu" "B.Cu")
		(remove_unused_layers yes)
		(keep_end_layers yes)
		(zone_layer_connections "In1.Cu" "In3.Cu" "In5.Cu" "In7.Cu" "In10.Cu")
		(net 1)
	)
	(via
		(at 219.351 104.848)
		(size 0.45)
		(drill 0.1)
		(layers "F.Cu" "B.Cu")
		(remove_unused_layers yes)
		(keep_end_layers yes)
		(zone_layer_connections "In1.Cu" "In3.Cu" "In5.Cu" "In7.Cu" "In10.Cu")
		(net 1)
	)
	(via
		(at 207.29 155.14)
		(size 0.45)
		(drill 0.1)
		(layers "F.Cu" "B.Cu")
		(remove_unused_layers yes)
		(keep_end_layers yes)
		(zone_layer_connections "In1.Cu" "In3.Cu" "In5.Cu" "In7.Cu" "In10.Cu")
		(net 1)
	)
	(via
		(at 142.49975 148.7445)
		(size 0.45)
		(drill 0.1)
		(layers "F.Cu" "B.Cu")
		(remove_unused_layers yes)
		(keep_end_layers yes)
		(zone_layer_connections "In1.Cu" "In3.Cu" "In5.Cu" "In7.Cu" "In10.Cu")
		(net 1)
	)
	(via
		(at 211.285 179.135)
		(size 0.45)
		(drill 0.1)
		(layers "F.Cu" "B.Cu")
		(remove_unused_layers yes)
		(keep_end_layers yes)
		(zone_layer_connections "In1.Cu" "In3.Cu" "In5.Cu" "In7.Cu" "In10.Cu")
		(net 1)
	)
	(via
		(at 140.524499 181.549)
		(size 0.45)
		(drill 0.1)
		(layers "F.Cu" "B.Cu")
		(remove_unused_layers yes)
		(keep_end_layers yes)
		(zone_layer_connections "In1.Cu" "In3.Cu" "In5.Cu" "In7.Cu" "In10.Cu")
		(net 1)
	)
	(via
		(at 225.235 169.41)
		(size 0.45)
		(drill 0.1)
		(layers "F.Cu" "B.Cu")
		(remove_unused_layers yes)
		(keep_end_layers yes)
		(zone_layer_connections "In1.Cu" "In3.Cu" "In5.Cu" "In7.Cu" "In10.Cu")
		(net 1)
	)
	(via
		(at 168.35 109.446)
		(size 0.45)
		(drill 0.1)
		(layers "F.Cu" "B.Cu")
		(remove_unused_layers yes)
		(keep_end_layers yes)
		(zone_layer_connections "In1.Cu" "In3.Cu" "In5.Cu" "In7.Cu" "In10.Cu")
		(net 1)
	)
	(via
		(at 224.45 109.446)
		(size 0.45)
		(drill 0.1)
		(layers "F.Cu" "B.Cu")
		(remove_unused_layers yes)
		(keep_end_layers yes)
		(zone_layer_connections "In1.Cu" "In3.Cu" "In5.Cu" "In7.Cu" "In10.Cu")
		(net 1)
	)
	(via
		(at 153.51 170.43)
		(size 0.45)
		(drill 0.1)
		(layers "F.Cu" "B.Cu")
		(remove_unused_layers yes)
		(keep_end_layers yes)
		(zone_layer_connections "In1.Cu" "In3.Cu" "In5.Cu" "In7.Cu" "In10.Cu")
		(net 1)
	)
	(via
		(at 222.785 173.71)
		(size 0.45)
		(drill 0.1)
		(layers "F.Cu" "B.Cu")
		(remove_unused_layers yes)
		(keep_end_layers yes)
		(zone_layer_connections "In1.Cu" "In3.Cu" "In5.Cu" "In7.Cu" "In10.Cu")
		(net 1)
	)
	(via
		(at 174.3 109.446)
		(size 0.45)
		(drill 0.1)
		(layers "F.Cu" "B.Cu")
		(remove_unused_layers yes)
		(keep_end_layers yes)
		(zone_layer_connections "In1.Cu" "In3.Cu" "In5.Cu" "In7.Cu" "In10.Cu")
		(net 1)
	)
	(via
		(at 177.5 160.5)
		(size 0.45)
		(drill 0.1)
		(layers "F.Cu" "B.Cu")
		(remove_unused_layers yes)
		(keep_end_layers yes)
		(zone_layer_connections "In1.Cu" "In3.Cu" "In5.Cu" "In7.Cu" "In10.Cu")
		(net 1)
	)
	(via
		(at 211.35 187.7)
		(size 0.45)
		(drill 0.1)
		(layers "F.Cu" "B.Cu")
		(remove_unused_layers yes)
		(keep_end_layers yes)
		(zone_layer_connections "In1.Cu" "In3.Cu" "In5.Cu" "In7.Cu" "In10.Cu")
		(net 1)
	)
	(via
		(at 246.75 123.75)
		(size 0.45)
		(drill 0.1)
		(layers "F.Cu" "B.Cu")
		(net 1)
	)
	(via
		(at 247.489499 135.614)
		(size 0.45)
		(drill 0.1)
		(layers "F.Cu" "B.Cu")
		(remove_unused_layers yes)
		(keep_end_layers yes)
		(zone_layer_connections "In1.Cu" "In3.Cu" "In5.Cu" "In7.Cu" "In10.Cu")
		(net 1)
	)
	(via
		(at 213.1 186.5)
		(size 0.45)
		(drill 0.1)
		(layers "F.Cu" "B.Cu")
		(remove_unused_layers yes)
		(keep_end_layers yes)
		(zone_layer_connections "In1.Cu" "In3.Cu" "In5.Cu" "In7.Cu" "In10.Cu")
		(net 1)
	)
	(via
		(at 231.251 109.446)
		(size 0.45)
		(drill 0.1)
		(layers "F.Cu" "B.Cu")
		(remove_unused_layers yes)
		(keep_end_layers yes)
		(zone_layer_connections "In1.Cu" "In3.Cu" "In5.Cu" "In7.Cu" "In10.Cu")
		(net 1)
	)
	(via
		(at 141.5 145.95)
		(size 0.45)
		(drill 0.1)
		(layers "F.Cu" "B.Cu")
		(remove_unused_layers yes)
		(keep_end_layers yes)
		(zone_layer_connections "In1.Cu" "In3.Cu" "In5.Cu" "In7.Cu" "In10.Cu")
		(net 1)
	)
	(via
		(at 207.8 155.65)
		(size 0.45)
		(drill 0.1)
		(layers "F.Cu" "B.Cu")
		(remove_unused_layers yes)
		(keep_end_layers yes)
		(zone_layer_connections "In1.Cu" "In3.Cu" "In5.Cu" "In7.Cu" "In10.Cu")
		(net 1)
	)
	(via
		(at 259.774499 141.347)
		(size 0.45)
		(drill 0.1)
		(layers "F.Cu" "B.Cu")
		(remove_unused_layers yes)
		(keep_end_layers yes)
		(zone_layer_connections "In1.Cu" "In3.Cu" "In5.Cu" "In7.Cu" "In10.Cu")
		(net 1)
	)
	(via
		(at 201.4995 162.4995)
		(size 0.45)
		(drill 0.1)
		(layers "F.Cu" "B.Cu")
		(remove_unused_layers yes)
		(keep_end_layers yes)
		(zone_layer_connections "In1.Cu" "In3.Cu" "In5.Cu" "In7.Cu" "In10.Cu")
		(net 1)
	)
	(via
		(at 202.5 159.5)
		(size 0.45)
		(drill 0.1)
		(layers "F.Cu" "B.Cu")
		(remove_unused_layers yes)
		(keep_end_layers yes)
		(zone_layer_connections "In1.Cu" "In3.Cu" "In5.Cu" "In7.Cu" "In10.Cu")
		(net 1)
	)
	(via
		(at 143.7 145.95)
		(size 0.45)
		(drill 0.1)
		(layers "F.Cu" "B.Cu")
		(remove_unused_layers yes)
		(keep_end_layers yes)
		(zone_layer_connections "In1.Cu" "In3.Cu" "In5.Cu" "In7.Cu" "In10.Cu")
		(net 1)
	)
	(via
		(at 255.26 115.525)
		(size 0.45)
		(drill 0.1)
		(layers "F.Cu" "B.Cu")
		(remove_unused_layers yes)
		(keep_end_layers yes)
		(zone_layer_connections "In1.Cu" "In3.Cu" "In5.Cu" "In7.Cu" "In10.Cu")
		(net 1)
	)
	(via
		(at 224.685 177.985)
		(size 0.45)
		(drill 0.1)
		(layers "F.Cu" "B.Cu")
		(remove_unused_layers yes)
		(keep_end_layers yes)
		(zone_layer_connections "In1.Cu" "In3.Cu" "In5.Cu" "In7.Cu" "In10.Cu")
		(net 1)
	)
	(via
		(at 196.5 160.5)
		(size 0.45)
		(drill 0.1)
		(layers "F.Cu" "B.Cu")
		(remove_unused_layers yes)
		(keep_end_layers yes)
		(zone_layer_connections "In1.Cu" "In3.Cu" "In5.Cu" "In7.Cu" "In10.Cu")
		(net 1)
	)
	(via
		(at 132.624499 188.649)
		(size 0.45)
		(drill 0.1)
		(layers "F.Cu" "B.Cu")
		(remove_unused_layers yes)
		(keep_end_layers yes)
		(zone_layer_connections "In1.Cu" "In3.Cu" "In5.Cu" "In7.Cu" "In10.Cu")
		(net 1)
	)
	(via
		(at 229.222 152.85)
		(size 0.45)
		(drill 0.1)
		(layers "F.Cu" "B.Cu")
		(remove_unused_layers yes)
		(keep_end_layers yes)
		(zone_layer_connections "In1.Cu" "In3.Cu" "In5.Cu" "In7.Cu" "In10.Cu")
		(net 1)
	)
	(via
		(at 202.5 163.5)
		(size 0.45)
		(drill 0.1)
		(layers "F.Cu" "B.Cu")
		(remove_unused_layers yes)
		(keep_end_layers yes)
		(zone_layer_connections "In1.Cu" "In3.Cu" "In5.Cu" "In7.Cu" "In10.Cu")
		(net 1)
	)
	(via
		(at 151.9795 194.789501)
		(size 0.45)
		(drill 0.1)
		(layers "F.Cu" "B.Cu")
		(remove_unused_layers yes)
		(keep_end_layers yes)
		(zone_layer_connections "In1.Cu" "In3.Cu" "In5.Cu" "In7.Cu" "In10.Cu")
		(net 1)
	)
	(via
		(at 181.5 158.5)
		(size 0.45)
		(drill 0.1)
		(layers "F.Cu" "B.Cu")
		(remove_unused_layers yes)
		(keep_end_layers yes)
		(zone_layer_connections "In1.Cu" "In3.Cu" "In5.Cu" "In7.Cu" "In10.Cu")
		(net 1)
	)
	(via
		(at 138.6 104.848)
		(size 0.45)
		(drill 0.1)
		(layers "F.Cu" "B.Cu")
		(remove_unused_layers yes)
		(keep_end_layers yes)
		(zone_layer_connections "In1.Cu" "In3.Cu" "In5.Cu" "In7.Cu" "In10.Cu")
		(net 1)
	)
	(via
		(at 223.735 171.46)
		(size 0.45)
		(drill 0.1)
		(layers "F.Cu" "B.Cu")
		(remove_unused_layers yes)
		(keep_end_layers yes)
		(zone_layer_connections "In1.Cu" "In3.Cu" "In5.Cu" "In7.Cu" "In10.Cu")
		(net 1)
	)
	(via
		(at 145.974499 169.399)
		(size 0.45)
		(drill 0.1)
		(layers "F.Cu" "B.Cu")
		(remove_unused_layers yes)
		(keep_end_layers yes)
		(zone_layer_connections "In1.Cu" "In3.Cu" "In5.Cu" "In7.Cu" "In10.Cu")
		(net 1)
	)
	(via
		(at 229.31 183.385)
		(size 0.45)
		(drill 0.1)
		(layers "F.Cu" "B.Cu")
		(remove_unused_layers yes)
		(keep_end_layers yes)
		(zone_layer_connections "In1.Cu" "In3.Cu" "In5.Cu" "In7.Cu" "In10.Cu")
		(net 1)
	)
	(via
		(at 224.35 157.025)
		(size 0.45)
		(drill 0.1)
		(layers "F.Cu" "B.Cu")
		(remove_unused_layers yes)
		(keep_end_layers yes)
		(zone_layer_connections "In1.Cu" "In3.Cu" "In5.Cu" "In7.Cu" "In10.Cu")
		(net 1)
	)
	(via
		(at 208.8 156.05)
		(size 0.45)
		(drill 0.1)
		(layers "F.Cu" "B.Cu")
		(remove_unused_layers yes)
		(keep_end_layers yes)
		(zone_layer_connections "In1.Cu" "In3.Cu" "In5.Cu" "In7.Cu" "In10.Cu")
		(net 1)
	)
	(via
		(at 150.950499 168.649)
		(size 0.45)
		(drill 0.1)
		(layers "F.Cu" "B.Cu")
		(remove_unused_layers yes)
		(keep_end_layers yes)
		(zone_layer_connections "In1.Cu" "In3.Cu" "In5.Cu" "In7.Cu" "In10.Cu")
		(net 1)
	)
	(via
		(at 242.399499 163.93)
		(size 0.45)
		(drill 0.1)
		(layers "F.Cu" "B.Cu")
		(remove_unused_layers yes)
		(keep_end_layers yes)
		(zone_layer_connections "In1.Cu" "In2.Cu" "In3.Cu" "In5.Cu" "In7.Cu" "In10.Cu")
		(net 1)
	)
	(via
		(at 227.001 104.848)
		(size 0.45)
		(drill 0.1)
		(layers "F.Cu" "B.Cu")
		(remove_unused_layers yes)
		(keep_end_layers yes)
		(zone_layer_connections "In1.Cu" "In3.Cu" "In5.Cu" "In7.Cu" "In10.Cu")
		(net 1)
	)
	(via
		(at 252.25 177.3)
		(size 0.45)
		(drill 0.1)
		(layers "F.Cu" "B.Cu")
		(remove_unused_layers yes)
		(keep_end_layers yes)
		(zone_layer_connections "In1.Cu" "In2.Cu" "In3.Cu" "In5.Cu" "In6.Cu" "In7.Cu"
			"In10.Cu"
		)
		(net 1)
	)
	(via
		(at 153.55 185.45)
		(size 0.45)
		(drill 0.1)
		(layers "F.Cu" "B.Cu")
		(remove_unused_layers yes)
		(keep_end_layers yes)
		(zone_layer_connections "In1.Cu" "In3.Cu" "In5.Cu" "In7.Cu" "In10.Cu")
		(net 1)
	)
	(via
		(at 250.95 119.7)
		(size 0.45)
		(drill 0.1)
		(layers "F.Cu" "B.Cu")
		(remove_unused_layers yes)
		(keep_end_layers yes)
		(zone_layer_connections "In1.Cu" "In3.Cu" "In5.Cu" "In7.Cu" "In10.Cu")
		(net 1)
	)
	(via
		(at 255.94 112.665)
		(size 0.45)
		(drill 0.1)
		(layers "F.Cu" "B.Cu")
		(remove_unused_layers yes)
		(keep_end_layers yes)
		(zone_layer_connections "In1.Cu" "In3.Cu" "In5.Cu" "In7.Cu" "In10.Cu")
		(net 1)
	)
	(via
		(at 257.37 114.785)
		(size 0.45)
		(drill 0.1)
		(layers "F.Cu" "B.Cu")
		(remove_unused_layers yes)
		(keep_end_layers yes)
		(zone_layer_connections "In1.Cu" "In3.Cu" "In5.Cu" "In7.Cu" "In10.Cu")
		(net 1)
	)
	(via
		(at 213.625 157.125)
		(size 0.45)
		(drill 0.1)
		(layers "F.Cu" "B.Cu")
		(remove_unused_layers yes)
		(keep_end_layers yes)
		(zone_layer_connections "In1.Cu" "In3.Cu" "In5.Cu" "In7.Cu" "In10.Cu")
		(net 1)
	)
	(via
		(at 179.5 146.5)
		(size 0.45)
		(drill 0.1)
		(layers "F.Cu" "B.Cu")
		(remove_unused_layers yes)
		(keep_end_layers yes)
		(zone_layer_connections "In1.Cu" "In3.Cu" "In5.Cu" "In7.Cu" "In10.Cu")
		(net 1)
	)
	(via
		(at 262.474499 158.399)
		(size 0.45)
		(drill 0.1)
		(layers "F.Cu" "B.Cu")
		(remove_unused_layers yes)
		(keep_end_layers yes)
		(zone_layer_connections "In1.Cu" "In3.Cu" "In5.Cu" "In6.Cu" "In7.Cu" "In10.Cu")
		(net 1)
	)
	(via
		(at 132.47 155.7)
		(size 0.45)
		(drill 0.1)
		(layers "F.Cu" "B.Cu")
		(remove_unused_layers yes)
		(keep_end_layers yes)
		(zone_layer_connections "In1.Cu" "In3.Cu" "In5.Cu" "In7.Cu" "In10.Cu")
		(net 1)
	)
	(via
		(at 196.55 189.46)
		(size 0.45)
		(drill 0.1)
		(layers "F.Cu" "B.Cu")
		(remove_unused_layers yes)
		(keep_end_layers yes)
		(zone_layer_connections "In1.Cu" "In3.Cu" "In5.Cu" "In7.Cu" "In10.Cu")
		(net 1)
	)
	(via
		(at 202.5 155.5)
		(size 0.45)
		(drill 0.1)
		(layers "F.Cu" "B.Cu")
		(remove_unused_layers yes)
		(keep_end_layers yes)
		(zone_layer_connections "In1.Cu" "In3.Cu" "In5.Cu" "In7.Cu" "In10.Cu")
		(net 1)
	)
	(via
		(at 209.15 109.446)
		(size 0.45)
		(drill 0.1)
		(layers "F.Cu" "B.Cu")
		(remove_unused_layers yes)
		(keep_end_layers yes)
		(zone_layer_connections "In1.Cu" "In3.Cu" "In5.Cu" "In7.Cu" "In10.Cu")
		(net 1)
	)
	(via
		(at 224.285 169.435)
		(size 0.45)
		(drill 0.1)
		(layers "F.Cu" "B.Cu")
		(remove_unused_layers yes)
		(keep_end_layers yes)
		(zone_layer_connections "In1.Cu" "In3.Cu" "In5.Cu" "In7.Cu" "In10.Cu")
		(net 1)
	)
	(via
		(at 151.35 109.446)
		(size 0.45)
		(drill 0.1)
		(layers "F.Cu" "B.Cu")
		(remove_unused_layers yes)
		(keep_end_layers yes)
		(zone_layer_connections "In1.Cu" "In3.Cu" "In5.Cu" "In7.Cu" "In10.Cu")
		(net 1)
	)
	(via
		(at 161.33 178.09)
		(size 0.45)
		(drill 0.1)
		(layers "F.Cu" "B.Cu")
		(remove_unused_layers yes)
		(keep_end_layers yes)
		(zone_layer_connections "In1.Cu" "In3.Cu" "In5.Cu" "In7.Cu" "In10.Cu")
		(net 1)
	)
	(via
		(at 176.5 158.5)
		(size 0.45)
		(drill 0.1)
		(layers "F.Cu" "B.Cu")
		(remove_unused_layers yes)
		(keep_end_layers yes)
		(zone_layer_connections "In1.Cu" "In3.Cu" "In5.Cu" "In7.Cu" "In10.Cu")
		(net 1)
	)
	(via
		(at 263.39 115.28)
		(size 0.45)
		(drill 0.1)
		(layers "F.Cu" "B.Cu")
		(remove_unused_layers yes)
		(keep_end_layers yes)
		(zone_layer_connections "In1.Cu" "In3.Cu" "In5.Cu" "In7.Cu" "In10.Cu")
		(net 1)
	)
	(via
		(at 213.035 182.335)
		(size 0.45)
		(drill 0.1)
		(layers "F.Cu" "B.Cu")
		(remove_unused_layers yes)
		(keep_end_layers yes)
		(zone_layer_connections "In1.Cu" "In3.Cu" "In5.Cu" "In7.Cu" "In10.Cu")
		(net 1)
	)
	(via
		(at 255.645 172.7595)
		(size 0.45)
		(drill 0.1)
		(layers "F.Cu" "B.Cu")
		(remove_unused_layers yes)
		(keep_end_layers yes)
		(zone_layer_connections "In1.Cu" "In2.Cu" "In3.Cu" "In4.Cu" "In5.Cu" "In6.Cu"
			"In7.Cu" "In10.Cu"
		)
		(net 1)
	)
	(via
		(at 109.85 163.875)
		(size 0.45)
		(drill 0.1)
		(layers "F.Cu" "B.Cu")
		(remove_unused_layers yes)
		(keep_end_layers yes)
		(zone_layer_connections "In1.Cu" "In3.Cu" "In5.Cu" "In7.Cu" "In10.Cu")
		(net 1)
	)
	(via
		(at 260.81 112.75)
		(size 0.45)
		(drill 0.1)
		(layers "F.Cu" "B.Cu")
		(remove_unused_layers yes)
		(keep_end_layers yes)
		(zone_layer_connections "In1.Cu" "In3.Cu" "In5.Cu" "In7.Cu" "In10.Cu")
		(net 1)
	)
	(via
		(at 241 130.05)
		(size 0.45)
		(drill 0.1)
		(layers "F.Cu" "B.Cu")
		(remove_unused_layers yes)
		(keep_end_layers yes)
		(zone_layer_connections "In1.Cu" "In3.Cu" "In5.Cu" "In7.Cu" "In10.Cu")
		(net 1)
	)
	(via
		(at 202.351 104.848)
		(size 0.45)
		(drill 0.1)
		(layers "F.Cu" "B.Cu")
		(remove_unused_layers yes)
		(keep_end_layers yes)
		(zone_layer_connections "In1.Cu" "In3.Cu" "In5.Cu" "In7.Cu" "In10.Cu")
		(net 1)
	)
	(via
		(at 114.632499 182.5535)
		(size 0.45)
		(drill 0.1)
		(layers "F.Cu" "B.Cu")
		(remove_unused_layers yes)
		(keep_end_layers yes)
		(zone_layer_connections "In1.Cu" "In3.Cu" "In5.Cu" "In7.Cu" "In10.Cu")
		(net 1)
	)
	(via
		(at 118.749499 117.201)
		(size 0.45)
		(drill 0.1)
		(layers "F.Cu" "B.Cu")
		(remove_unused_layers yes)
		(keep_end_layers yes)
		(zone_layer_connections "In1.Cu" "In3.Cu" "In5.Cu" "In7.Cu" "In10.Cu")
		(net 1)
	)
	(via
		(at 198.95 104.848)
		(size 0.45)
		(drill 0.1)
		(layers "F.Cu" "B.Cu")
		(remove_unused_layers yes)
		(keep_end_layers yes)
		(zone_layer_connections "In1.Cu" "In3.Cu" "In5.Cu" "In7.Cu" "In10.Cu")
		(net 1)
	)
	(via
		(at 181.5005 165.4995)
		(size 0.45)
		(drill 0.1)
		(layers "F.Cu" "B.Cu")
		(remove_unused_layers yes)
		(keep_end_layers yes)
		(zone_layer_connections "In1.Cu" "In3.Cu" "In5.Cu" "In7.Cu" "In10.Cu")
		(net 1)
	)
	(via
		(at 213.2 178.09)
		(size 0.45)
		(drill 0.1)
		(layers "F.Cu" "B.Cu")
		(remove_unused_layers yes)
		(keep_end_layers yes)
		(free yes)
		(zone_layer_connections "In1.Cu" "In3.Cu" "In5.Cu" "In7.Cu" "In10.Cu")
		(net 1)
	)
	(via
		(at 122.636 126.499)
		(size 0.45)
		(drill 0.1)
		(layers "F.Cu" "B.Cu")
		(remove_unused_layers yes)
		(keep_end_layers yes)
		(zone_layer_connections "In1.Cu" "In3.Cu" "In5.Cu" "In7.Cu" "In9.Cu" "In10.Cu")
		(net 1)
	)
	(via
		(at 227.498 100.510001)
		(size 0.45)
		(drill 0.1)
		(layers "F.Cu" "B.Cu")
		(remove_unused_layers yes)
		(keep_end_layers yes)
		(zone_layer_connections "In1.Cu" "In3.Cu" "In5.Cu" "In7.Cu" "In10.Cu")
		(net 1)
	)
	(via
		(at 150.9 183.75)
		(size 0.45)
		(drill 0.1)
		(layers "F.Cu" "B.Cu")
		(remove_unused_layers yes)
		(keep_end_layers yes)
		(zone_layer_connections "In1.Cu" "In3.Cu" "In5.Cu" "In7.Cu" "In10.Cu")
		(net 1)
	)
	(via
		(at 199.5 148.5)
		(size 0.45)
		(drill 0.1)
		(layers "F.Cu" "B.Cu")
		(remove_unused_layers yes)
		(keep_end_layers yes)
		(zone_layer_connections "In1.Cu" "In3.Cu" "In5.Cu" "In7.Cu" "In10.Cu")
		(net 1)
	)
	(via
		(at 130.656 170.552)
		(size 0.45)
		(drill 0.1)
		(layers "F.Cu" "B.Cu")
		(remove_unused_layers yes)
		(keep_end_layers yes)
		(zone_layer_connections "In1.Cu" "In3.Cu" "In5.Cu" "In7.Cu" "In10.Cu")
		(net 1)
	)
	(via
		(at 178.500001 162.5)
		(size 0.45)
		(drill 0.1)
		(layers "F.Cu" "B.Cu")
		(remove_unused_layers yes)
		(keep_end_layers yes)
		(zone_layer_connections "In1.Cu" "In3.Cu" "In5.Cu" "In7.Cu" "In10.Cu")
		(net 1)
	)
	(via
		(at 205.752 109.446)
		(size 0.45)
		(drill 0.1)
		(layers "F.Cu" "B.Cu")
		(remove_unused_layers yes)
		(keep_end_layers yes)
		(zone_layer_connections "In1.Cu" "In3.Cu" "In5.Cu" "In7.Cu" "In10.Cu")
		(net 1)
	)
	(via
		(at 261.924499 180.549)
		(size 0.45)
		(drill 0.1)
		(layers "F.Cu" "B.Cu")
		(remove_unused_layers yes)
		(keep_end_layers yes)
		(zone_layer_connections "In1.Cu" "In3.Cu" "In5.Cu" "In6.Cu" "In7.Cu" "In10.Cu")
		(net 1)
	)
	(via
		(at 135.924499 145.399)
		(size 0.45)
		(drill 0.1)
		(layers "F.Cu" "B.Cu")
		(remove_unused_layers yes)
		(keep_end_layers yes)
		(zone_layer_connections "In1.Cu" "In3.Cu" "In5.Cu" "In7.Cu" "In10.Cu")
		(net 1)
	)
	(via
		(at 222.751 104.848)
		(size 0.45)
		(drill 0.1)
		(layers "F.Cu" "B.Cu")
		(remove_unused_layers yes)
		(keep_end_layers yes)
		(zone_layer_connections "In1.Cu" "In3.Cu" "In5.Cu" "In7.Cu" "In10.Cu")
		(net 1)
	)
	(via
		(at 217.65 104.848)
		(size 0.45)
		(drill 0.1)
		(layers "F.Cu" "B.Cu")
		(remove_unused_layers yes)
		(keep_end_layers yes)
		(zone_layer_connections "In1.Cu" "In3.Cu" "In5.Cu" "In7.Cu" "In10.Cu")
		(net 1)
	)
	(via
		(at 200 165.7064)
		(size 0.45)
		(drill 0.1)
		(layers "F.Cu" "B.Cu")
		(remove_unused_layers yes)
		(keep_end_layers yes)
		(zone_layer_connections "In1.Cu" "In3.Cu" "In5.Cu" "In7.Cu" "In10.Cu")
		(net 1)
	)
	(via
		(at 125.85 104.848)
		(size 0.45)
		(drill 0.1)
		(layers "F.Cu" "B.Cu")
		(remove_unused_layers yes)
		(keep_end_layers yes)
		(zone_layer_connections "In1.Cu" "In3.Cu" "In5.Cu" "In7.Cu" "In10.Cu")
		(net 1)
	)
	(via
		(at 166.6866 100.498601)
		(size 0.45)
		(drill 0.1)
		(layers "F.Cu" "B.Cu")
		(remove_unused_layers yes)
		(keep_end_layers yes)
		(zone_layer_connections "In1.Cu" "In3.Cu" "In5.Cu" "In7.Cu" "In10.Cu")
		(net 1)
	)
	(via
		(at 210.735 184.535)
		(size 0.45)
		(drill 0.1)
		(layers "F.Cu" "B.Cu")
		(remove_unused_layers yes)
		(keep_end_layers yes)
		(zone_layer_connections "In1.Cu" "In3.Cu" "In5.Cu" "In7.Cu" "In10.Cu")
		(net 1)
	)
	(via
		(at 169.202 104.848)
		(size 0.45)
		(drill 0.1)
		(layers "F.Cu" "B.Cu")
		(remove_unused_layers yes)
		(keep_end_layers yes)
		(zone_layer_connections "In1.Cu" "In3.Cu" "In5.Cu" "In7.Cu" "In10.Cu")
		(net 1)
	)
	(via
		(at 159.95 155.975)
		(size 0.45)
		(drill 0.1)
		(layers "F.Cu" "B.Cu")
		(remove_unused_layers yes)
		(keep_end_layers yes)
		(zone_layer_connections "In1.Cu" "In3.Cu" "In5.Cu" "In7.Cu" "In10.Cu")
		(net 1)
	)
	(via
		(at 177.5 158.5)
		(size 0.45)
		(drill 0.1)
		(layers "F.Cu" "B.Cu")
		(remove_unused_layers yes)
		(keep_end_layers yes)
		(zone_layer_connections "In1.Cu" "In3.Cu" "In5.Cu" "In7.Cu" "In10.Cu")
		(net 1)
	)
	(via
		(at 112.037258 170.3535)
		(size 0.45)
		(drill 0.1)
		(layers "F.Cu" "B.Cu")
		(remove_unused_layers yes)
		(keep_end_layers yes)
		(zone_layer_connections "In1.Cu" "In3.Cu" "In5.Cu" "In7.Cu" "In10.Cu")
		(net 1)
	)
	(via
		(at 254.725 105.275)
		(size 0.45)
		(drill 0.1)
		(layers "F.Cu" "B.Cu")
		(remove_unused_layers yes)
		(keep_end_layers yes)
		(zone_layer_connections "In1.Cu" "In3.Cu" "In5.Cu" "In7.Cu" "In10.Cu")
		(net 1)
	)
	(via
		(at 134.924499 145.399)
		(size 0.45)
		(drill 0.1)
		(layers "F.Cu" "B.Cu")
		(remove_unused_layers yes)
		(keep_end_layers yes)
		(zone_layer_connections "In1.Cu" "In3.Cu" "In5.Cu" "In7.Cu" "In10.Cu")
		(net 1)
	)
	(via
		(at 211.935 180.085)
		(size 0.45)
		(drill 0.1)
		(layers "F.Cu" "B.Cu")
		(remove_unused_layers yes)
		(keep_end_layers yes)
		(zone_layer_connections "In1.Cu" "In3.Cu" "In5.Cu" "In7.Cu" "In10.Cu")
		(net 1)
	)
	(via
		(at 256.624499 159.449)
		(size 0.45)
		(drill 0.1)
		(layers "F.Cu" "B.Cu")
		(remove_unused_layers yes)
		(keep_end_layers yes)
		(zone_layer_connections "In1.Cu" "In3.Cu" "In4.Cu" "In5.Cu" "In6.Cu" "In7.Cu"
			"In10.Cu"
		)
		(net 1)
	)
	(via
		(at 163.4866 100.498601)
		(size 0.45)
		(drill 0.1)
		(layers "F.Cu" "B.Cu")
		(remove_unused_layers yes)
		(keep_end_layers yes)
		(zone_layer_connections "In1.Cu" "In3.Cu" "In5.Cu" "In7.Cu" "In10.Cu")
		(net 1)
	)
	(via
		(at 166.65 104.848)
		(size 0.45)
		(drill 0.1)
		(layers "F.Cu" "B.Cu")
		(remove_unused_layers yes)
		(keep_end_layers yes)
		(zone_layer_connections "In1.Cu" "In3.Cu" "In5.Cu" "In7.Cu" "In10.Cu")
		(net 1)
	)
	(via
		(at 184.5 151.5)
		(size 0.45)
		(drill 0.1)
		(layers "F.Cu" "B.Cu")
		(remove_unused_layers yes)
		(keep_end_layers yes)
		(zone_layer_connections "In1.Cu" "In3.Cu" "In5.Cu" "In7.Cu" "In10.Cu")
		(net 1)
	)
	(via
		(at 200.5 141.5)
		(size 0.45)
		(drill 0.1)
		(layers "F.Cu" "B.Cu")
		(remove_unused_layers yes)
		(keep_end_layers yes)
		(zone_layer_connections "In1.Cu" "In3.Cu" "In5.Cu" "In7.Cu" "In10.Cu")
		(net 1)
	)
	(via
		(at 254.7555 154.448)
		(size 0.45)
		(drill 0.1)
		(layers "F.Cu" "B.Cu")
		(remove_unused_layers yes)
		(keep_end_layers yes)
		(zone_layer_connections "In1.Cu" "In2.Cu" "In3.Cu" "In4.Cu" "In5.Cu" "In6.Cu"
			"In7.Cu" "In10.Cu"
		)
		(net 1)
	)
	(via
		(at 127.716328 143.032157)
		(size 0.45)
		(drill 0.1)
		(layers "F.Cu" "B.Cu")
		(remove_unused_layers yes)
		(keep_end_layers yes)
		(zone_layer_connections "In1.Cu" "In3.Cu" "In5.Cu" "In7.Cu" "In10.Cu")
		(net 1)
	)
	(via
		(at 185.5 148.5)
		(size 0.45)
		(drill 0.1)
		(layers "F.Cu" "B.Cu")
		(remove_unused_layers yes)
		(keep_end_layers yes)
		(zone_layer_connections "In1.Cu" "In3.Cu" "In5.Cu" "In7.Cu" "In10.Cu")
		(net 1)
	)
	(via
		(at 164.94 160.049999)
		(size 0.45)
		(drill 0.1)
		(layers "F.Cu" "B.Cu")
		(remove_unused_layers yes)
		(keep_end_layers yes)
		(zone_layer_connections "In1.Cu" "In3.Cu" "In5.Cu" "In7.Cu" "In10.Cu")
		(net 1)
	)
	(via
		(at 216.95 155.6)
		(size 0.45)
		(drill 0.1)
		(layers "F.Cu" "B.Cu")
		(remove_unused_layers yes)
		(keep_end_layers yes)
		(zone_layer_connections "In1.Cu" "In3.Cu" "In5.Cu" "In7.Cu" "In10.Cu")
		(net 1)
	)
	(via
		(at 211.285 183.46)
		(size 0.45)
		(drill 0.1)
		(layers "F.Cu" "B.Cu")
		(remove_unused_layers yes)
		(keep_end_layers yes)
		(free yes)
		(zone_layer_connections "In1.Cu" "In3.Cu" "In5.Cu" "In7.Cu" "In10.Cu")
		(net 1)
	)
	(via
		(at 145.035 143.385)
		(size 0.45)
		(drill 0.1)
		(layers "F.Cu" "B.Cu")
		(remove_unused_layers yes)
		(keep_end_layers yes)
		(zone_layer_connections "In1.Cu" "In3.Cu" "In5.Cu" "In7.Cu" "In10.Cu")
		(net 1)
	)
	(via
		(at 237.129499 187.262)
		(size 0.45)
		(drill 0.1)
		(layers "F.Cu" "B.Cu")
		(remove_unused_layers yes)
		(keep_end_layers yes)
		(zone_layer_connections "In1.Cu" "In3.Cu" "In5.Cu" "In7.Cu" "In10.Cu")
		(net 1)
	)
	(via
		(at 229.222 150.85)
		(size 0.45)
		(drill 0.1)
		(layers "F.Cu" "B.Cu")
		(remove_unused_layers yes)
		(keep_end_layers yes)
		(zone_layer_connections "In1.Cu" "In3.Cu" "In5.Cu" "In7.Cu" "In10.Cu")
		(net 1)
	)
	(via
		(at 106.807 163.868)
		(size 0.45)
		(drill 0.1)
		(layers "F.Cu" "B.Cu")
		(remove_unused_layers yes)
		(keep_end_layers yes)
		(zone_layer_connections "In1.Cu" "In3.Cu" "In5.Cu" "In7.Cu" "In10.Cu")
		(net 1)
	)
	(via
		(at 177.5 164.5)
		(size 0.45)
		(drill 0.1)
		(layers "F.Cu" "B.Cu")
		(remove_unused_layers yes)
		(keep_end_layers yes)
		(zone_layer_connections "In1.Cu" "In3.Cu" "In5.Cu" "In7.Cu" "In10.Cu")
		(net 1)
	)
	(via
		(at 224.285 170.51)
		(size 0.45)
		(drill 0.1)
		(layers "F.Cu" "B.Cu")
		(remove_unused_layers yes)
		(keep_end_layers yes)
		(zone_layer_connections "In1.Cu" "In3.Cu" "In5.Cu" "In7.Cu" "In10.Cu")
		(net 1)
	)
	(via
		(at 254.7555 156.171)
		(size 0.45)
		(drill 0.1)
		(layers "F.Cu" "B.Cu")
		(remove_unused_layers yes)
		(keep_end_layers yes)
		(zone_layer_connections "In1.Cu" "In2.Cu" "In3.Cu" "In4.Cu" "In5.Cu" "In6.Cu"
			"In7.Cu" "In10.Cu"
		)
		(net 1)
	)
	(via
		(at 185.5005 165.4995)
		(size 0.45)
		(drill 0.1)
		(layers "F.Cu" "B.Cu")
		(remove_unused_layers yes)
		(keep_end_layers yes)
		(zone_layer_connections "In1.Cu" "In3.Cu" "In5.Cu" "In7.Cu" "In10.Cu")
		(net 1)
	)
	(via
		(at 234.61 169.935)
		(size 0.45)
		(drill 0.1)
		(layers "F.Cu" "B.Cu")
		(remove_unused_layers yes)
		(keep_end_layers yes)
		(zone_layer_connections "In1.Cu" "In3.Cu" "In5.Cu" "In7.Cu" "In10.Cu")
		(net 1)
	)
	(via
		(at 252.11 189.46)
		(size 0.45)
		(drill 0.1)
		(layers "F.Cu" "B.Cu")
		(remove_unused_layers yes)
		(keep_end_layers yes)
		(zone_layer_connections "In1.Cu" "In3.Cu" "In5.Cu" "In7.Cu" "In10.Cu")
		(net 1)
	)
	(via
		(at 211.935 188.685)
		(size 0.45)
		(drill 0.1)
		(layers "F.Cu" "B.Cu")
		(remove_unused_layers yes)
		(keep_end_layers yes)
		(zone_layer_connections "In1.Cu" "In3.Cu" "In5.Cu" "In7.Cu" "In10.Cu")
		(net 1)
	)
	(via
		(at 215.101 109.446)
		(size 0.45)
		(drill 0.1)
		(layers "F.Cu" "B.Cu")
		(remove_unused_layers yes)
		(keep_end_layers yes)
		(zone_layer_connections "In1.Cu" "In3.Cu" "In5.Cu" "In7.Cu" "In10.Cu")
		(net 1)
	)
	(via
		(at 166.72 164.24)
		(size 0.45)
		(drill 0.1)
		(layers "F.Cu" "B.Cu")
		(remove_unused_layers yes)
		(keep_end_layers yes)
		(zone_layer_connections "In1.Cu" "In3.Cu" "In5.Cu" "In7.Cu" "In10.Cu")
		(net 1)
	)
	(via
		(at 150.6866 100.498601)
		(size 0.45)
		(drill 0.1)
		(layers "F.Cu" "B.Cu")
		(remove_unused_layers yes)
		(keep_end_layers yes)
		(zone_layer_connections "In1.Cu" "In3.Cu" "In5.Cu" "In7.Cu" "In10.Cu")
		(net 1)
	)
	(via
		(at 263.924499 143.949)
		(size 0.45)
		(drill 0.1)
		(layers "F.Cu" "B.Cu")
		(remove_unused_layers yes)
		(keep_end_layers yes)
		(zone_layer_connections "In1.Cu" "In3.Cu" "In5.Cu" "In7.Cu" "In10.Cu")
		(net 1)
	)
	(via
		(at 126.875 145.522149)
		(size 0.45)
		(drill 0.1)
		(layers "F.Cu" "B.Cu")
		(remove_unused_layers yes)
		(keep_end_layers yes)
		(zone_layer_connections "In1.Cu" "In3.Cu" "In5.Cu" "In7.Cu" "In10.Cu")
		(net 1)
	)
	(via
		(at 210.549001 155.098999)
		(size 0.45)
		(drill 0.1)
		(layers "F.Cu" "B.Cu")
		(remove_unused_layers yes)
		(keep_end_layers yes)
		(zone_layer_connections "In1.Cu" "In3.Cu" "In5.Cu" "In7.Cu" "In10.Cu")
		(net 1)
	)
	(via
		(at 249.572499 155.223)
		(size 0.45)
		(drill 0.1)
		(layers "F.Cu" "B.Cu")
		(remove_unused_layers yes)
		(keep_end_layers yes)
		(zone_layer_connections "In1.Cu" "In2.Cu" "In3.Cu" "In4.Cu" "In5.Cu" "In6.Cu"
			"In7.Cu" "In10.Cu"
		)
		(net 1)
	)
	(via
		(at 223.585 174.685)
		(size 0.45)
		(drill 0.1)
		(layers "F.Cu" "B.Cu")
		(remove_unused_layers yes)
		(keep_end_layers yes)
		(zone_layer_connections "In1.Cu" "In3.Cu" "In5.Cu" "In7.Cu" "In10.Cu")
		(net 1)
	)
	(via
		(at 184.87 102.73)
		(size 0.45)
		(drill 0.1)
		(layers "F.Cu" "B.Cu")
		(remove_unused_layers yes)
		(keep_end_layers yes)
		(zone_layer_connections "In1.Cu" "In3.Cu" "In5.Cu" "In7.Cu" "In10.Cu")
		(net 1)
	)
	(via
		(at 215.53 176.95)
		(size 0.45)
		(drill 0.1)
		(layers "F.Cu" "B.Cu")
		(remove_unused_layers yes)
		(keep_end_layers yes)
		(zone_layer_connections "In1.Cu" "In3.Cu" "In5.Cu" "In7.Cu" "In10.Cu")
		(net 1)
	)
	(via
		(at 178.5 143.5)
		(size 0.45)
		(drill 0.1)
		(layers "F.Cu" "B.Cu")
		(remove_unused_layers yes)
		(keep_end_layers yes)
		(zone_layer_connections "In1.Cu" "In3.Cu" "In5.Cu" "In7.Cu" "In10.Cu")
		(net 1)
	)
	(via
		(at 192.5 147.5)
		(size 0.45)
		(drill 0.1)
		(layers "F.Cu" "B.Cu")
		(remove_unused_layers yes)
		(keep_end_layers yes)
		(zone_layer_connections "In1.Cu" "In3.Cu" "In5.Cu" "In7.Cu" "In10.Cu")
		(net 1)
	)
	(via
		(at 214.735 187.685)
		(size 0.45)
		(drill 0.1)
		(layers "F.Cu" "B.Cu")
		(remove_unused_layers yes)
		(keep_end_layers yes)
		(zone_layer_connections "In1.Cu" "In3.Cu" "In5.Cu" "In7.Cu" "In10.Cu")
		(net 1)
	)
	(via
		(at 213.585 179.135)
		(size 0.45)
		(drill 0.1)
		(layers "F.Cu" "B.Cu")
		(remove_unused_layers yes)
		(keep_end_layers yes)
		(free yes)
		(zone_layer_connections "In1.Cu" "In3.Cu" "In5.Cu" "In7.Cu" "In10.Cu")
		(net 1)
	)
	(via
		(at 201.4995 158.4995)
		(size 0.45)
		(drill 0.1)
		(layers "F.Cu" "B.Cu")
		(remove_unused_layers yes)
		(keep_end_layers yes)
		(zone_layer_connections "In1.Cu" "In3.Cu" "In5.Cu" "In7.Cu" "In10.Cu")
		(net 1)
	)
	(via
		(at 191.5 163.5)
		(size 0.45)
		(drill 0.1)
		(layers "F.Cu" "B.Cu")
		(remove_unused_layers yes)
		(keep_end_layers yes)
		(zone_layer_connections "In1.Cu" "In3.Cu" "In5.Cu" "In7.Cu" "In10.Cu")
		(net 1)
	)
	(via
		(at 262.474499 175.049)
		(size 0.45)
		(drill 0.1)
		(layers "F.Cu" "B.Cu")
		(remove_unused_layers yes)
		(keep_end_layers yes)
		(zone_layer_connections "In1.Cu" "In3.Cu" "In5.Cu" "In6.Cu" "In7.Cu" "In10.Cu")
		(net 1)
	)
	(via
		(at 241.07 115.14)
		(size 0.45)
		(drill 0.1)
		(layers "F.Cu" "B.Cu")
		(remove_unused_layers yes)
		(keep_end_layers yes)
		(zone_layer_connections "In1.Cu" "In3.Cu" "In5.Cu" "In7.Cu" "In10.Cu")
		(net 1)
	)
	(via
		(at 190.5 148.5)
		(size 0.45)
		(drill 0.1)
		(layers "F.Cu" "B.Cu")
		(remove_unused_layers yes)
		(keep_end_layers yes)
		(zone_layer_connections "In1.Cu" "In3.Cu" "In5.Cu" "In7.Cu" "In10.Cu")
		(net 1)
	)
	(via
		(at 235.501 109.446)
		(size 0.45)
		(drill 0.1)
		(layers "F.Cu" "B.Cu")
		(remove_unused_layers yes)
		(keep_end_layers yes)
		(zone_layer_connections "In1.Cu" "In3.Cu" "In5.Cu" "In7.Cu" "In10.Cu")
		(net 1)
	)
	(via
		(at 119.625 157.65)
		(size 0.45)
		(drill 0.1)
		(layers "F.Cu" "B.Cu")
		(remove_unused_layers yes)
		(keep_end_layers yes)
		(zone_layer_connections "In1.Cu" "In3.Cu" "In5.Cu" "In7.Cu" "In10.Cu")
		(net 1)
	)
	(via
		(at 261.374499 159.349)
		(size 0.45)
		(drill 0.1)
		(layers "F.Cu" "B.Cu")
		(remove_unused_layers yes)
		(keep_end_layers yes)
		(zone_layer_connections "In1.Cu" "In3.Cu" "In5.Cu" "In6.Cu" "In7.Cu" "In10.Cu")
		(net 1)
	)
	(via
		(at 213.585 187.735)
		(size 0.45)
		(drill 0.1)
		(layers "F.Cu" "B.Cu")
		(remove_unused_layers yes)
		(keep_end_layers yes)
		(zone_layer_connections "In1.Cu" "In3.Cu" "In5.Cu" "In7.Cu" "In10.Cu")
		(net 1)
	)
	(via
		(at 235.06 169.385)
		(size 0.45)
		(drill 0.1)
		(layers "F.Cu" "B.Cu")
		(remove_unused_layers yes)
		(keep_end_layers yes)
		(zone_layer_connections "In1.Cu" "In3.Cu" "In5.Cu" "In7.Cu" "In10.Cu")
		(net 1)
	)
	(via
		(at 246.365 187.404)
		(size 0.45)
		(drill 0.1)
		(layers "F.Cu" "B.Cu")
		(remove_unused_layers yes)
		(keep_end_layers yes)
		(zone_layer_connections "In1.Cu" "In3.Cu" "In5.Cu" "In7.Cu" "In10.Cu")
		(net 1)
	)
	(via
		(at 124.5616 155.0416)
		(size 0.45)
		(drill 0.1)
		(layers "F.Cu" "B.Cu")
		(remove_unused_layers yes)
		(keep_end_layers yes)
		(zone_layer_connections "In1.Cu" "In3.Cu" "In5.Cu" "In7.Cu" "In10.Cu")
		(net 1)
	)
	(via
		(at 175.125 194.849501)
		(size 0.45)
		(drill 0.1)
		(layers "F.Cu" "B.Cu")
		(remove_unused_layers yes)
		(keep_end_layers yes)
		(zone_layer_connections "In1.Cu" "In3.Cu" "In5.Cu" "In7.Cu" "In10.Cu")
		(net 1)
	)
	(via
		(at 157.0866 100.498601)
		(size 0.45)
		(drill 0.1)
		(layers "F.Cu" "B.Cu")
		(remove_unused_layers yes)
		(keep_end_layers yes)
		(zone_layer_connections "In1.Cu" "In3.Cu" "In5.Cu" "In7.Cu" "In10.Cu")
		(net 1)
	)
	(via
		(at 105.95 154.97)
		(size 0.45)
		(drill 0.1)
		(layers "F.Cu" "B.Cu")
		(remove_unused_layers yes)
		(keep_end_layers yes)
		(zone_layer_connections "In1.Cu" "In3.Cu" "In5.Cu" "In7.Cu" "In10.Cu")
		(net 1)
	)
	(via
		(at 262.397 135.424999)
		(size 0.45)
		(drill 0.1)
		(layers "F.Cu" "B.Cu")
		(remove_unused_layers yes)
		(keep_end_layers yes)
		(zone_layer_connections "In1.Cu" "In3.Cu" "In5.Cu" "In7.Cu" "In10.Cu")
		(net 1)
	)
	(via
		(at 124.5616 151.0538)
		(size 0.45)
		(drill 0.1)
		(layers "F.Cu" "B.Cu")
		(remove_unused_layers yes)
		(keep_end_layers yes)
		(zone_layer_connections "In1.Cu" "In3.Cu" "In5.Cu" "In7.Cu" "In10.Cu")
		(net 1)
	)
	(via
		(at 256.5055 171.899)
		(size 0.45)
		(drill 0.1)
		(layers "F.Cu" "B.Cu")
		(remove_unused_layers yes)
		(keep_end_layers yes)
		(zone_layer_connections "In1.Cu" "In2.Cu" "In3.Cu" "In4.Cu" "In5.Cu" "In6.Cu"
			"In7.Cu" "In10.Cu"
		)
		(net 1)
	)
	(via
		(at 133.82 176.9485)
		(size 0.45)
		(drill 0.1)
		(layers "F.Cu" "B.Cu")
		(remove_unused_layers yes)
		(keep_end_layers yes)
		(zone_layer_connections "In1.Cu" "In3.Cu" "In5.Cu" "In7.Cu" "In10.Cu")
		(net 1)
	)
	(via
		(at 249.599499 172.674)
		(size 0.45)
		(drill 0.1)
		(layers "F.Cu" "B.Cu")
		(remove_unused_layers yes)
		(keep_end_layers yes)
		(zone_layer_connections "In1.Cu" "In2.Cu" "In3.Cu" "In4.Cu" "In5.Cu" "In6.Cu"
			"In7.Cu" "In10.Cu"
		)
		(net 1)
	)
	(via
		(at 151.050499 171.667)
		(size 0.45)
		(drill 0.1)
		(layers "F.Cu" "B.Cu")
		(remove_unused_layers yes)
		(keep_end_layers yes)
		(zone_layer_connections "In1.Cu" "In3.Cu" "In5.Cu" "In7.Cu" "In10.Cu")
		(net 1)
	)
	(via
		(at 171.1595 101.1785)
		(size 0.45)
		(drill 0.1)
		(layers "F.Cu" "B.Cu")
		(remove_unused_layers yes)
		(keep_end_layers yes)
		(zone_layer_connections "In1.Cu" "In3.Cu" "In5.Cu" "In7.Cu" "In10.Cu")
		(net 1)
	)
	(via
		(at 189.5 154.5)
		(size 0.45)
		(drill 0.1)
		(layers "F.Cu" "B.Cu")
		(remove_unused_layers yes)
		(keep_end_layers yes)
		(zone_layer_connections "In1.Cu" "In3.Cu" "In5.Cu" "In7.Cu" "In10.Cu")
		(net 1)
	)
	(via
		(at 170.3 133.16)
		(size 0.45)
		(drill 0.1)
		(layers "F.Cu" "B.Cu")
		(remove_unused_layers yes)
		(keep_end_layers yes)
		(zone_layer_connections "In1.Cu" "In3.Cu" "In5.Cu" "In7.Cu" "In10.Cu")
		(net 1)
	)
	(via
		(at 192.5 150.5)
		(size 0.45)
		(drill 0.1)
		(layers "F.Cu" "B.Cu")
		(remove_unused_layers yes)
		(keep_end_layers yes)
		(zone_layer_connections "In1.Cu" "In3.Cu" "In5.Cu" "In7.Cu" "In10.Cu")
		(net 1)
	)
	(via
		(at 241.124499 184.599)
		(size 0.45)
		(drill 0.1)
		(layers "F.Cu" "B.Cu")
		(remove_unused_layers yes)
		(keep_end_layers yes)
		(zone_layer_connections "In1.Cu" "In3.Cu" "In5.Cu" "In7.Cu" "In10.Cu")
		(net 1)
	)
	(via
		(at 247.904 142.099)
		(size 0.45)
		(drill 0.1)
		(layers "F.Cu" "B.Cu")
		(remove_unused_layers yes)
		(keep_end_layers yes)
		(zone_layer_connections "In1.Cu" "In3.Cu" "In5.Cu" "In7.Cu" "In10.Cu")
		(net 1)
	)
	(via
		(at 208.8 158.2)
		(size 0.45)
		(drill 0.1)
		(layers "F.Cu" "B.Cu")
		(remove_unused_layers yes)
		(keep_end_layers yes)
		(zone_layer_connections "In1.Cu" "In3.Cu" "In5.Cu" "In7.Cu" "In10.Cu")
		(net 1)
	)
	(via
		(at 256.474499 176.899)
		(size 0.45)
		(drill 0.1)
		(layers "F.Cu" "B.Cu")
		(remove_unused_layers yes)
		(keep_end_layers yes)
		(zone_layer_connections "In1.Cu" "In3.Cu" "In4.Cu" "In5.Cu" "In6.Cu" "In7.Cu"
			"In10.Cu"
		)
		(net 1)
	)
	(via
		(at 247.924499 173.349)
		(size 0.45)
		(drill 0.1)
		(layers "F.Cu" "B.Cu")
		(remove_unused_layers yes)
		(keep_end_layers yes)
		(zone_layer_connections "In1.Cu" "In2.Cu" "In3.Cu" "In4.Cu" "In5.Cu" "In6.Cu"
			"In7.Cu" "In10.Cu"
		)
		(net 1)
	)
	(via
		(at 221.8 155.55)
		(size 0.45)
		(drill 0.1)
		(layers "F.Cu" "B.Cu")
		(remove_unused_layers yes)
		(keep_end_layers yes)
		(zone_layer_connections "In1.Cu" "In3.Cu" "In5.Cu" "In7.Cu" "In10.Cu")
		(net 1)
	)
	(via
		(at 105.83 128.051)
		(size 0.45)
		(drill 0.1)
		(layers "F.Cu" "B.Cu")
		(remove_unused_layers yes)
		(keep_end_layers yes)
		(free yes)
		(zone_layer_connections "In1.Cu" "In3.Cu" "In5.Cu" "In7.Cu" "In10.Cu")
		(net 1)
	)
	(via
		(at 187.500001 153.5)
		(size 0.45)
		(drill 0.1)
		(layers "F.Cu" "B.Cu")
		(remove_unused_layers yes)
		(keep_end_layers yes)
		(zone_layer_connections "In1.Cu" "In3.Cu" "In5.Cu" "In7.Cu" "In10.Cu")
		(net 1)
	)
	(via
		(at 128.506 173.113)
		(size 0.45)
		(drill 0.1)
		(layers "F.Cu" "B.Cu")
		(remove_unused_layers yes)
		(keep_end_layers yes)
		(zone_layer_connections "In1.Cu" "In3.Cu" "In5.Cu" "In7.Cu" "In10.Cu")
		(net 1)
	)
	(via
		(at 190.5 150.5)
		(size 0.45)
		(drill 0.1)
		(layers "F.Cu" "B.Cu")
		(remove_unused_layers yes)
		(keep_end_layers yes)
		(zone_layer_connections "In1.Cu" "In3.Cu" "In5.Cu" "In7.Cu" "In10.Cu")
		(net 1)
	)
	(via
		(at 174.795 107.75)
		(size 0.45)
		(drill 0.1)
		(layers "F.Cu" "B.Cu")
		(remove_unused_layers yes)
		(keep_end_layers yes)
		(zone_layer_connections "In1.Cu" "In3.Cu" "In5.Cu" "In7.Cu" "In10.Cu")
		(net 1)
	)
	(via
		(at 193.5 140.5)
		(size 0.45)
		(drill 0.1)
		(layers "F.Cu" "B.Cu")
		(remove_unused_layers yes)
		(keep_end_layers yes)
		(zone_layer_connections "In1.Cu" "In3.Cu" "In5.Cu" "In7.Cu" "In10.Cu")
		(net 1)
	)
	(via
		(at 187.5 158.5)
		(size 0.45)
		(drill 0.1)
		(layers "F.Cu" "B.Cu")
		(remove_unused_layers yes)
		(keep_end_layers yes)
		(zone_layer_connections "In1.Cu" "In3.Cu" "In5.Cu" "In7.Cu" "In10.Cu")
		(net 1)
	)
	(via
		(at 156.25 158.4)
		(size 0.45)
		(drill 0.1)
		(layers "F.Cu" "B.Cu")
		(remove_unused_layers yes)
		(keep_end_layers yes)
		(zone_layer_connections "In1.Cu" "In3.Cu" "In5.Cu" "In7.Cu" "In10.Cu")
		(net 1)
	)
	(via
		(at 261.324499 157.524)
		(size 0.45)
		(drill 0.1)
		(layers "F.Cu" "B.Cu")
		(remove_unused_layers yes)
		(keep_end_layers yes)
		(zone_layer_connections "In1.Cu" "In3.Cu" "In5.Cu" "In6.Cu" "In7.Cu" "In10.Cu")
		(net 1)
	)
	(via
		(at 156.39 169.87)
		(size 0.45)
		(drill 0.1)
		(layers "F.Cu" "B.Cu")
		(remove_unused_layers yes)
		(keep_end_layers yes)
		(zone_layer_connections "In1.Cu" "In3.Cu" "In5.Cu" "In7.Cu" "In10.Cu")
		(net 1)
	)
	(via
		(at 256.65 112.665)
		(size 0.45)
		(drill 0.1)
		(layers "F.Cu" "B.Cu")
		(remove_unused_layers yes)
		(keep_end_layers yes)
		(zone_layer_connections "In1.Cu" "In3.Cu" "In5.Cu" "In7.Cu" "In10.Cu")
		(net 1)
	)
	(via
		(at 250.924499 155.249)
		(size 0.45)
		(drill 0.1)
		(layers "F.Cu" "B.Cu")
		(remove_unused_layers yes)
		(keep_end_layers yes)
		(zone_layer_connections "In1.Cu" "In2.Cu" "In3.Cu" "In4.Cu" "In5.Cu" "In6.Cu"
			"In7.Cu" "In10.Cu"
		)
		(net 1)
	)
	(via
		(at 207.292864 142.792864)
		(size 0.45)
		(drill 0.1)
		(layers "F.Cu" "B.Cu")
		(net 1)
	)
	(via
		(at 258.424499 151.149)
		(size 0.45)
		(drill 0.1)
		(layers "F.Cu" "B.Cu")
		(remove_unused_layers yes)
		(keep_end_layers yes)
		(zone_layer_connections "In1.Cu" "In3.Cu" "In4.Cu" "In5.Cu" "In6.Cu" "In7.Cu"
			"In10.Cu"
		)
		(net 1)
	)
	(via
		(at 135.023499 186.349)
		(size 0.45)
		(drill 0.1)
		(layers "F.Cu" "B.Cu")
		(remove_unused_layers yes)
		(keep_end_layers yes)
		(zone_layer_connections "In1.Cu" "In3.Cu" "In5.Cu" "In7.Cu" "In10.Cu")
		(net 1)
	)
	(via
		(at 177.5 165.5)
		(size 0.45)
		(drill 0.1)
		(layers "F.Cu" "B.Cu")
		(remove_unused_layers yes)
		(keep_end_layers yes)
		(zone_layer_connections "In1.Cu" "In3.Cu" "In5.Cu" "In7.Cu" "In10.Cu")
		(net 1)
	)
	(via
		(at 253.55 181.575)
		(size 0.45)
		(drill 0.1)
		(layers "F.Cu" "B.Cu")
		(remove_unused_layers yes)
		(keep_end_layers yes)
		(zone_layer_connections "In1.Cu" "In3.Cu" "In5.Cu" "In6.Cu" "In7.Cu" "In10.Cu")
		(net 1)
	)
	(via
		(at 150.275 113.875)
		(size 0.45)
		(drill 0.1)
		(layers "F.Cu" "B.Cu")
		(remove_unused_layers yes)
		(keep_end_layers yes)
		(zone_layer_connections "In1.Cu" "In3.Cu" "In5.Cu" "In7.Cu" "In9.Cu" "In10.Cu")
		(net 1)
	)
	(via
		(at 240.45 114.95)
		(size 0.45)
		(drill 0.1)
		(layers "F.Cu" "B.Cu")
		(remove_unused_layers yes)
		(keep_end_layers yes)
		(zone_layer_connections "In1.Cu" "In3.Cu" "In5.Cu" "In7.Cu" "In10.Cu")
		(net 1)
	)
	(via
		(at 233.95 176.35)
		(size 0.45)
		(drill 0.1)
		(layers "F.Cu" "B.Cu")
		(remove_unused_layers yes)
		(keep_end_layers yes)
		(zone_layer_connections "In1.Cu" "In3.Cu" "In5.Cu" "In7.Cu" "In10.Cu")
		(net 1)
	)
	(via
		(at 226.6 185.55)
		(size 0.45)
		(drill 0.1)
		(layers "F.Cu" "B.Cu")
		(remove_unused_layers yes)
		(keep_end_layers yes)
		(zone_layer_connections "In1.Cu" "In3.Cu" "In5.Cu" "In7.Cu" "In10.Cu")
		(net 1)
	)
	(via
		(at 201.4995 161.4995)
		(size 0.45)
		(drill 0.1)
		(layers "F.Cu" "B.Cu")
		(remove_unused_layers yes)
		(keep_end_layers yes)
		(zone_layer_connections "In1.Cu" "In3.Cu" "In5.Cu" "In7.Cu" "In10.Cu")
		(net 1)
	)
	(via
		(at 153.7995 194.249501)
		(size 0.45)
		(drill 0.1)
		(layers "F.Cu" "B.Cu")
		(remove_unused_layers yes)
		(keep_end_layers yes)
		(zone_layer_connections "In1.Cu" "In3.Cu" "In5.Cu" "In7.Cu" "In10.Cu")
		(net 1)
	)
	(via
		(at 180.5 144.5)
		(size 0.45)
		(drill 0.1)
		(layers "F.Cu" "B.Cu")
		(remove_unused_layers yes)
		(keep_end_layers yes)
		(zone_layer_connections "In1.Cu" "In3.Cu" "In5.Cu" "In7.Cu" "In10.Cu")
		(net 1)
	)
	(via
		(at 116.225 117.45)
		(size 0.45)
		(drill 0.1)
		(layers "F.Cu" "B.Cu")
		(remove_unused_layers yes)
		(keep_end_layers yes)
		(zone_layer_connections "In1.Cu" "In3.Cu" "In5.Cu" "In7.Cu" "In10.Cu")
		(net 1)
	)
	(via
		(at 132.052656 140.592165)
		(size 0.45)
		(drill 0.1)
		(layers "F.Cu" "B.Cu")
		(remove_unused_layers yes)
		(keep_end_layers yes)
		(zone_layer_connections "In1.Cu" "In3.Cu" "In5.Cu" "In7.Cu" "In10.Cu")
		(net 1)
	)
	(via
		(at 195.5 146.5)
		(size 0.45)
		(drill 0.1)
		(layers "F.Cu" "B.Cu")
		(remove_unused_layers yes)
		(keep_end_layers yes)
		(zone_layer_connections "In1.Cu" "In3.Cu" "In5.Cu" "In7.Cu" "In10.Cu")
		(net 1)
	)
	(via
		(at 135.6355 101.1895)
		(size 0.45)
		(drill 0.1)
		(layers "F.Cu" "B.Cu")
		(remove_unused_layers yes)
		(keep_end_layers yes)
		(zone_layer_connections "In1.Cu" "In3.Cu" "In5.Cu" "In7.Cu" "In10.Cu")
		(net 1)
	)
	(via
		(at 263.024499 180.549)
		(size 0.45)
		(drill 0.1)
		(layers "F.Cu" "B.Cu")
		(remove_unused_layers yes)
		(keep_end_layers yes)
		(zone_layer_connections "In1.Cu" "In3.Cu" "In5.Cu" "In6.Cu" "In7.Cu" "In10.Cu")
		(net 1)
	)
	(via
		(at 126.701 109.446)
		(size 0.45)
		(drill 0.1)
		(layers "F.Cu" "B.Cu")
		(remove_unused_layers yes)
		(keep_end_layers yes)
		(zone_layer_connections "In1.Cu" "In3.Cu" "In5.Cu" "In7.Cu" "In10.Cu")
		(net 1)
	)
	(via
		(at 201.5 155.5)
		(size 0.45)
		(drill 0.1)
		(layers "F.Cu" "B.Cu")
		(remove_unused_layers yes)
		(keep_end_layers yes)
		(zone_layer_connections "In1.Cu" "In3.Cu" "In5.Cu" "In7.Cu" "In10.Cu")
		(net 1)
	)
	(via
		(at 122.646 122.124)
		(size 0.45)
		(drill 0.1)
		(layers "F.Cu" "B.Cu")
		(remove_unused_layers yes)
		(keep_end_layers yes)
		(zone_layer_connections "In1.Cu" "In3.Cu" "In5.Cu" "In7.Cu" "In9.Cu" "In10.Cu")
		(net 1)
	)
	(via
		(at 185.500001 155.5)
		(size 0.45)
		(drill 0.1)
		(layers "F.Cu" "B.Cu")
		(remove_unused_layers yes)
		(keep_end_layers yes)
		(zone_layer_connections "In1.Cu" "In3.Cu" "In5.Cu" "In7.Cu" "In10.Cu")
		(net 1)
	)
	(via
		(at 252.999499 134.674)
		(size 0.45)
		(drill 0.1)
		(layers "F.Cu" "B.Cu")
		(remove_unused_layers yes)
		(keep_end_layers yes)
		(zone_layer_connections "In1.Cu" "In3.Cu" "In5.Cu" "In7.Cu" "In10.Cu")
		(net 1)
	)
	(via
		(at 224.385 185.63)
		(size 0.45)
		(drill 0.1)
		(layers "F.Cu" "B.Cu")
		(remove_unused_layers yes)
		(keep_end_layers yes)
		(zone_layer_connections "In1.Cu" "In3.Cu" "In5.Cu" "In7.Cu" "In10.Cu")
		(net 1)
	)
	(via
		(at 224.285 168.36)
		(size 0.45)
		(drill 0.1)
		(layers "F.Cu" "B.Cu")
		(remove_unused_layers yes)
		(keep_end_layers yes)
		(zone_layer_connections "In1.Cu" "In3.Cu" "In5.Cu" "In7.Cu" "In10.Cu")
		(net 1)
	)
	(via
		(at 186.5 149.5)
		(size 0.45)
		(drill 0.1)
		(layers "F.Cu" "B.Cu")
		(remove_unused_layers yes)
		(keep_end_layers yes)
		(zone_layer_connections "In1.Cu" "In3.Cu" "In5.Cu" "In7.Cu" "In10.Cu")
		(net 1)
	)
	(via
		(at 256.338998 140.25)
		(size 0.45)
		(drill 0.1)
		(layers "F.Cu" "B.Cu")
		(remove_unused_layers yes)
		(keep_end_layers yes)
		(zone_layer_connections "In1.Cu" "In3.Cu" "In5.Cu" "In7.Cu" "In10.Cu")
		(net 1)
	)
	(via
		(at 246.749499 173.374)
		(size 0.45)
		(drill 0.1)
		(layers "F.Cu" "B.Cu")
		(remove_unused_layers yes)
		(keep_end_layers yes)
		(zone_layer_connections "In1.Cu" "In2.Cu" "In3.Cu" "In4.Cu" "In5.Cu" "In6.Cu"
			"In7.Cu" "In10.Cu"
		)
		(net 1)
	)
	(via
		(at 105.824499 153.63)
		(size 0.45)
		(drill 0.1)
		(layers "F.Cu" "B.Cu")
		(remove_unused_layers yes)
		(keep_end_layers yes)
		(zone_layer_connections "In1.Cu" "In3.Cu" "In5.Cu" "In7.Cu" "In10.Cu")
		(net 1)
	)
	(via
		(at 201.499501 156.4995)
		(size 0.45)
		(drill 0.1)
		(layers "F.Cu" "B.Cu")
		(remove_unused_layers yes)
		(keep_end_layers yes)
		(zone_layer_connections "In1.Cu" "In3.Cu" "In5.Cu" "In7.Cu" "In10.Cu")
		(net 1)
	)
	(via
		(at 209.875 155.95)
		(size 0.45)
		(drill 0.1)
		(layers "F.Cu" "B.Cu")
		(remove_unused_layers yes)
		(keep_end_layers yes)
		(zone_layer_connections "In1.Cu" "In3.Cu" "In5.Cu" "In7.Cu" "In10.Cu")
		(net 1)
	)
	(via
		(at 261.374499 158.399)
		(size 0.45)
		(drill 0.1)
		(layers "F.Cu" "B.Cu")
		(remove_unused_layers yes)
		(keep_end_layers yes)
		(zone_layer_connections "In1.Cu" "In3.Cu" "In5.Cu" "In6.Cu" "In7.Cu" "In10.Cu")
		(net 1)
	)
	(via
		(at 105.775 159.369)
		(size 0.45)
		(drill 0.1)
		(layers "F.Cu" "B.Cu")
		(remove_unused_layers yes)
		(keep_end_layers yes)
		(zone_layer_connections "In1.Cu" "In3.Cu" "In5.Cu" "In7.Cu" "In10.Cu")
		(net 1)
	)
	(via
		(at 213.585 168.385)
		(size 0.45)
		(drill 0.1)
		(layers "F.Cu" "B.Cu")
		(remove_unused_layers yes)
		(keep_end_layers yes)
		(zone_layer_connections "In1.Cu" "In3.Cu" "In5.Cu" "In7.Cu" "In10.Cu")
		(net 1)
	)
	(via
		(at 192.151 104.848)
		(size 0.45)
		(drill 0.1)
		(layers "F.Cu" "B.Cu")
		(remove_unused_layers yes)
		(keep_end_layers yes)
		(zone_layer_connections "In1.Cu" "In3.Cu" "In5.Cu" "In7.Cu" "In10.Cu")
		(net 1)
	)
	(via
		(at 253.975 128.225)
		(size 0.45)
		(drill 0.1)
		(layers "F.Cu" "B.Cu")
		(remove_unused_layers yes)
		(keep_end_layers yes)
		(zone_layer_connections "In1.Cu" "In3.Cu" "In5.Cu" "In7.Cu" "In10.Cu")
		(net 1)
	)
	(via
		(at 223.735 176.935)
		(size 0.45)
		(drill 0.1)
		(layers "F.Cu" "B.Cu")
		(remove_unused_layers yes)
		(keep_end_layers yes)
		(zone_layer_connections "In1.Cu" "In3.Cu" "In5.Cu" "In7.Cu" "In10.Cu")
		(net 1)
	)
	(via
		(at 237.74 143.09)
		(size 0.45)
		(drill 0.1)
		(layers "F.Cu" "B.Cu")
		(remove_unused_layers yes)
		(keep_end_layers yes)
		(zone_layer_connections "In1.Cu" "In3.Cu" "In5.Cu" "In7.Cu" "In10.Cu")
		(net 1)
	)
	(via
		(at 121.7 117.15)
		(size 0.45)
		(drill 0.1)
		(layers "F.Cu" "B.Cu")
		(remove_unused_layers yes)
		(keep_end_layers yes)
		(zone_layer_connections "In1.Cu" "In3.Cu" "In5.Cu" "In7.Cu" "In10.Cu")
		(net 1)
	)
	(via
		(at 153.902 104.848)
		(size 0.45)
		(drill 0.1)
		(layers "F.Cu" "B.Cu")
		(remove_unused_layers yes)
		(keep_end_layers yes)
		(zone_layer_connections "In1.Cu" "In3.Cu" "In5.Cu" "In7.Cu" "In10.Cu")
		(net 1)
	)
	(via
		(at 178.55 104.848)
		(size 0.45)
		(drill 0.1)
		(layers "F.Cu" "B.Cu")
		(remove_unused_layers yes)
		(keep_end_layers yes)
		(zone_layer_connections "In1.Cu" "In3.Cu" "In5.Cu" "In7.Cu" "In10.Cu")
		(net 1)
	)
	(via
		(at 121.086 174.922)
		(size 0.45)
		(drill 0.1)
		(layers "F.Cu" "B.Cu")
		(remove_unused_layers yes)
		(keep_end_layers yes)
		(zone_layer_connections "In1.Cu" "In3.Cu" "In5.Cu" "In7.Cu" "In10.Cu")
		(net 1)
	)
	(via
		(at 181.101 109.446)
		(size 0.45)
		(drill 0.1)
		(layers "F.Cu" "B.Cu")
		(remove_unused_layers yes)
		(keep_end_layers yes)
		(zone_layer_connections "In1.Cu" "In3.Cu" "In5.Cu" "In7.Cu" "In10.Cu")
		(net 1)
	)
	(via
		(at 247.774499 154.724)
		(size 0.45)
		(drill 0.1)
		(layers "F.Cu" "B.Cu")
		(remove_unused_layers yes)
		(keep_end_layers yes)
		(zone_layer_connections "In1.Cu" "In2.Cu" "In3.Cu" "In4.Cu" "In5.Cu" "In6.Cu"
			"In7.Cu" "In10.Cu"
		)
		(net 1)
	)
	(via
		(at 244.001 104.848)
		(size 0.45)
		(drill 0.1)
		(layers "F.Cu" "B.Cu")
		(remove_unused_layers yes)
		(keep_end_layers yes)
		(zone_layer_connections "In1.Cu" "In3.Cu" "In5.Cu" "In7.Cu" "In10.Cu")
		(net 1)
	)
	(via
		(at 211.285 181.285)
		(size 0.45)
		(drill 0.1)
		(layers "F.Cu" "B.Cu")
		(remove_unused_layers yes)
		(keep_end_layers yes)
		(free yes)
		(zone_layer_connections "In1.Cu" "In3.Cu" "In5.Cu" "In7.Cu" "In10.Cu")
		(net 1)
	)
	(via
		(at 204.875 171)
		(size 0.45)
		(drill 0.1)
		(layers "F.Cu" "B.Cu")
		(remove_unused_layers yes)
		(keep_end_layers yes)
		(zone_layer_connections "In1.Cu" "In3.Cu" "In5.Cu" "In7.Cu" "In10.Cu")
		(net 1)
	)
	(via
		(at 214.698 100.510001)
		(size 0.45)
		(drill 0.1)
		(layers "F.Cu" "B.Cu")
		(remove_unused_layers yes)
		(keep_end_layers yes)
		(zone_layer_connections "In1.Cu" "In3.Cu" "In5.Cu" "In7.Cu" "In10.Cu")
		(net 1)
	)
	(via
		(at 212.485 181.16)
		(size 0.45)
		(drill 0.1)
		(layers "F.Cu" "B.Cu")
		(remove_unused_layers yes)
		(keep_end_layers yes)
		(zone_layer_connections "In1.Cu" "In3.Cu" "In5.Cu" "In7.Cu" "In10.Cu")
		(net 1)
	)
	(via
		(at 126.306 174.912)
		(size 0.45)
		(drill 0.1)
		(layers "F.Cu" "B.Cu")
		(remove_unused_layers yes)
		(keep_end_layers yes)
		(zone_layer_connections "In1.Cu" "In3.Cu" "In5.Cu" "In7.Cu" "In10.Cu")
		(net 1)
	)
	(via
		(at 227.25 163.15)
		(size 0.45)
		(drill 0.1)
		(layers "F.Cu" "B.Cu")
		(remove_unused_layers yes)
		(keep_end_layers yes)
		(zone_layer_connections "In1.Cu" "In3.Cu" "In5.Cu" "In7.Cu" "In10.Cu")
		(net 1)
	)
	(via
		(at 105.977 163.868)
		(size 0.45)
		(drill 0.1)
		(layers "F.Cu" "B.Cu")
		(remove_unused_layers yes)
		(keep_end_layers yes)
		(zone_layer_connections "In1.Cu" "In3.Cu" "In5.Cu" "In7.Cu" "In10.Cu")
		(net 1)
	)
	(via
		(at 259.498 100.510001)
		(size 0.45)
		(drill 0.1)
		(layers "F.Cu" "B.Cu")
		(remove_unused_layers yes)
		(keep_end_layers yes)
		(zone_layer_connections "In1.Cu" "In3.Cu" "In5.Cu" "In7.Cu" "In10.Cu")
		(net 1)
	)
	(via
		(at 232.1 104.848)
		(size 0.45)
		(drill 0.1)
		(layers "F.Cu" "B.Cu")
		(remove_unused_layers yes)
		(keep_end_layers yes)
		(zone_layer_connections "In1.Cu" "In3.Cu" "In5.Cu" "In7.Cu" "In10.Cu")
		(net 1)
	)
	(via
		(at 234.785 171.51)
		(size 0.45)
		(drill 0.1)
		(layers "F.Cu" "B.Cu")
		(remove_unused_layers yes)
		(keep_end_layers yes)
		(zone_layer_connections "In1.Cu" "In3.Cu" "In5.Cu" "In7.Cu" "In10.Cu")
		(net 1)
	)
	(via
		(at 110.209499 149.049)
		(size 0.45)
		(drill 0.1)
		(layers "F.Cu" "B.Cu")
		(remove_unused_layers yes)
		(keep_end_layers yes)
		(zone_layer_connections "In1.Cu" "In3.Cu" "In5.Cu" "In7.Cu" "In10.Cu")
		(net 1)
	)
	(via
		(at 166.6 150)
		(size 0.45)
		(drill 0.1)
		(layers "F.Cu" "B.Cu")
		(remove_unused_layers yes)
		(keep_end_layers yes)
		(zone_layer_connections "In1.Cu" "In3.Cu" "In5.Cu" "In7.Cu" "In10.Cu")
		(net 1)
	)
	(via
		(at 198.5 140.5)
		(size 0.45)
		(drill 0.1)
		(layers "F.Cu" "B.Cu")
		(remove_unused_layers yes)
		(keep_end_layers yes)
		(zone_layer_connections "In1.Cu" "In3.Cu" "In5.Cu" "In7.Cu" "In10.Cu")
		(net 1)
	)
	(via
		(at 246.551 109.446)
		(size 0.45)
		(drill 0.1)
		(layers "F.Cu" "B.Cu")
		(remove_unused_layers yes)
		(keep_end_layers yes)
		(zone_layer_connections "In1.Cu" "In3.Cu" "In5.Cu" "In7.Cu" "In10.Cu")
		(net 1)
	)
	(via
		(at 251.151499 167.85)
		(size 0.45)
		(drill 0.1)
		(layers "F.Cu" "B.Cu")
		(remove_unused_layers yes)
		(keep_end_layers yes)
		(zone_layer_connections "In1.Cu" "In2.Cu" "In3.Cu" "In5.Cu" "In6.Cu" "In7.Cu"
			"In10.Cu"
		)
		(net 1)
	)
	(via
		(at 246.749499 172.124)
		(size 0.45)
		(drill 0.1)
		(layers "F.Cu" "B.Cu")
		(remove_unused_layers yes)
		(keep_end_layers yes)
		(zone_layer_connections "In1.Cu" "In2.Cu" "In3.Cu" "In4.Cu" "In5.Cu" "In6.Cu"
			"In7.Cu" "In10.Cu"
		)
		(net 1)
	)
	(via
		(at 105.824499 134.61)
		(size 0.45)
		(drill 0.1)
		(layers "F.Cu" "B.Cu")
		(remove_unused_layers yes)
		(keep_end_layers yes)
		(zone_layer_connections "In1.Cu" "In3.Cu" "In5.Cu" "In7.Cu" "In10.Cu")
		(net 1)
	)
	(via
		(at 123.8826 118.4976)
		(size 0.45)
		(drill 0.1)
		(layers "F.Cu" "B.Cu")
		(remove_unused_layers yes)
		(keep_end_layers yes)
		(zone_layer_connections "In1.Cu" "In3.Cu" "In5.Cu" "In7.Cu" "In9.Cu" "In10.Cu")
		(net 1)
	)
	(via
		(at 154.75 109.446)
		(size 0.45)
		(drill 0.1)
		(layers "F.Cu" "B.Cu")
		(remove_unused_layers yes)
		(keep_end_layers yes)
		(zone_layer_connections "In1.Cu" "In3.Cu" "In5.Cu" "In7.Cu" "In10.Cu")
		(net 1)
	)
	(via
		(at 192.5 153.5)
		(size 0.45)
		(drill 0.1)
		(layers "F.Cu" "B.Cu")
		(remove_unused_layers yes)
		(keep_end_layers yes)
		(zone_layer_connections "In1.Cu" "In3.Cu" "In5.Cu" "In7.Cu" "In10.Cu")
		(net 1)
	)
	(via
		(at 195.03 102.73)
		(size 0.45)
		(drill 0.1)
		(layers "F.Cu" "B.Cu")
		(remove_unused_layers yes)
		(keep_end_layers yes)
		(zone_layer_connections "In1.Cu" "In3.Cu" "In5.Cu" "In7.Cu" "In10.Cu")
		(net 1)
	)
	(via
		(at 185.5005 160.4995)
		(size 0.45)
		(drill 0.1)
		(layers "F.Cu" "B.Cu")
		(remove_unused_layers yes)
		(keep_end_layers yes)
		(zone_layer_connections "In1.Cu" "In3.Cu" "In5.Cu" "In7.Cu" "In10.Cu")
		(net 1)
	)
	(via
		(at 179.5 165.5)
		(size 0.45)
		(drill 0.1)
		(layers "F.Cu" "B.Cu")
		(remove_unused_layers yes)
		(keep_end_layers yes)
		(zone_layer_connections "In1.Cu" "In3.Cu" "In5.Cu" "In7.Cu" "In10.Cu")
		(net 1)
	)
	(via
		(at 183.5005 165.4995)
		(size 0.45)
		(drill 0.1)
		(layers "F.Cu" "B.Cu")
		(remove_unused_layers yes)
		(keep_end_layers yes)
		(zone_layer_connections "In1.Cu" "In3.Cu" "In5.Cu" "In7.Cu" "In10.Cu")
		(net 1)
	)
	(via
		(at 243.151 109.446)
		(size 0.45)
		(drill 0.1)
		(layers "F.Cu" "B.Cu")
		(remove_unused_layers yes)
		(keep_end_layers yes)
		(zone_layer_connections "In1.Cu" "In3.Cu" "In5.Cu" "In7.Cu" "In10.Cu")
		(net 1)
	)
	(via
		(at 180.5 155.5)
		(size 0.45)
		(drill 0.1)
		(layers "F.Cu" "B.Cu")
		(remove_unused_layers yes)
		(keep_end_layers yes)
		(zone_layer_connections "In1.Cu" "In3.Cu" "In5.Cu" "In7.Cu" "In10.Cu")
		(net 1)
	)
	(via
		(at 177.5 156.5)
		(size 0.45)
		(drill 0.1)
		(layers "F.Cu" "B.Cu")
		(remove_unused_layers yes)
		(keep_end_layers yes)
		(zone_layer_connections "In1.Cu" "In3.Cu" "In5.Cu" "In7.Cu" "In10.Cu")
		(net 1)
	)
	(via
		(at 144.552 104.848)
		(size 0.45)
		(drill 0.1)
		(layers "F.Cu" "B.Cu")
		(remove_unused_layers yes)
		(keep_end_layers yes)
		(zone_layer_connections "In1.Cu" "In3.Cu" "In5.Cu" "In7.Cu" "In10.Cu")
		(net 1)
	)
	(via
		(at 182.5 163.5)
		(size 0.45)
		(drill 0.1)
		(layers "F.Cu" "B.Cu")
		(remove_unused_layers yes)
		(keep_end_layers yes)
		(zone_layer_connections "In1.Cu" "In3.Cu" "In5.Cu" "In7.Cu" "In10.Cu")
		(net 1)
	)
	(via
		(at 198.499501 160.4995)
		(size 0.45)
		(drill 0.1)
		(layers "F.Cu" "B.Cu")
		(remove_unused_layers yes)
		(keep_end_layers yes)
		(zone_layer_connections "In1.Cu" "In3.Cu" "In5.Cu" "In7.Cu" "In10.Cu")
		(net 1)
	)
	(via
		(at 262.474499 175.649)
		(size 0.45)
		(drill 0.1)
		(layers "F.Cu" "B.Cu")
		(remove_unused_layers yes)
		(keep_end_layers yes)
		(zone_layer_connections "In1.Cu" "In3.Cu" "In5.Cu" "In6.Cu" "In7.Cu" "In10.Cu")
		(net 1)
	)
	(via
		(at 189.175 194.849501)
		(size 0.45)
		(drill 0.1)
		(layers "F.Cu" "B.Cu")
		(remove_unused_layers yes)
		(keep_end_layers yes)
		(zone_layer_connections "In1.Cu" "In3.Cu" "In5.Cu" "In7.Cu" "In10.Cu")
		(net 1)
	)
	(via
		(at 231.0995 162.245999)
		(size 0.45)
		(drill 0.1)
		(layers "F.Cu" "B.Cu")
		(remove_unused_layers yes)
		(keep_end_layers yes)
		(zone_layer_connections "In1.Cu" "In3.Cu" "In5.Cu" "In7.Cu" "In10.Cu")
		(net 1)
	)
	(via
		(at 157.9 186.9)
		(size 0.45)
		(drill 0.1)
		(layers "F.Cu" "B.Cu")
		(remove_unused_layers yes)
		(keep_end_layers yes)
		(zone_layer_connections "In1.Cu" "In3.Cu" "In5.Cu" "In7.Cu" "In10.Cu")
		(net 1)
	)
	(via
		(at 206.601 104.848)
		(size 0.45)
		(drill 0.1)
		(layers "F.Cu" "B.Cu")
		(remove_unused_layers yes)
		(keep_end_layers yes)
		(zone_layer_connections "In1.Cu" "In3.Cu" "In5.Cu" "In7.Cu" "In10.Cu")
		(net 1)
	)
	(via
		(at 115.4 158.277)
		(size 0.45)
		(drill 0.1)
		(layers "F.Cu" "B.Cu")
		(remove_unused_layers yes)
		(keep_end_layers yes)
		(zone_layer_connections "In1.Cu" "In3.Cu" "In5.Cu" "In7.Cu" "In10.Cu")
		(net 1)
	)
	(via
		(at 125.35 162.5)
		(size 0.45)
		(drill 0.1)
		(layers "F.Cu" "B.Cu")
		(remove_unused_layers yes)
		(keep_end_layers yes)
		(zone_layer_connections "In1.Cu" "In3.Cu" "In5.Cu" "In7.Cu" "In10.Cu")
		(net 1)
	)
	(via
		(at 235.06 168.31)
		(size 0.45)
		(drill 0.1)
		(layers "F.Cu" "B.Cu")
		(remove_unused_layers yes)
		(keep_end_layers yes)
		(zone_layer_connections "In1.Cu" "In3.Cu" "In5.Cu" "In7.Cu" "In10.Cu")
		(net 1)
	)
	(via
		(at 263.424499 158.449)
		(size 0.45)
		(drill 0.1)
		(layers "F.Cu" "B.Cu")
		(remove_unused_layers yes)
		(keep_end_layers yes)
		(zone_layer_connections "In1.Cu" "In3.Cu" "In5.Cu" "In6.Cu" "In7.Cu" "In10.Cu")
		(net 1)
	)
	(via
		(at 195.5 162.5)
		(size 0.45)
		(drill 0.1)
		(layers "F.Cu" "B.Cu")
		(remove_unused_layers yes)
		(keep_end_layers yes)
		(zone_layer_connections "In1.Cu" "In3.Cu" "In5.Cu" "In7.Cu" "In10.Cu")
		(net 1)
	)
	(via
		(at 254.221999 174.1515)
		(size 0.45)
		(drill 0.1)
		(layers "F.Cu" "B.Cu")
		(remove_unused_layers yes)
		(keep_end_layers yes)
		(zone_layer_connections "In1.Cu" "In2.Cu" "In3.Cu" "In4.Cu" "In5.Cu" "In6.Cu"
			"In7.Cu" "In10.Cu"
		)
		(net 1)
	)
	(via
		(at 242.399499 173.8)
		(size 0.45)
		(drill 0.1)
		(layers "F.Cu" "B.Cu")
		(remove_unused_layers yes)
		(keep_end_layers yes)
		(zone_layer_connections "In1.Cu" "In3.Cu" "In5.Cu" "In7.Cu" "In10.Cu")
		(net 1)
	)
	(via
		(at 172.602 104.848)
		(size 0.45)
		(drill 0.1)
		(layers "F.Cu" "B.Cu")
		(remove_unused_layers yes)
		(keep_end_layers yes)
		(zone_layer_connections "In1.Cu" "In3.Cu" "In5.Cu" "In7.Cu" "In10.Cu")
		(net 1)
	)
	(via
		(at 170.42 158.43)
		(size 0.45)
		(drill 0.1)
		(layers "F.Cu" "B.Cu")
		(remove_unused_layers yes)
		(keep_end_layers yes)
		(zone_layer_connections "In1.Cu" "In3.Cu" "In5.Cu" "In7.Cu" "In10.Cu")
		(net 1)
	)
	(via
		(at 263.924499 140.749)
		(size 0.45)
		(drill 0.1)
		(layers "F.Cu" "B.Cu")
		(remove_unused_layers yes)
		(keep_end_layers yes)
		(zone_layer_connections "In1.Cu" "In3.Cu" "In5.Cu" "In7.Cu" "In10.Cu")
		(net 1)
	)
	(via
		(at 226.135001 186.68)
		(size 0.45)
		(drill 0.1)
		(layers "F.Cu" "B.Cu")
		(remove_unused_layers yes)
		(keep_end_layers yes)
		(zone_layer_connections "In1.Cu" "In3.Cu" "In5.Cu" "In7.Cu" "In10.Cu")
		(net 1)
	)
	(via
		(at 119.824499 188.649)
		(size 0.45)
		(drill 0.1)
		(layers "F.Cu" "B.Cu")
		(remove_unused_layers yes)
		(keep_end_layers yes)
		(zone_layer_connections "In1.Cu" "In3.Cu" "In5.Cu" "In7.Cu" "In10.Cu")
		(net 1)
	)
	(via
		(at 114.724499 140.149)
		(size 0.45)
		(drill 0.1)
		(layers "F.Cu" "B.Cu")
		(remove_unused_layers yes)
		(keep_end_layers yes)
		(zone_layer_connections "In1.Cu" "In3.Cu" "In5.Cu" "In7.Cu" "In10.Cu")
		(net 1)
	)
	(via
		(at 205.098 100.510001)
		(size 0.45)
		(drill 0.1)
		(layers "F.Cu" "B.Cu")
		(remove_unused_layers yes)
		(keep_end_layers yes)
		(zone_layer_connections "In1.Cu" "In3.Cu" "In5.Cu" "In7.Cu" "In10.Cu")
		(net 1)
	)
	(via
		(at 128.88 143.89)
		(size 0.45)
		(drill 0.1)
		(layers "F.Cu" "B.Cu")
		(remove_unused_layers yes)
		(keep_end_layers yes)
		(zone_layer_connections "In1.Cu" "In3.Cu" "In5.Cu" "In7.Cu" "In10.Cu")
		(net 1)
	)
	(via
		(at 221.098 100.510001)
		(size 0.45)
		(drill 0.1)
		(layers "F.Cu" "B.Cu")
		(remove_unused_layers yes)
		(keep_end_layers yes)
		(zone_layer_connections "In1.Cu" "In3.Cu" "In5.Cu" "In7.Cu" "In10.Cu")
		(net 1)
	)
	(via
		(at 239.224499 130.024)
		(size 0.45)
		(drill 0.1)
		(layers "F.Cu" "B.Cu")
		(remove_unused_layers yes)
		(keep_end_layers yes)
		(zone_layer_connections "In1.Cu" "In3.Cu" "In5.Cu" "In7.Cu" "In10.Cu")
		(net 1)
	)
	(via
		(at 225.485 187.88)
		(size 0.45)
		(drill 0.1)
		(layers "F.Cu" "B.Cu")
		(remove_unused_layers yes)
		(keep_end_layers yes)
		(zone_layer_connections "In1.Cu" "In3.Cu" "In5.Cu" "In7.Cu" "In10.Cu")
		(net 1)
	)
	(via
		(at 261.39 176.41)
		(size 0.45)
		(drill 0.1)
		(layers "F.Cu" "B.Cu")
		(remove_unused_layers yes)
		(keep_end_layers yes)
		(zone_layer_connections "In1.Cu" "In3.Cu" "In5.Cu" "In6.Cu" "In7.Cu" "In10.Cu")
		(net 1)
	)
	(via
		(at 113.026 170.3235)
		(size 0.45)
		(drill 0.1)
		(layers "F.Cu" "B.Cu")
		(remove_unused_layers yes)
		(keep_end_layers yes)
		(zone_layer_connections "In1.Cu" "In3.Cu" "In5.Cu" "In7.Cu" "In10.Cu")
		(net 1)
	)
	(via
		(at 247.124498 137.0995)
		(size 0.45)
		(drill 0.1)
		(layers "F.Cu" "B.Cu")
		(remove_unused_layers yes)
		(keep_end_layers yes)
		(zone_layer_connections "In1.Cu" "In3.Cu" "In5.Cu" "In7.Cu" "In10.Cu")
		(net 1)
	)
	(via
		(at 156.7 185.5)
		(size 0.45)
		(drill 0.1)
		(layers "F.Cu" "B.Cu")
		(remove_unused_layers yes)
		(keep_end_layers yes)
		(zone_layer_connections "In1.Cu" "In3.Cu" "In5.Cu" "In7.Cu" "In10.Cu")
		(net 1)
	)
	(via
		(at 235 166.7)
		(size 0.45)
		(drill 0.1)
		(layers "F.Cu" "B.Cu")
		(remove_unused_layers yes)
		(keep_end_layers yes)
		(zone_layer_connections "In1.Cu" "In3.Cu" "In5.Cu" "In7.Cu" "In10.Cu")
		(net 1)
	)
	(via
		(at 176.5 163.5)
		(size 0.45)
		(drill 0.1)
		(layers "F.Cu" "B.Cu")
		(remove_unused_layers yes)
		(keep_end_layers yes)
		(zone_layer_connections "In1.Cu" "In3.Cu" "In5.Cu" "In7.Cu" "In10.Cu")
		(net 1)
	)
	(via
		(at 147.4866 100.498601)
		(size 0.45)
		(drill 0.1)
		(layers "F.Cu" "B.Cu")
		(remove_unused_layers yes)
		(keep_end_layers yes)
		(zone_layer_connections "In1.Cu" "In3.Cu" "In5.Cu" "In7.Cu" "In10.Cu")
		(net 1)
	)
	(via
		(at 105.545 152.685)
		(size 0.45)
		(drill 0.1)
		(layers "F.Cu" "B.Cu")
		(remove_unused_layers yes)
		(keep_end_layers yes)
		(zone_layer_connections "In1.Cu" "In3.Cu" "In5.Cu" "In7.Cu" "In10.Cu")
		(net 1)
	)
	(via
		(at 259.774499 145.445)
		(size 0.45)
		(drill 0.1)
		(layers "F.Cu" "B.Cu")
		(remove_unused_layers yes)
		(keep_end_layers yes)
		(zone_layer_connections "In1.Cu" "In3.Cu" "In5.Cu" "In7.Cu" "In10.Cu")
		(net 1)
	)
	(via
		(at 259.751499 173.1)
		(size 0.45)
		(drill 0.1)
		(layers "F.Cu" "B.Cu")
		(remove_unused_layers yes)
		(keep_end_layers yes)
		(zone_layer_connections "In1.Cu" "In3.Cu" "In4.Cu" "In5.Cu" "In6.Cu" "In7.Cu"
			"In10.Cu"
		)
		(net 1)
	)
	(via
		(at 204.5 155.5)
		(size 0.45)
		(drill 0.1)
		(layers "F.Cu" "B.Cu")
		(remove_unused_layers yes)
		(keep_end_layers yes)
		(zone_layer_connections "In1.Cu" "In3.Cu" "In5.Cu" "In7.Cu" "In10.Cu")
		(net 1)
	)
	(via
		(at 103.45 100.498601)
		(size 0.45)
		(drill 0.1)
		(layers "F.Cu" "B.Cu")
		(remove_unused_layers yes)
		(keep_end_layers yes)
		(zone_layer_connections "In1.Cu" "In3.Cu" "In5.Cu" "In7.Cu" "In10.Cu")
		(net 1)
	)
	(via
		(at 197.5005 164.4995)
		(size 0.45)
		(drill 0.1)
		(layers "F.Cu" "B.Cu")
		(remove_unused_layers yes)
		(keep_end_layers yes)
		(zone_layer_connections "In1.Cu" "In3.Cu" "In5.Cu" "In7.Cu" "In10.Cu")
		(net 1)
	)
	(via
		(at 123.8786 125.8176)
		(size 0.45)
		(drill 0.1)
		(layers "F.Cu" "B.Cu")
		(remove_unused_layers yes)
		(keep_end_layers yes)
		(zone_layer_connections "In1.Cu" "In3.Cu" "In5.Cu" "In7.Cu" "In9.Cu" "In10.Cu")
		(net 1)
	)
	(via
		(at 130.03 178.9785)
		(size 0.45)
		(drill 0.1)
		(layers "F.Cu" "B.Cu")
		(remove_unused_layers yes)
		(keep_end_layers yes)
		(zone_layer_connections "In1.Cu" "In3.Cu" "In5.Cu" "In7.Cu" "In10.Cu")
		(net 1)
	)
	(via
		(at 255.94 115.525)
		(size 0.45)
		(drill 0.1)
		(layers "F.Cu" "B.Cu")
		(remove_unused_layers yes)
		(keep_end_layers yes)
		(zone_layer_connections "In1.Cu" "In3.Cu" "In5.Cu" "In7.Cu" "In10.Cu")
		(net 1)
	)
	(via
		(at 133.5 104.848)
		(size 0.45)
		(drill 0.1)
		(layers "F.Cu" "B.Cu")
		(remove_unused_layers yes)
		(keep_end_layers yes)
		(zone_layer_connections "In1.Cu" "In3.Cu" "In5.Cu" "In7.Cu" "In10.Cu")
		(net 1)
	)
	(via
		(at 245.71 189.46)
		(size 0.45)
		(drill 0.1)
		(layers "F.Cu" "B.Cu")
		(remove_unused_layers yes)
		(keep_end_layers yes)
		(zone_layer_connections "In1.Cu" "In3.Cu" "In5.Cu" "In7.Cu" "In10.Cu")
		(net 1)
	)
	(via
		(at 136.675 152.9)
		(size 0.45)
		(drill 0.1)
		(layers "F.Cu" "B.Cu")
		(remove_unused_layers yes)
		(keep_end_layers yes)
		(zone_layer_connections "In1.Cu" "In3.Cu" "In5.Cu" "In7.Cu" "In10.Cu")
		(net 1)
	)
	(via
		(at 185.5 163.5)
		(size 0.45)
		(drill 0.1)
		(layers "F.Cu" "B.Cu")
		(remove_unused_layers yes)
		(keep_end_layers yes)
		(zone_layer_connections "In1.Cu" "In3.Cu" "In5.Cu" "In7.Cu" "In10.Cu")
		(net 1)
	)
	(via
		(at 256.423998 132.663)
		(size 0.45)
		(drill 0.1)
		(layers "F.Cu" "B.Cu")
		(remove_unused_layers yes)
		(keep_end_layers yes)
		(zone_layer_connections "In1.Cu" "In3.Cu" "In5.Cu" "In7.Cu" "In10.Cu")
		(net 1)
	)
	(via
		(at 171.175 194.849501)
		(size 0.45)
		(drill 0.1)
		(layers "F.Cu" "B.Cu")
		(remove_unused_layers yes)
		(keep_end_layers yes)
		(zone_layer_connections "In1.Cu" "In3.Cu" "In5.Cu" "In7.Cu" "In10.Cu")
		(net 1)
	)
	(via
		(at 191.5 158.5)
		(size 0.45)
		(drill 0.1)
		(layers "F.Cu" "B.Cu")
		(remove_unused_layers yes)
		(keep_end_layers yes)
		(zone_layer_connections "In1.Cu" "In3.Cu" "In5.Cu" "In7.Cu" "In10.Cu")
		(net 1)
	)
	(via
		(at 163.95 160.039999)
		(size 0.45)
		(drill 0.1)
		(layers "F.Cu" "B.Cu")
		(remove_unused_layers yes)
		(keep_end_layers yes)
		(zone_layer_connections "In1.Cu" "In3.Cu" "In5.Cu" "In7.Cu" "In10.Cu")
		(net 1)
	)
	(via
		(at 241.124499 180.849)
		(size 0.45)
		(drill 0.1)
		(layers "F.Cu" "B.Cu")
		(remove_unused_layers yes)
		(keep_end_layers yes)
		(zone_layer_connections "In1.Cu" "In3.Cu" "In5.Cu" "In7.Cu" "In10.Cu")
		(net 1)
	)
	(via
		(at 190.5 158.5)
		(size 0.45)
		(drill 0.1)
		(layers "F.Cu" "B.Cu")
		(remove_unused_layers yes)
		(keep_end_layers yes)
		(zone_layer_connections "In1.Cu" "In3.Cu" "In5.Cu" "In7.Cu" "In10.Cu")
		(net 1)
	)
	(via
		(at 185.5 153.5)
		(size 0.45)
		(drill 0.1)
		(layers "F.Cu" "B.Cu")
		(remove_unused_layers yes)
		(keep_end_layers yes)
		(zone_layer_connections "In1.Cu" "In3.Cu" "In5.Cu" "In7.Cu" "In10.Cu")
		(net 1)
	)
	(via
		(at 254.221999 171.3515)
		(size 0.45)
		(drill 0.1)
		(layers "F.Cu" "B.Cu")
		(remove_unused_layers yes)
		(keep_end_layers yes)
		(zone_layer_connections "In1.Cu" "In2.Cu" "In3.Cu" "In4.Cu" "In5.Cu" "In6.Cu"
			"In7.Cu" "In10.Cu"
		)
		(net 1)
	)
	(via
		(at 162.7 126.74)
		(size 0.45)
		(drill 0.1)
		(layers "F.Cu" "B.Cu")
		(remove_unused_layers yes)
		(keep_end_layers yes)
		(zone_layer_connections "In1.Cu" "In3.Cu" "In5.Cu" "In7.Cu" "In10.Cu")
		(net 1)
	)
	(via
		(at 161.76 118.34)
		(size 0.45)
		(drill 0.1)
		(layers "F.Cu" "B.Cu")
		(remove_unused_layers yes)
		(keep_end_layers yes)
		(zone_layer_connections "In1.Cu" "In3.Cu" "In5.Cu" "In7.Cu" "In10.Cu")
		(net 1)
	)
	(via
		(at 194.5 163.5)
		(size 0.45)
		(drill 0.1)
		(layers "F.Cu" "B.Cu")
		(remove_unused_layers yes)
		(keep_end_layers yes)
		(zone_layer_connections "In1.Cu" "In3.Cu" "In5.Cu" "In7.Cu" "In10.Cu")
		(net 1)
	)
	(via
		(at 191.500001 162.5)
		(size 0.45)
		(drill 0.1)
		(layers "F.Cu" "B.Cu")
		(remove_unused_layers yes)
		(keep_end_layers yes)
		(zone_layer_connections "In1.Cu" "In3.Cu" "In5.Cu" "In7.Cu" "In10.Cu")
		(net 1)
	)
	(via
		(at 179.5 163.5)
		(size 0.45)
		(drill 0.1)
		(layers "F.Cu" "B.Cu")
		(remove_unused_layers yes)
		(keep_end_layers yes)
		(zone_layer_connections "In1.Cu" "In3.Cu" "In5.Cu" "In7.Cu" "In10.Cu")
		(net 1)
	)
	(via
		(at 125 109.446)
		(size 0.45)
		(drill 0.1)
		(layers "F.Cu" "B.Cu")
		(remove_unused_layers yes)
		(keep_end_layers yes)
		(zone_layer_connections "In1.Cu" "In3.Cu" "In5.Cu" "In7.Cu" "In10.Cu")
		(net 1)
	)
	(via
		(at 120.75 164.5)
		(size 0.45)
		(drill 0.1)
		(layers "F.Cu" "B.Cu")
		(remove_unused_layers yes)
		(keep_end_layers yes)
		(zone_layer_connections "In1.Cu" "In3.Cu" "In5.Cu" "In7.Cu" "In10.Cu")
		(net 1)
	)
	(via
		(at 162.4 109.446)
		(size 0.45)
		(drill 0.1)
		(layers "F.Cu" "B.Cu")
		(remove_unused_layers yes)
		(keep_end_layers yes)
		(zone_layer_connections "In1.Cu" "In3.Cu" "In5.Cu" "In7.Cu" "In10.Cu")
		(net 1)
	)
	(via
		(at 111.111 183.2685)
		(size 0.45)
		(drill 0.1)
		(layers "F.Cu" "B.Cu")
		(remove_unused_layers yes)
		(keep_end_layers yes)
		(zone_layer_connections "In1.Cu" "In3.Cu" "In5.Cu" "In7.Cu" "In10.Cu")
		(net 1)
	)
	(via
		(at 246.8 154.699)
		(size 0.45)
		(drill 0.1)
		(layers "F.Cu" "B.Cu")
		(remove_unused_layers yes)
		(keep_end_layers yes)
		(zone_layer_connections "In1.Cu" "In2.Cu" "In3.Cu" "In4.Cu" "In5.Cu" "In6.Cu"
			"In7.Cu" "In10.Cu"
		)
		(net 1)
	)
	(via
		(at 186.5 163.5)
		(size 0.45)
		(drill 0.1)
		(layers "F.Cu" "B.Cu")
		(remove_unused_layers yes)
		(keep_end_layers yes)
		(zone_layer_connections "In1.Cu" "In3.Cu" "In5.Cu" "In7.Cu" "In10.Cu")
		(net 1)
	)
	(via
		(at 235.085 174.76)
		(size 0.45)
		(drill 0.1)
		(layers "F.Cu" "B.Cu")
		(remove_unused_layers yes)
		(keep_end_layers yes)
		(zone_layer_connections "In1.Cu" "In3.Cu" "In5.Cu" "In7.Cu" "In10.Cu")
		(net 1)
	)
	(via
		(at 253.975 130.225)
		(size 0.45)
		(drill 0.1)
		(layers "F.Cu" "B.Cu")
		(remove_unused_layers yes)
		(keep_end_layers yes)
		(zone_layer_connections "In1.Cu" "In3.Cu" "In5.Cu" "In7.Cu" "In10.Cu")
		(net 1)
	)
	(via
		(at 179.5 160.5)
		(size 0.45)
		(drill 0.1)
		(layers "F.Cu" "B.Cu")
		(remove_unused_layers yes)
		(keep_end_layers yes)
		(zone_layer_connections "In1.Cu" "In3.Cu" "In5.Cu" "In7.Cu" "In10.Cu")
		(net 1)
	)
	(via
		(at 229.222 142.851)
		(size 0.45)
		(drill 0.1)
		(layers "F.Cu" "B.Cu")
		(remove_unused_layers yes)
		(keep_end_layers yes)
		(zone_layer_connections "In1.Cu" "In3.Cu" "In5.Cu" "In7.Cu" "In10.Cu")
		(net 1)
	)
	(via
		(at 183.5 158.5)
		(size 0.45)
		(drill 0.1)
		(layers "F.Cu" "B.Cu")
		(remove_unused_layers yes)
		(keep_end_layers yes)
		(zone_layer_connections "In1.Cu" "In3.Cu" "In5.Cu" "In7.Cu" "In10.Cu")
		(net 1)
	)
	(via
		(at 254.7825 171.899)
		(size 0.45)
		(drill 0.1)
		(layers "F.Cu" "B.Cu")
		(remove_unused_layers yes)
		(keep_end_layers yes)
		(zone_layer_connections "In1.Cu" "In2.Cu" "In3.Cu" "In4.Cu" "In5.Cu" "In6.Cu"
			"In7.Cu" "In10.Cu"
		)
		(net 1)
	)
	(via
		(at 216.485 186.585)
		(size 0.45)
		(drill 0.1)
		(layers "F.Cu" "B.Cu")
		(remove_unused_layers yes)
		(keep_end_layers yes)
		(zone_layer_connections "In1.Cu" "In3.Cu" "In5.Cu" "In7.Cu" "In10.Cu")
		(net 1)
	)
	(via
		(at 241.45 104.848)
		(size 0.45)
		(drill 0.1)
		(layers "F.Cu" "B.Cu")
		(remove_unused_layers yes)
		(keep_end_layers yes)
		(zone_layer_connections "In1.Cu" "In3.Cu" "In5.Cu" "In7.Cu" "In10.Cu")
		(net 1)
	)
	(via
		(at 189.5 163.5)
		(size 0.45)
		(drill 0.1)
		(layers "F.Cu" "B.Cu")
		(remove_unused_layers yes)
		(keep_end_layers yes)
		(zone_layer_connections "In1.Cu" "In3.Cu" "In5.Cu" "In7.Cu" "In10.Cu")
		(net 1)
	)
	(via
		(at 212.485 179.01)
		(size 0.45)
		(drill 0.1)
		(layers "F.Cu" "B.Cu")
		(remove_unused_layers yes)
		(keep_end_layers yes)
		(free yes)
		(zone_layer_connections "In1.Cu" "In3.Cu" "In5.Cu" "In7.Cu" "In10.Cu")
		(net 1)
	)
	(via
		(at 159.001 109.446)
		(size 0.45)
		(drill 0.1)
		(layers "F.Cu" "B.Cu")
		(remove_unused_layers yes)
		(keep_end_layers yes)
		(zone_layer_connections "In1.Cu" "In3.Cu" "In5.Cu" "In7.Cu" "In10.Cu")
		(net 1)
	)
	(via
		(at 128.402 109.446)
		(size 0.45)
		(drill 0.1)
		(layers "F.Cu" "B.Cu")
		(remove_unused_layers yes)
		(keep_end_layers yes)
		(zone_layer_connections "In1.Cu" "In3.Cu" "In5.Cu" "In7.Cu" "In10.Cu")
		(net 1)
	)
	(via
		(at 111.326 171.0485)
		(size 0.45)
		(drill 0.1)
		(layers "F.Cu" "B.Cu")
		(remove_unused_layers yes)
		(keep_end_layers yes)
		(zone_layer_connections "In1.Cu" "In3.Cu" "In5.Cu" "In7.Cu" "In10.Cu")
		(net 1)
	)
	(via
		(at 254.194999 156.7005)
		(size 0.45)
		(drill 0.1)
		(layers "F.Cu" "B.Cu")
		(remove_unused_layers yes)
		(keep_end_layers yes)
		(zone_layer_connections "In1.Cu" "In2.Cu" "In3.Cu" "In4.Cu" "In5.Cu" "In6.Cu"
			"In7.Cu" "In10.Cu"
		)
		(net 1)
	)
	(via
		(at 140.424499 170.049)
		(size 0.45)
		(drill 0.1)
		(layers "F.Cu" "B.Cu")
		(remove_unused_layers yes)
		(keep_end_layers yes)
		(zone_layer_connections "In1.Cu" "In3.Cu" "In5.Cu" "In7.Cu" "In10.Cu")
		(net 1)
	)
	(via
		(at 125.902 181.303)
		(size 0.45)
		(drill 0.1)
		(layers "F.Cu" "B.Cu")
		(remove_unused_layers yes)
		(keep_end_layers yes)
		(zone_layer_connections "In1.Cu" "In3.Cu" "In5.Cu" "In7.Cu" "In10.Cu")
		(net 1)
	)
	(via
		(at 214.6 158.1)
		(size 0.45)
		(drill 0.1)
		(layers "F.Cu" "B.Cu")
		(remove_unused_layers yes)
		(keep_end_layers yes)
		(zone_layer_connections "In1.Cu" "In3.Cu" "In5.Cu" "In7.Cu" "In10.Cu")
		(net 1)
	)
	(via
		(at 185.125 194.849501)
		(size 0.45)
		(drill 0.1)
		(layers "F.Cu" "B.Cu")
		(remove_unused_layers yes)
		(keep_end_layers yes)
		(zone_layer_connections "In1.Cu" "In3.Cu" "In5.Cu" "In7.Cu" "In10.Cu")
		(net 1)
	)
	(via
		(at 165.801 109.446)
		(size 0.45)
		(drill 0.1)
		(layers "F.Cu" "B.Cu")
		(remove_unused_layers yes)
		(keep_end_layers yes)
		(zone_layer_connections "In1.Cu" "In3.Cu" "In5.Cu" "In7.Cu" "In10.Cu")
		(net 1)
	)
	(via
		(at 195.5005 165.4995)
		(size 0.45)
		(drill 0.1)
		(layers "F.Cu" "B.Cu")
		(remove_unused_layers yes)
		(keep_end_layers yes)
		(zone_layer_connections "In1.Cu" "In3.Cu" "In5.Cu" "In7.Cu" "In10.Cu")
		(net 1)
	)
	(via
		(at 183.5 148.5)
		(size 0.45)
		(drill 0.1)
		(layers "F.Cu" "B.Cu")
		(remove_unused_layers yes)
		(keep_end_layers yes)
		(zone_layer_connections "In1.Cu" "In3.Cu" "In5.Cu" "In7.Cu" "In10.Cu")
		(net 1)
	)
	(via
		(at 212.635 170.41)
		(size 0.45)
		(drill 0.1)
		(layers "F.Cu" "B.Cu")
		(remove_unused_layers yes)
		(keep_end_layers yes)
		(zone_layer_connections "In1.Cu" "In3.Cu" "In5.Cu" "In7.Cu" "In10.Cu")
		(net 1)
	)
	(via
		(at 181.499999 142.5)
		(size 0.45)
		(drill 0.1)
		(layers "F.Cu" "B.Cu")
		(remove_unused_layers yes)
		(keep_end_layers yes)
		(zone_layer_connections "In1.Cu" "In3.Cu" "In5.Cu" "In7.Cu" "In10.Cu")
		(net 1)
	)
	(via
		(at 193.5 149.5)
		(size 0.45)
		(drill 0.1)
		(layers "F.Cu" "B.Cu")
		(remove_unused_layers yes)
		(keep_end_layers yes)
		(zone_layer_connections "In1.Cu" "In3.Cu" "In5.Cu" "In7.Cu" "In10.Cu")
		(net 1)
	)
	(via
		(at 233.9 171.1)
		(size 0.45)
		(drill 0.1)
		(layers "F.Cu" "B.Cu")
		(remove_unused_layers yes)
		(keep_end_layers yes)
		(zone_layer_connections "In1.Cu" "In3.Cu" "In5.Cu" "In7.Cu" "In10.Cu")
		(net 1)
	)
	(via
		(at 136.052 109.446)
		(size 0.45)
		(drill 0.1)
		(layers "F.Cu" "B.Cu")
		(remove_unused_layers yes)
		(keep_end_layers yes)
		(zone_layer_connections "In1.Cu" "In3.Cu" "In5.Cu" "In7.Cu" "In10.Cu")
		(net 1)
	)
	(via
		(at 226.4 156.441001)
		(size 0.45)
		(drill 0.1)
		(layers "F.Cu" "B.Cu")
		(remove_unused_layers yes)
		(keep_end_layers yes)
		(zone_layer_connections "In1.Cu" "In3.Cu" "In5.Cu" "In7.Cu" "In10.Cu")
		(net 1)
	)
	(via
		(at 193.5 163.5)
		(size 0.45)
		(drill 0.1)
		(layers "F.Cu" "B.Cu")
		(remove_unused_layers yes)
		(keep_end_layers yes)
		(zone_layer_connections "In1.Cu" "In3.Cu" "In5.Cu" "In7.Cu" "In10.Cu")
		(net 1)
	)
	(via
		(at 190.4995 163.4995)
		(size 0.45)
		(drill 0.1)
		(layers "F.Cu" "B.Cu")
		(remove_unused_layers yes)
		(keep_end_layers yes)
		(zone_layer_connections "In1.Cu" "In3.Cu" "In5.Cu" "In7.Cu" "In10.Cu")
		(net 1)
	)
	(via
		(at 230.401 104.848)
		(size 0.45)
		(drill 0.1)
		(layers "F.Cu" "B.Cu")
		(remove_unused_layers yes)
		(keep_end_layers yes)
		(zone_layer_connections "In1.Cu" "In3.Cu" "In5.Cu" "In7.Cu" "In10.Cu")
		(net 1)
	)
	(via
		(at 240.298 100.510001)
		(size 0.45)
		(drill 0.1)
		(layers "F.Cu" "B.Cu")
		(remove_unused_layers yes)
		(keep_end_layers yes)
		(zone_layer_connections "In1.Cu" "In3.Cu" "In5.Cu" "In7.Cu" "In10.Cu")
		(net 1)
	)
	(via
		(at 214.275 184.475)
		(size 0.45)
		(drill 0.1)
		(layers "F.Cu" "B.Cu")
		(remove_unused_layers yes)
		(keep_end_layers yes)
		(zone_layer_connections "In1.Cu" "In3.Cu" "In5.Cu" "In7.Cu" "In10.Cu")
		(net 1)
	)
	(via
		(at 145.402 109.446)
		(size 0.45)
		(drill 0.1)
		(layers "F.Cu" "B.Cu")
		(remove_unused_layers yes)
		(keep_end_layers yes)
		(zone_layer_connections "In1.Cu" "In3.Cu" "In5.Cu" "In7.Cu" "In10.Cu")
		(net 1)
	)
	(via
		(at 184.5 146.5)
		(size 0.45)
		(drill 0.1)
		(layers "F.Cu" "B.Cu")
		(remove_unused_layers yes)
		(keep_end_layers yes)
		(zone_layer_connections "In1.Cu" "In3.Cu" "In5.Cu" "In7.Cu" "In10.Cu")
		(net 1)
	)
	(via
		(at 223.585 172.535)
		(size 0.45)
		(drill 0.1)
		(layers "F.Cu" "B.Cu")
		(remove_unused_layers yes)
		(keep_end_layers yes)
		(zone_layer_connections "In1.Cu" "In3.Cu" "In5.Cu" "In7.Cu" "In10.Cu")
		(net 1)
	)
	(via
		(at 222.785 171.585)
		(size 0.45)
		(drill 0.1)
		(layers "F.Cu" "B.Cu")
		(remove_unused_layers yes)
		(keep_end_layers yes)
		(zone_layer_connections "In1.Cu" "In3.Cu" "In5.Cu" "In7.Cu" "In10.Cu")
		(net 1)
	)
	(via
		(at 237.276998 176.747501)
		(size 0.45)
		(drill 0.1)
		(layers "F.Cu" "B.Cu")
		(remove_unused_layers yes)
		(keep_end_layers yes)
		(zone_layer_connections "In1.Cu" "In3.Cu" "In5.Cu" "In7.Cu" "In10.Cu")
		(net 1)
	)
	(via
		(at 209.975 157.025)
		(size 0.45)
		(drill 0.1)
		(layers "F.Cu" "B.Cu")
		(remove_unused_layers yes)
		(keep_end_layers yes)
		(zone_layer_connections "In1.Cu" "In3.Cu" "In5.Cu" "In7.Cu" "In10.Cu")
		(net 1)
	)
	(via
		(at 263.424499 157.499)
		(size 0.45)
		(drill 0.1)
		(layers "F.Cu" "B.Cu")
		(remove_unused_layers yes)
		(keep_end_layers yes)
		(zone_layer_connections "In1.Cu" "In3.Cu" "In5.Cu" "In6.Cu" "In7.Cu" "In10.Cu")
		(net 1)
	)
	(via
		(at 176.298 100.510001)
		(size 0.45)
		(drill 0.1)
		(layers "F.Cu" "B.Cu")
		(remove_unused_layers yes)
		(keep_end_layers yes)
		(zone_layer_connections "In1.Cu" "In3.Cu" "In5.Cu" "In7.Cu" "In10.Cu")
		(net 1)
	)
	(via
		(at 165.125 194.824501)
		(size 0.45)
		(drill 0.1)
		(layers "F.Cu" "B.Cu")
		(remove_unused_layers yes)
		(keep_end_layers yes)
		(zone_layer_connections "In1.Cu" "In3.Cu" "In5.Cu" "In7.Cu" "In10.Cu")
		(net 1)
	)
	(via
		(at 200.500001 156.5)
		(size 0.45)
		(drill 0.1)
		(layers "F.Cu" "B.Cu")
		(remove_unused_layers yes)
		(keep_end_layers yes)
		(zone_layer_connections "In1.Cu" "In3.Cu" "In5.Cu" "In7.Cu" "In10.Cu")
		(net 1)
	)
	(via
		(at 255.594999 154.1005)
		(size 0.45)
		(drill 0.1)
		(layers "F.Cu" "B.Cu")
		(remove_unused_layers yes)
		(keep_end_layers yes)
		(zone_layer_connections "In1.Cu" "In2.Cu" "In3.Cu" "In4.Cu" "In5.Cu" "In6.Cu"
			"In7.Cu" "In10.Cu"
		)
		(net 1)
	)
	(via
		(at 214.6 155.95)
		(size 0.45)
		(drill 0.1)
		(layers "F.Cu" "B.Cu")
		(remove_unused_layers yes)
		(keep_end_layers yes)
		(zone_layer_connections "In1.Cu" "In3.Cu" "In5.Cu" "In7.Cu" "In10.Cu")
		(net 1)
	)
	(via
		(at 177.5 140.5)
		(size 0.45)
		(drill 0.1)
		(layers "F.Cu" "B.Cu")
		(remove_unused_layers yes)
		(keep_end_layers yes)
		(zone_layer_connections "In1.Cu" "In3.Cu" "In5.Cu" "In7.Cu" "In10.Cu")
		(net 1)
	)
	(via
		(at 204.875 174.55)
		(size 0.45)
		(drill 0.1)
		(layers "F.Cu" "B.Cu")
		(remove_unused_layers yes)
		(keep_end_layers yes)
		(zone_layer_connections "In1.Cu" "In3.Cu" "In5.Cu" "In7.Cu" "In10.Cu")
		(net 1)
	)
	(via
		(at 133.424499 137.999)
		(size 0.45)
		(drill 0.1)
		(layers "F.Cu" "B.Cu")
		(remove_unused_layers yes)
		(keep_end_layers yes)
		(zone_layer_connections "In1.Cu" "In3.Cu" "In5.Cu" "In7.Cu" "In10.Cu")
		(net 1)
	)
	(via
		(at 253.851499 176.8)
		(size 0.45)
		(drill 0.1)
		(layers "F.Cu" "B.Cu")
		(remove_unused_layers yes)
		(keep_end_layers yes)
		(zone_layer_connections "In1.Cu" "In2.Cu" "In3.Cu" "In4.Cu" "In5.Cu" "In6.Cu"
			"In7.Cu" "In10.Cu"
		)
		(net 1)
	)
	(via
		(at 259.774499 159.124)
		(size 0.45)
		(drill 0.1)
		(layers "F.Cu" "B.Cu")
		(remove_unused_layers yes)
		(keep_end_layers yes)
		(zone_layer_connections "In1.Cu" "In3.Cu" "In5.Cu" "In6.Cu" "In7.Cu" "In10.Cu")
		(net 1)
	)
	(via
		(at 204.875 165.725)
		(size 0.45)
		(drill 0.1)
		(layers "F.Cu" "B.Cu")
		(remove_unused_layers yes)
		(keep_end_layers yes)
		(zone_layer_connections "In1.Cu" "In3.Cu" "In5.Cu" "In7.Cu" "In10.Cu")
		(net 1)
	)
	(via
		(at 133.808 165.538)
		(size 0.45)
		(drill 0.1)
		(layers "F.Cu" "B.Cu")
		(remove_unused_layers yes)
		(keep_end_layers yes)
		(zone_layer_connections "In1.Cu" "In3.Cu" "In5.Cu" "In7.Cu" "In10.Cu")
		(net 1)
	)
	(via
		(at 236.35 104.848)
		(size 0.45)
		(drill 0.1)
		(layers "F.Cu" "B.Cu")
		(remove_unused_layers yes)
		(keep_end_layers yes)
		(zone_layer_connections "In1.Cu" "In3.Cu" "In5.Cu" "In7.Cu" "In10.Cu")
		(net 1)
	)
	(via
		(at 257.121999 174.1515)
		(size 0.45)
		(drill 0.1)
		(layers "F.Cu" "B.Cu")
		(remove_unused_layers yes)
		(keep_end_layers yes)
		(zone_layer_connections "In1.Cu" "In2.Cu" "In3.Cu" "In4.Cu" "In5.Cu" "In6.Cu"
			"In7.Cu" "In10.Cu"
		)
		(net 1)
	)
	(via
		(at 128.506 172.113)
		(size 0.45)
		(drill 0.1)
		(layers "F.Cu" "B.Cu")
		(remove_unused_layers yes)
		(keep_end_layers yes)
		(zone_layer_connections "In1.Cu" "In3.Cu" "In5.Cu" "In7.Cu" "In10.Cu")
		(net 1)
	)
	(via
		(at 109.349499 149.724)
		(size 0.45)
		(drill 0.1)
		(layers "F.Cu" "B.Cu")
		(remove_unused_layers yes)
		(keep_end_layers yes)
		(zone_layer_connections "In1.Cu" "In3.Cu" "In5.Cu" "In7.Cu" "In10.Cu")
		(net 1)
	)
	(via
		(at 157.301 104.848)
		(size 0.45)
		(drill 0.1)
		(layers "F.Cu" "B.Cu")
		(remove_unused_layers yes)
		(keep_end_layers yes)
		(zone_layer_connections "In1.Cu" "In3.Cu" "In5.Cu" "In7.Cu" "In10.Cu")
		(net 1)
	)
	(via
		(at 218.65 184.245001)
		(size 0.45)
		(drill 0.1)
		(layers "F.Cu" "B.Cu")
		(remove_unused_layers yes)
		(keep_end_layers yes)
		(zone_layer_connections "In1.Cu" "In3.Cu" "In5.Cu" "In7.Cu" "In10.Cu")
		(net 1)
	)
	(via
		(at 133.006843 161.831328)
		(size 0.45)
		(drill 0.1)
		(layers "F.Cu" "B.Cu")
		(remove_unused_layers yes)
		(keep_end_layers yes)
		(zone_layer_connections "In1.Cu" "In3.Cu" "In5.Cu" "In7.Cu" "In10.Cu")
		(net 1)
	)
	(via
		(at 115.4866 100.498601)
		(size 0.45)
		(drill 0.1)
		(layers "F.Cu" "B.Cu")
		(remove_unused_layers yes)
		(keep_end_layers yes)
		(zone_layer_connections "In1.Cu" "In3.Cu" "In5.Cu" "In7.Cu" "In10.Cu")
		(net 1)
	)
	(via
		(at 113.25 151.7)
		(size 0.45)
		(drill 0.1)
		(layers "F.Cu" "B.Cu")
		(remove_unused_layers yes)
		(keep_end_layers yes)
		(zone_layer_connections "In1.Cu" "In3.Cu" "In5.Cu" "In7.Cu" "In10.Cu")
		(net 1)
	)
	(via
		(at 198.101 109.446)
		(size 0.45)
		(drill 0.1)
		(layers "F.Cu" "B.Cu")
		(remove_unused_layers yes)
		(keep_end_layers yes)
		(zone_layer_connections "In1.Cu" "In3.Cu" "In5.Cu" "In7.Cu" "In10.Cu")
		(net 1)
	)
	(via
		(at 262.449499 159.349)
		(size 0.45)
		(drill 0.1)
		(layers "F.Cu" "B.Cu")
		(remove_unused_layers yes)
		(keep_end_layers yes)
		(zone_layer_connections "In1.Cu" "In3.Cu" "In5.Cu" "In6.Cu" "In7.Cu" "In10.Cu")
		(net 1)
	)
	(via
		(at 142.6 145.95)
		(size 0.45)
		(drill 0.1)
		(layers "F.Cu" "B.Cu")
		(remove_unused_layers yes)
		(keep_end_layers yes)
		(zone_layer_connections "In1.Cu" "In3.Cu" "In5.Cu" "In7.Cu" "In10.Cu")
		(net 1)
	)
	(via
		(at 251.377998 129.769)
		(size 0.45)
		(drill 0.1)
		(layers "F.Cu" "B.Cu")
		(remove_unused_layers yes)
		(keep_end_layers yes)
		(zone_layer_connections "In1.Cu" "In3.Cu" "In5.Cu" "In7.Cu" "In10.Cu")
		(net 1)
	)
	(via
		(at 168.6455 101.1785)
		(size 0.45)
		(drill 0.1)
		(layers "F.Cu" "B.Cu")
		(remove_unused_layers yes)
		(keep_end_layers yes)
		(zone_layer_connections "In1.Cu" "In3.Cu" "In5.Cu" "In7.Cu" "In10.Cu")
		(net 1)
	)
	(via
		(at 105.824499 131.41)
		(size 0.45)
		(drill 0.1)
		(layers "F.Cu" "B.Cu")
		(remove_unused_layers yes)
		(keep_end_layers yes)
		(zone_layer_connections "In1.Cu" "In3.Cu" "In5.Cu" "In7.Cu" "In10.Cu")
		(net 1)
	)
	(via
		(at 210.735 186.685)
		(size 0.45)
		(drill 0.1)
		(layers "F.Cu" "B.Cu")
		(remove_unused_layers yes)
		(keep_end_layers yes)
		(zone_layer_connections "In1.Cu" "In3.Cu" "In5.Cu" "In7.Cu" "In10.Cu")
		(net 1)
	)
	(via
		(at 124.587 153.1112)
		(size 0.45)
		(drill 0.1)
		(layers "F.Cu" "B.Cu")
		(remove_unused_layers yes)
		(keep_end_layers yes)
		(zone_layer_connections "In1.Cu" "In3.Cu" "In5.Cu" "In7.Cu" "In10.Cu")
		(net 1)
	)
	(via
		(at 263.924499 120.839999)
		(size 0.45)
		(drill 0.1)
		(layers "F.Cu" "B.Cu")
		(remove_unused_layers yes)
		(keep_end_layers yes)
		(zone_layer_connections "In1.Cu" "In3.Cu" "In5.Cu" "In7.Cu" "In10.Cu")
		(net 1)
	)
	(via
		(at 202.95 189.46)
		(size 0.45)
		(drill 0.1)
		(layers "F.Cu" "B.Cu")
		(remove_unused_layers yes)
		(keep_end_layers yes)
		(zone_layer_connections "In1.Cu" "In3.Cu" "In5.Cu" "In7.Cu" "In10.Cu")
		(net 1)
	)
	(via
		(at 260.62 113.35)
		(size 0.45)
		(drill 0.1)
		(layers "F.Cu" "B.Cu")
		(remove_unused_layers yes)
		(keep_end_layers yes)
		(zone_layer_connections "In1.Cu" "In3.Cu" "In5.Cu" "In7.Cu" "In10.Cu")
		(net 1)
	)
	(via
		(at 111.111 175.7675)
		(size 0.45)
		(drill 0.1)
		(layers "F.Cu" "B.Cu")
		(remove_unused_layers yes)
		(keep_end_layers yes)
		(zone_layer_connections "In1.Cu" "In3.Cu" "In5.Cu" "In7.Cu" "In10.Cu")
		(net 1)
	)
	(via
		(at 166.73 162.87)
		(size 0.45)
		(drill 0.1)
		(layers "F.Cu" "B.Cu")
		(remove_unused_layers yes)
		(keep_end_layers yes)
		(zone_layer_connections "In1.Cu" "In3.Cu" "In5.Cu" "In7.Cu" "In10.Cu")
		(net 1)
	)
	(via
		(at 181.125 194.849501)
		(size 0.45)
		(drill 0.1)
		(layers "F.Cu" "B.Cu")
		(remove_unused_layers yes)
		(keep_end_layers yes)
		(zone_layer_connections "In1.Cu" "In3.Cu" "In5.Cu" "In7.Cu" "In10.Cu")
		(net 1)
	)
	(via
		(at 132.874499 145.399)
		(size 0.45)
		(drill 0.1)
		(layers "F.Cu" "B.Cu")
		(remove_unused_layers yes)
		(keep_end_layers yes)
		(zone_layer_connections "In1.Cu" "In3.Cu" "In5.Cu" "In7.Cu" "In10.Cu")
		(net 1)
	)
	(via
		(at 201.5 157.5)
		(size 0.45)
		(drill 0.1)
		(layers "F.Cu" "B.Cu")
		(remove_unused_layers yes)
		(keep_end_layers yes)
		(zone_layer_connections "In1.Cu" "In3.Cu" "In5.Cu" "In7.Cu" "In10.Cu")
		(net 1)
	)
	(via
		(at 175.5 149.5)
		(size 0.45)
		(drill 0.1)
		(layers "F.Cu" "B.Cu")
		(remove_unused_layers yes)
		(keep_end_layers yes)
		(zone_layer_connections "In1.Cu" "In3.Cu" "In5.Cu" "In7.Cu" "In10.Cu")
		(net 1)
	)
	(via
		(at 234.785 178.01)
		(size 0.45)
		(drill 0.1)
		(layers "F.Cu" "B.Cu")
		(remove_unused_layers yes)
		(keep_end_layers yes)
		(zone_layer_connections "In1.Cu" "In3.Cu" "In5.Cu" "In7.Cu" "In10.Cu")
		(net 1)
	)
	(via
		(at 189.5 158.5)
		(size 0.45)
		(drill 0.1)
		(layers "F.Cu" "B.Cu")
		(remove_unused_layers yes)
		(keep_end_layers yes)
		(zone_layer_connections "In1.Cu" "In3.Cu" "In5.Cu" "In7.Cu" "In10.Cu")
		(net 1)
	)
	(via
		(at 233.801 109.446)
		(size 0.45)
		(drill 0.1)
		(layers "F.Cu" "B.Cu")
		(remove_unused_layers yes)
		(keep_end_layers yes)
		(zone_layer_connections "In1.Cu" "In3.Cu" "In5.Cu" "In7.Cu" "In10.Cu")
		(net 1)
	)
	(via
		(at 191.5 156.5)
		(size 0.45)
		(drill 0.1)
		(layers "F.Cu" "B.Cu")
		(remove_unused_layers yes)
		(keep_end_layers yes)
		(zone_layer_connections "In1.Cu" "In3.Cu" "In5.Cu" "In7.Cu" "In10.Cu")
		(net 1)
	)
	(via
		(at 181.5 152.499683)
		(size 0.45)
		(drill 0.1)
		(layers "F.Cu" "B.Cu")
		(remove_unused_layers yes)
		(keep_end_layers yes)
		(zone_layer_connections "In1.Cu" "In3.Cu" "In5.Cu" "In7.Cu" "In10.Cu")
		(net 1)
	)
	(via
		(at 157.202276 155.073553)
		(size 0.45)
		(drill 0.1)
		(layers "F.Cu" "B.Cu")
		(remove_unused_layers yes)
		(keep_end_layers yes)
		(zone_layer_connections "In1.Cu" "In3.Cu" "In5.Cu" "In7.Cu" "In10.Cu")
		(net 1)
	)
	(via
		(at 111.111 180.2685)
		(size 0.45)
		(drill 0.1)
		(layers "F.Cu" "B.Cu")
		(remove_unused_layers yes)
		(keep_end_layers yes)
		(zone_layer_connections "In1.Cu" "In3.Cu" "In5.Cu" "In7.Cu" "In10.Cu")
		(net 1)
	)
	(via
		(at 169.175 194.849501)
		(size 0.45)
		(drill 0.1)
		(layers "F.Cu" "B.Cu")
		(remove_unused_layers yes)
		(keep_end_layers yes)
		(zone_layer_connections "In1.Cu" "In3.Cu" "In5.Cu" "In7.Cu" "In10.Cu")
		(net 1)
	)
	(via
		(at 187.175 194.849501)
		(size 0.45)
		(drill 0.1)
		(layers "F.Cu" "B.Cu")
		(remove_unused_layers yes)
		(keep_end_layers yes)
		(zone_layer_connections "In1.Cu" "In3.Cu" "In5.Cu" "In7.Cu" "In10.Cu")
		(net 1)
	)
	(via
		(at 122.75 181.303)
		(size 0.45)
		(drill 0.1)
		(layers "F.Cu" "B.Cu")
		(remove_unused_layers yes)
		(keep_end_layers yes)
		(zone_layer_connections "In1.Cu" "In3.Cu" "In5.Cu" "In7.Cu" "In10.Cu")
		(net 1)
	)
	(via
		(at 242.399499 168.24)
		(size 0.45)
		(drill 0.1)
		(layers "F.Cu" "B.Cu")
		(remove_unused_layers yes)
		(keep_end_layers yes)
		(zone_layer_connections "In1.Cu" "In3.Cu" "In5.Cu" "In7.Cu" "In10.Cu")
		(net 1)
	)
	(via
		(at 180.5 162.5)
		(size 0.45)
		(drill 0.1)
		(layers "F.Cu" "B.Cu")
		(remove_unused_layers yes)
		(keep_end_layers yes)
		(zone_layer_connections "In1.Cu" "In3.Cu" "In5.Cu" "In7.Cu" "In10.Cu")
		(net 1)
	)
	(via
		(at 175.5 139.5)
		(size 0.45)
		(drill 0.1)
		(layers "F.Cu" "B.Cu")
		(remove_unused_layers yes)
		(keep_end_layers yes)
		(zone_layer_connections "In1.Cu" "In3.Cu" "In5.Cu" "In7.Cu" "In10.Cu")
		(net 1)
	)
	(via
		(at 200.5 146.5)
		(size 0.45)
		(drill 0.1)
		(layers "F.Cu" "B.Cu")
		(remove_unused_layers yes)
		(keep_end_layers yes)
		(zone_layer_connections "In1.Cu" "In3.Cu" "In5.Cu" "In7.Cu" "In10.Cu")
		(net 1)
	)
	(via
		(at 233.898 100.510001)
		(size 0.45)
		(drill 0.1)
		(layers "F.Cu" "B.Cu")
		(remove_unused_layers yes)
		(keep_end_layers yes)
		(zone_layer_connections "In1.Cu" "In3.Cu" "In5.Cu" "In7.Cu" "In10.Cu")
		(net 1)
	)
	(via
		(at 227.25 186.9)
		(size 0.45)
		(drill 0.1)
		(layers "F.Cu" "B.Cu")
		(remove_unused_layers yes)
		(keep_end_layers yes)
		(zone_layer_connections "In1.Cu" "In3.Cu" "In5.Cu" "In7.Cu" "In10.Cu")
		(net 1)
	)
	(via
		(at 175.15 104.848)
		(size 0.45)
		(drill 0.1)
		(layers "F.Cu" "B.Cu")
		(remove_unused_layers yes)
		(keep_end_layers yes)
		(zone_layer_connections "In1.Cu" "In3.Cu" "In5.Cu" "In7.Cu" "In10.Cu")
		(net 1)
	)
	(via
		(at 241.695 123.905)
		(size 0.45)
		(drill 0.1)
		(layers "F.Cu" "B.Cu")
		(remove_unused_layers yes)
		(keep_end_layers yes)
		(zone_layer_connections "In1.Cu" "In3.Cu" "In5.Cu" "In7.Cu" "In10.Cu")
		(net 1)
	)
	(via
		(at 192.5 163.5)
		(size 0.45)
		(drill 0.1)
		(layers "F.Cu" "B.Cu")
		(remove_unused_layers yes)
		(keep_end_layers yes)
		(zone_layer_connections "In1.Cu" "In3.Cu" "In5.Cu" "In7.Cu" "In10.Cu")
		(net 1)
	)
	(via
		(at 108.797 163.868)
		(size 0.45)
		(drill 0.1)
		(layers "F.Cu" "B.Cu")
		(remove_unused_layers yes)
		(keep_end_layers yes)
		(zone_layer_connections "In1.Cu" "In3.Cu" "In5.Cu" "In7.Cu" "In10.Cu")
		(net 1)
	)
	(via
		(at 112.024499 141.249)
		(size 0.45)
		(drill 0.1)
		(layers "F.Cu" "B.Cu")
		(remove_unused_layers yes)
		(keep_end_layers yes)
		(zone_layer_connections "In1.Cu" "In3.Cu" "In5.Cu" "In7.Cu" "In10.Cu")
		(net 1)
	)
	(via
		(at 216.485 188.735)
		(size 0.45)
		(drill 0.1)
		(layers "F.Cu" "B.Cu")
		(remove_unused_layers yes)
		(keep_end_layers yes)
		(zone_layer_connections "In1.Cu" "In3.Cu" "In5.Cu" "In7.Cu" "In10.Cu")
		(net 1)
	)
	(via
		(at 105.824499 177.449)
		(size 0.45)
		(drill 0.1)
		(layers "F.Cu" "B.Cu")
		(remove_unused_layers yes)
		(keep_end_layers yes)
		(zone_layer_connections "In1.Cu" "In3.Cu" "In5.Cu" "In7.Cu" "In10.Cu")
		(net 1)
	)
	(via
		(at 193.5 145.5)
		(size 0.45)
		(drill 0.1)
		(layers "F.Cu" "B.Cu")
		(remove_unused_layers yes)
		(keep_end_layers yes)
		(zone_layer_connections "In1.Cu" "In3.Cu" "In5.Cu" "In7.Cu" "In10.Cu")
		(net 1)
	)
	(via
		(at 190.45 104.848)
		(size 0.45)
		(drill 0.1)
		(layers "F.Cu" "B.Cu")
		(remove_unused_layers yes)
		(keep_end_layers yes)
		(zone_layer_connections "In1.Cu" "In3.Cu" "In5.Cu" "In7.Cu" "In10.Cu")
		(net 1)
	)
	(via
		(at 117.34 167.22)
		(size 0.45)
		(drill 0.1)
		(layers "F.Cu" "B.Cu")
		(remove_unused_layers yes)
		(keep_end_layers yes)
		(zone_layer_connections "In1.Cu" "In3.Cu" "In5.Cu" "In7.Cu" "In10.Cu")
		(net 1)
	)
	(via
		(at 133.924499 145.399)
		(size 0.45)
		(drill 0.1)
		(layers "F.Cu" "B.Cu")
		(remove_unused_layers yes)
		(keep_end_layers yes)
		(zone_layer_connections "In1.Cu" "In3.Cu" "In5.Cu" "In7.Cu" "In10.Cu")
		(net 1)
	)
	(via
		(at 262.449499 176.349)
		(size 0.45)
		(drill 0.1)
		(layers "F.Cu" "B.Cu")
		(remove_unused_layers yes)
		(keep_end_layers yes)
		(zone_layer_connections "In1.Cu" "In3.Cu" "In5.Cu" "In6.Cu" "In7.Cu" "In10.Cu")
		(net 1)
	)
	(via
		(at 171.1505 104.1385)
		(size 0.45)
		(drill 0.1)
		(layers "F.Cu" "B.Cu")
		(remove_unused_layers yes)
		(keep_end_layers yes)
		(zone_layer_connections "In1.Cu" "In3.Cu" "In5.Cu" "In7.Cu" "In10.Cu")
		(net 1)
	)
	(via
		(at 181.5005 164.4995)
		(size 0.45)
		(drill 0.1)
		(layers "F.Cu" "B.Cu")
		(remove_unused_layers yes)
		(keep_end_layers yes)
		(zone_layer_connections "In1.Cu" "In3.Cu" "In5.Cu" "In7.Cu" "In10.Cu")
		(net 1)
	)
	(via
		(at 163.67 162.299999)
		(size 0.45)
		(drill 0.1)
		(layers "F.Cu" "B.Cu")
		(remove_unused_layers yes)
		(keep_end_layers yes)
		(zone_layer_connections "In1.Cu" "In3.Cu" "In5.Cu" "In7.Cu" "In10.Cu")
		(net 1)
	)
	(via
		(at 225.475 185.57)
		(size 0.45)
		(drill 0.1)
		(layers "F.Cu" "B.Cu")
		(remove_unused_layers yes)
		(keep_end_layers yes)
		(zone_layer_connections "In1.Cu" "In3.Cu" "In5.Cu" "In7.Cu" "In10.Cu")
		(net 1)
	)
	(via
		(at 128.389 127.978)
		(size 0.45)
		(drill 0.1)
		(layers "F.Cu" "B.Cu")
		(remove_unused_layers yes)
		(keep_end_layers yes)
		(zone_layer_connections "In1.Cu" "In3.Cu" "In5.Cu" "In7.Cu" "In9.Cu" "In10.Cu")
		(net 1)
	)
	(via
		(at 219.55 157.025)
		(size 0.45)
		(drill 0.1)
		(layers "F.Cu" "B.Cu")
		(remove_unused_layers yes)
		(keep_end_layers yes)
		(zone_layer_connections "In1.Cu" "In3.Cu" "In5.Cu" "In7.Cu" "In10.Cu")
		(net 1)
	)
	(via
		(at 197.5005 165.4995)
		(size 0.45)
		(drill 0.1)
		(layers "F.Cu" "B.Cu")
		(remove_unused_layers yes)
		(keep_end_layers yes)
		(zone_layer_connections "In1.Cu" "In3.Cu" "In5.Cu" "In7.Cu" "In10.Cu")
		(net 1)
	)
	(via
		(at 196.5 163.5)
		(size 0.45)
		(drill 0.1)
		(layers "F.Cu" "B.Cu")
		(remove_unused_layers yes)
		(keep_end_layers yes)
		(zone_layer_connections "In1.Cu" "In3.Cu" "In5.Cu" "In7.Cu" "In10.Cu")
		(net 1)
	)
	(via
		(at 130.951 109.446)
		(size 0.45)
		(drill 0.1)
		(layers "F.Cu" "B.Cu")
		(remove_unused_layers yes)
		(keep_end_layers yes)
		(zone_layer_connections "In1.Cu" "In3.Cu" "In5.Cu" "In7.Cu" "In10.Cu")
		(net 1)
	)
	(via
		(at 212.635 169.36)
		(size 0.45)
		(drill 0.1)
		(layers "F.Cu" "B.Cu")
		(remove_unused_layers yes)
		(keep_end_layers yes)
		(zone_layer_connections "In1.Cu" "In3.Cu" "In5.Cu" "In7.Cu" "In10.Cu")
		(net 1)
	)
	(via
		(at 257.37 113.395)
		(size 0.45)
		(drill 0.1)
		(layers "F.Cu" "B.Cu")
		(remove_unused_layers yes)
		(keep_end_layers yes)
		(zone_layer_connections "In1.Cu" "In3.Cu" "In5.Cu" "In7.Cu" "In10.Cu")
		(net 1)
	)
	(via
		(at 161.551 104.848)
		(size 0.45)
		(drill 0.1)
		(layers "F.Cu" "B.Cu")
		(remove_unused_layers yes)
		(keep_end_layers yes)
		(zone_layer_connections "In1.Cu" "In3.Cu" "In5.Cu" "In7.Cu" "In10.Cu")
		(net 1)
	)
	(via
		(at 213.525 156.05)
		(size 0.45)
		(drill 0.1)
		(layers "F.Cu" "B.Cu")
		(remove_unused_layers yes)
		(keep_end_layers yes)
		(zone_layer_connections "In1.Cu" "In3.Cu" "In5.Cu" "In7.Cu" "In10.Cu")
		(net 1)
	)
	(via
		(at 234.05 172.75)
		(size 0.45)
		(drill 0.1)
		(layers "F.Cu" "B.Cu")
		(remove_unused_layers yes)
		(keep_end_layers yes)
		(zone_layer_connections "In1.Cu" "In3.Cu" "In5.Cu" "In7.Cu" "In10.Cu")
		(net 1)
	)
	(via
		(at 140.227656 139.242165)
		(size 0.45)
		(drill 0.1)
		(layers "F.Cu" "B.Cu")
		(remove_unused_layers yes)
		(keep_end_layers yes)
		(zone_layer_connections "In1.Cu" "In3.Cu" "In5.Cu" "In7.Cu" "In10.Cu")
		(net 1)
	)
	(via
		(at 253.975 127.55)
		(size 0.45)
		(drill 0.1)
		(layers "F.Cu" "B.Cu")
		(remove_unused_layers yes)
		(keep_end_layers yes)
		(zone_layer_connections "In1.Cu" "In3.Cu" "In5.Cu" "In7.Cu" "In10.Cu")
		(net 1)
	)
	(via
		(at 129.8296 102.638)
		(size 0.45)
		(drill 0.1)
		(layers "F.Cu" "B.Cu")
		(remove_unused_layers yes)
		(keep_end_layers yes)
		(zone_layer_connections "In1.Cu" "In3.Cu" "In5.Cu" "In7.Cu" "In10.Cu")
		(net 1)
	)
	(via
		(at 225.635 176.91)
		(size 0.45)
		(drill 0.1)
		(layers "F.Cu" "B.Cu")
		(remove_unused_layers yes)
		(keep_end_layers yes)
		(zone_layer_connections "In1.Cu" "In3.Cu" "In5.Cu" "In7.Cu" "In10.Cu")
		(net 1)
	)
	(via
		(at 256.5055 173.622)
		(size 0.45)
		(drill 0.1)
		(layers "F.Cu" "B.Cu")
		(remove_unused_layers yes)
		(keep_end_layers yes)
		(zone_layer_connections "In1.Cu" "In2.Cu" "In3.Cu" "In4.Cu" "In5.Cu" "In6.Cu"
			"In7.Cu" "In10.Cu"
		)
		(net 1)
	)
	(via
		(at 254.374499 181.449)
		(size 0.45)
		(drill 0.1)
		(layers "F.Cu" "B.Cu")
		(remove_unused_layers yes)
		(keep_end_layers yes)
		(zone_layer_connections "In1.Cu" "In3.Cu" "In5.Cu" "In6.Cu" "In7.Cu" "In10.Cu")
		(net 1)
	)
	(via
		(at 244.85 109.446)
		(size 0.45)
		(drill 0.1)
		(layers "F.Cu" "B.Cu")
		(remove_unused_layers yes)
		(keep_end_layers yes)
		(zone_layer_connections "In1.Cu" "In3.Cu" "In5.Cu" "In7.Cu" "In10.Cu")
		(net 1)
	)
	(via
		(at 224.685 175.835)
		(size 0.45)
		(drill 0.1)
		(layers "F.Cu" "B.Cu")
		(remove_unused_layers yes)
		(keep_end_layers yes)
		(zone_layer_connections "In1.Cu" "In3.Cu" "In5.Cu" "In7.Cu" "In10.Cu")
		(net 1)
	)
	(via
		(at 240.765 129.355)
		(size 0.45)
		(drill 0.1)
		(layers "F.Cu" "B.Cu")
		(remove_unused_layers yes)
		(keep_end_layers yes)
		(zone_layer_connections "In1.Cu" "In3.Cu" "In5.Cu" "In7.Cu" "In10.Cu")
		(net 1)
	)
	(via
		(at 110.09 146.97)
		(size 0.45)
		(drill 0.1)
		(layers "F.Cu" "B.Cu")
		(remove_unused_layers yes)
		(keep_end_layers yes)
		(zone_layer_connections "In1.Cu" "In3.Cu" "In5.Cu" "In7.Cu" "In10.Cu")
		(net 1)
	)
	(via
		(at 203.55 135.2)
		(size 0.45)
		(drill 0.1)
		(layers "F.Cu" "B.Cu")
		(net 1)
	)
	(via
		(at 214.185 186.635)
		(size 0.45)
		(drill 0.1)
		(layers "F.Cu" "B.Cu")
		(remove_unused_layers yes)
		(keep_end_layers yes)
		(zone_layer_connections "In1.Cu" "In3.Cu" "In5.Cu" "In7.Cu" "In10.Cu")
		(net 1)
	)
	(via
		(at 136.8 154.9)
		(size 0.45)
		(drill 0.1)
		(layers "F.Cu" "B.Cu")
		(remove_unused_layers yes)
		(keep_end_layers yes)
		(zone_layer_connections "In1.Cu" "In3.Cu" "In5.Cu" "In7.Cu" "In10.Cu")
		(net 1)
	)
	(via
		(at 134.124499 158.749)
		(size 0.45)
		(drill 0.1)
		(layers "F.Cu" "B.Cu")
		(remove_unused_layers yes)
		(keep_end_layers yes)
		(zone_layer_connections "In1.Cu" "In3.Cu" "In5.Cu" "In7.Cu" "In10.Cu")
		(net 1)
	)
	(via
		(at 196.5 158.5)
		(size 0.45)
		(drill 0.1)
		(layers "F.Cu" "B.Cu")
		(remove_unused_layers yes)
		(keep_end_layers yes)
		(zone_layer_connections "In1.Cu" "In3.Cu" "In5.Cu" "In7.Cu" "In10.Cu")
		(net 1)
	)
	(via
		(at 193.5 156.5)
		(size 0.45)
		(drill 0.1)
		(layers "F.Cu" "B.Cu")
		(remove_unused_layers yes)
		(keep_end_layers yes)
		(zone_layer_connections "In1.Cu" "In3.Cu" "In5.Cu" "In7.Cu" "In10.Cu")
		(net 1)
	)
	(via
		(at 257.094999 153.9005)
		(size 0.45)
		(drill 0.1)
		(layers "F.Cu" "B.Cu")
		(remove_unused_layers yes)
		(keep_end_layers yes)
		(zone_layer_connections "In1.Cu" "In2.Cu" "In3.Cu" "In4.Cu" "In5.Cu" "In6.Cu"
			"In7.Cu" "In10.Cu"
		)
		(net 1)
	)
	(via
		(at 175.5 155.5)
		(size 0.45)
		(drill 0.1)
		(layers "F.Cu" "B.Cu")
		(remove_unused_layers yes)
		(keep_end_layers yes)
		(zone_layer_connections "In1.Cu" "In3.Cu" "In5.Cu" "In7.Cu" "In10.Cu")
		(net 1)
	)
	(via
		(at 152.201 104.848)
		(size 0.45)
		(drill 0.1)
		(layers "F.Cu" "B.Cu")
		(remove_unused_layers yes)
		(keep_end_layers yes)
		(zone_layer_connections "In1.Cu" "In3.Cu" "In5.Cu" "In7.Cu" "In10.Cu")
		(net 1)
	)
	(via
		(at 193.5005 164.4995)
		(size 0.45)
		(drill 0.1)
		(layers "F.Cu" "B.Cu")
		(remove_unused_layers yes)
		(keep_end_layers yes)
		(zone_layer_connections "In1.Cu" "In3.Cu" "In5.Cu" "In7.Cu" "In10.Cu")
		(net 1)
	)
	(via
		(at 221.901 109.446)
		(size 0.45)
		(drill 0.1)
		(layers "F.Cu" "B.Cu")
		(remove_unused_layers yes)
		(keep_end_layers yes)
		(zone_layer_connections "In1.Cu" "In3.Cu" "In5.Cu" "In7.Cu" "In10.Cu")
		(net 1)
	)
	(via
		(at 263.924499 104.839999)
		(size 0.45)
		(drill 0.1)
		(layers "F.Cu" "B.Cu")
		(remove_unused_layers yes)
		(keep_end_layers yes)
		(zone_layer_connections "In1.Cu" "In3.Cu" "In5.Cu" "In7.Cu" "In10.Cu")
		(net 1)
	)
	(via
		(at 229.31 184.185)
		(size 0.45)
		(drill 0.1)
		(layers "F.Cu" "B.Cu")
		(remove_unused_layers yes)
		(keep_end_layers yes)
		(zone_layer_connections "In1.Cu" "In3.Cu" "In5.Cu" "In7.Cu" "In10.Cu")
		(net 1)
	)
	(via
		(at 234.035 174.71)
		(size 0.45)
		(drill 0.1)
		(layers "F.Cu" "B.Cu")
		(remove_unused_layers yes)
		(keep_end_layers yes)
		(zone_layer_connections "In1.Cu" "In3.Cu" "In5.Cu" "In7.Cu" "In10.Cu")
		(net 1)
	)
	(via
		(at 201.501 109.446)
		(size 0.45)
		(drill 0.1)
		(layers "F.Cu" "B.Cu")
		(remove_unused_layers yes)
		(keep_end_layers yes)
		(zone_layer_connections "In1.Cu" "In3.Cu" "In5.Cu" "In7.Cu" "In10.Cu")
		(net 1)
	)
	(via
		(at 175.5 144.5)
		(size 0.45)
		(drill 0.1)
		(layers "F.Cu" "B.Cu")
		(remove_unused_layers yes)
		(keep_end_layers yes)
		(zone_layer_connections "In1.Cu" "In3.Cu" "In5.Cu" "In7.Cu" "In10.Cu")
		(net 1)
	)
	(via
		(at 146.45 160.834)
		(size 0.45)
		(drill 0.1)
		(layers "F.Cu" "B.Cu")
		(remove_unused_layers yes)
		(keep_end_layers yes)
		(zone_layer_connections "In1.Cu" "In3.Cu" "In5.Cu" "In7.Cu" "In10.Cu")
		(net 1)
	)
	(via
		(at 213.8 185.5)
		(size 0.45)
		(drill 0.1)
		(layers "F.Cu" "B.Cu")
		(remove_unused_layers yes)
		(keep_end_layers yes)
		(zone_layer_connections "In1.Cu" "In3.Cu" "In5.Cu" "In7.Cu" "In10.Cu")
		(net 1)
	)
	(via
		(at 239.31 189.46)
		(size 0.45)
		(drill 0.1)
		(layers "F.Cu" "B.Cu")
		(remove_unused_layers yes)
		(keep_end_layers yes)
		(zone_layer_connections "In1.Cu" "In3.Cu" "In5.Cu" "In7.Cu" "In10.Cu")
		(net 1)
	)
	(via
		(at 190.5 141.5)
		(size 0.45)
		(drill 0.1)
		(layers "F.Cu" "B.Cu")
		(remove_unused_layers yes)
		(keep_end_layers yes)
		(zone_layer_connections "In1.Cu" "In3.Cu" "In5.Cu" "In7.Cu" "In10.Cu")
		(net 1)
	)
	(via
		(at 219.45 156)
		(size 0.45)
		(drill 0.1)
		(layers "F.Cu" "B.Cu")
		(remove_unused_layers yes)
		(keep_end_layers yes)
		(zone_layer_connections "In1.Cu" "In3.Cu" "In5.Cu" "In7.Cu" "In10.Cu")
		(net 1)
	)
	(via
		(at 254.65 168.6)
		(size 0.45)
		(drill 0.1)
		(layers "F.Cu" "B.Cu")
		(remove_unused_layers yes)
		(keep_end_layers yes)
		(zone_layer_connections "In1.Cu" "In3.Cu" "In4.Cu" "In5.Cu" "In6.Cu" "In7.Cu"
			"In10.Cu"
		)
		(net 1)
	)
	(via
		(at 257.094999 156.7005)
		(size 0.45)
		(drill 0.1)
		(layers "F.Cu" "B.Cu")
		(remove_unused_layers yes)
		(keep_end_layers yes)
		(zone_layer_connections "In1.Cu" "In2.Cu" "In3.Cu" "In4.Cu" "In5.Cu" "In6.Cu"
			"In7.Cu" "In10.Cu"
		)
		(net 1)
	)
	(via
		(at 224.685 181.235)
		(size 0.45)
		(drill 0.1)
		(layers "F.Cu" "B.Cu")
		(remove_unused_layers yes)
		(keep_end_layers yes)
		(zone_layer_connections "In1.Cu" "In3.Cu" "In5.Cu" "In7.Cu" "In10.Cu")
		(net 1)
	)
	(via
		(at 130.215 137.025)
		(size 0.45)
		(drill 0.1)
		(layers "F.Cu" "B.Cu")
		(remove_unused_layers yes)
		(keep_end_layers yes)
		(zone_layer_connections "In1.Cu" "In3.Cu" "In5.Cu" "In7.Cu" "In10.Cu")
		(net 1)
	)
	(via
		(at 223.8 179.075)
		(size 0.45)
		(drill 0.1)
		(layers "F.Cu" "B.Cu")
		(remove_unused_layers yes)
		(keep_end_layers yes)
		(zone_layer_connections "In1.Cu" "In3.Cu" "In5.Cu" "In7.Cu" "In10.Cu")
		(net 1)
	)
	(via
		(at 251.074499 177.674)
		(size 0.45)
		(drill 0.1)
		(layers "F.Cu" "B.Cu")
		(remove_unused_layers yes)
		(keep_end_layers yes)
		(zone_layer_connections "In1.Cu" "In2.Cu" "In3.Cu" "In5.Cu" "In6.Cu" "In7.Cu"
			"In10.Cu"
		)
		(net 1)
	)
	(via
		(at 211.285 185.585)
		(size 0.45)
		(drill 0.1)
		(layers "F.Cu" "B.Cu")
		(remove_unused_layers yes)
		(keep_end_layers yes)
		(zone_layer_connections "In1.Cu" "In3.Cu" "In5.Cu" "In7.Cu" "In10.Cu")
		(net 1)
	)
	(via
		(at 216.91 185.51)
		(size 0.45)
		(drill 0.1)
		(layers "F.Cu" "B.Cu")
		(remove_unused_layers yes)
		(keep_end_layers yes)
		(zone_layer_connections "In1.Cu" "In3.Cu" "In5.Cu" "In7.Cu" "In10.Cu")
		(net 1)
	)
	(via
		(at 176.5 142.500001)
		(size 0.45)
		(drill 0.1)
		(layers "F.Cu" "B.Cu")
		(remove_unused_layers yes)
		(keep_end_layers yes)
		(zone_layer_connections "In1.Cu" "In3.Cu" "In5.Cu" "In7.Cu" "In10.Cu")
		(net 1)
	)
	(via
		(at 237.129499 183.512)
		(size 0.45)
		(drill 0.1)
		(layers "F.Cu" "B.Cu")
		(remove_unused_layers yes)
		(keep_end_layers yes)
		(zone_layer_connections "In1.Cu" "In3.Cu" "In5.Cu" "In7.Cu" "In10.Cu")
		(net 1)
	)
	(via
		(at 205.19 102.73)
		(size 0.45)
		(drill 0.1)
		(layers "F.Cu" "B.Cu")
		(remove_unused_layers yes)
		(keep_end_layers yes)
		(zone_layer_connections "In1.Cu" "In3.Cu" "In5.Cu" "In7.Cu" "In10.Cu")
		(net 1)
	)
	(via
		(at 136.024499 137.999)
		(size 0.45)
		(drill 0.1)
		(layers "F.Cu" "B.Cu")
		(remove_unused_layers yes)
		(keep_end_layers yes)
		(zone_layer_connections "In1.Cu" "In3.Cu" "In5.Cu" "In7.Cu" "In10.Cu")
		(net 1)
	)
	(via
		(at 251.09 187.404)
		(size 0.45)
		(drill 0.1)
		(layers "F.Cu" "B.Cu")
		(remove_unused_layers yes)
		(keep_end_layers yes)
		(zone_layer_connections "In1.Cu" "In3.Cu" "In5.Cu" "In7.Cu" "In10.Cu")
		(net 1)
	)
	(via
		(at 139.024499 188.649)
		(size 0.45)
		(drill 0.1)
		(layers "F.Cu" "B.Cu")
		(remove_unused_layers yes)
		(keep_end_layers yes)
		(zone_layer_connections "In1.Cu" "In3.Cu" "In5.Cu" "In7.Cu" "In10.Cu")
		(net 1)
	)
	(via
		(at 163.251 104.848)
		(size 0.45)
		(drill 0.1)
		(layers "F.Cu" "B.Cu")
		(remove_unused_layers yes)
		(keep_end_layers yes)
		(zone_layer_connections "In1.Cu" "In3.Cu" "In5.Cu" "In7.Cu" "In10.Cu")
		(net 1)
	)
	(via
		(at 224.2 158.1)
		(size 0.45)
		(drill 0.1)
		(layers "F.Cu" "B.Cu")
		(remove_unused_layers yes)
		(keep_end_layers yes)
		(zone_layer_connections "In1.Cu" "In3.Cu" "In5.Cu" "In7.Cu" "In10.Cu")
		(net 1)
	)
	(via
		(at 107.024499 188.649)
		(size 0.45)
		(drill 0.1)
		(layers "F.Cu" "B.Cu")
		(remove_unused_layers yes)
		(keep_end_layers yes)
		(zone_layer_connections "In1.Cu" "In3.Cu" "In5.Cu" "In7.Cu" "In10.Cu")
		(net 1)
	)
	(via
		(at 136.624499 186.349)
		(size 0.45)
		(drill 0.1)
		(layers "F.Cu" "B.Cu")
		(remove_unused_layers yes)
		(keep_end_layers yes)
		(zone_layer_connections "In1.Cu" "In3.Cu" "In5.Cu" "In7.Cu" "In10.Cu")
		(net 1)
	)
	(via
		(at 215.35 102.73)
		(size 0.45)
		(drill 0.1)
		(layers "F.Cu" "B.Cu")
		(remove_unused_layers yes)
		(keep_end_layers yes)
		(zone_layer_connections "In1.Cu" "In3.Cu" "In5.Cu" "In7.Cu" "In10.Cu")
		(net 1)
	)
	(via
		(at 191.5005 164.4995)
		(size 0.45)
		(drill 0.1)
		(layers "F.Cu" "B.Cu")
		(remove_unused_layers yes)
		(keep_end_layers yes)
		(zone_layer_connections "In1.Cu" "In3.Cu" "In5.Cu" "In7.Cu" "In10.Cu")
		(net 1)
	)
	(via
		(at 150.854499 194.749501)
		(size 0.45)
		(drill 0.1)
		(layers "F.Cu" "B.Cu")
		(remove_unused_layers yes)
		(keep_end_layers yes)
		(zone_layer_connections "In1.Cu" "In3.Cu" "In5.Cu" "In7.Cu" "In10.Cu")
		(net 1)
	)
	(via
		(at 122.646 101.159)
		(size 0.45)
		(drill 0.1)
		(layers "F.Cu" "B.Cu")
		(remove_unused_layers yes)
		(keep_end_layers yes)
		(zone_layer_connections "In1.Cu" "In3.Cu" "In5.Cu" "In7.Cu" "In10.Cu")
		(net 1)
	)
	(via
		(at 195.1975 194.849501)
		(size 0.45)
		(drill 0.1)
		(layers "F.Cu" "B.Cu")
		(remove_unused_layers yes)
		(keep_end_layers yes)
		(zone_layer_connections "In1.Cu" "In3.Cu" "In5.Cu" "In7.Cu" "In10.Cu")
		(net 1)
	)
	(via
		(at 229.222 140.852)
		(size 0.45)
		(drill 0.1)
		(layers "F.Cu" "B.Cu")
		(remove_unused_layers yes)
		(keep_end_layers yes)
		(zone_layer_connections "In1.Cu" "In3.Cu" "In5.Cu" "In7.Cu" "In10.Cu")
		(net 1)
	)
	(via
		(at 193 109.446)
		(size 0.45)
		(drill 0.1)
		(layers "F.Cu" "B.Cu")
		(remove_unused_layers yes)
		(keep_end_layers yes)
		(zone_layer_connections "In1.Cu" "In3.Cu" "In5.Cu" "In7.Cu" "In10.Cu")
		(net 1)
	)
	(via
		(at 256.024499 159.449)
		(size 0.45)
		(drill 0.1)
		(layers "F.Cu" "B.Cu")
		(remove_unused_layers yes)
		(keep_end_layers yes)
		(zone_layer_connections "In1.Cu" "In3.Cu" "In4.Cu" "In5.Cu" "In6.Cu" "In7.Cu"
			"In10.Cu"
		)
		(net 1)
	)
	(via
		(at 187.500001 145.5)
		(size 0.45)
		(drill 0.1)
		(layers "F.Cu" "B.Cu")
		(remove_unused_layers yes)
		(keep_end_layers yes)
		(zone_layer_connections "In1.Cu" "In3.Cu" "In5.Cu" "In7.Cu" "In10.Cu")
		(net 1)
	)
	(via
		(at 189.5 156.5)
		(size 0.45)
		(drill 0.1)
		(layers "F.Cu" "B.Cu")
		(remove_unused_layers yes)
		(keep_end_layers yes)
		(zone_layer_connections "In1.Cu" "In3.Cu" "In5.Cu" "In7.Cu" "In10.Cu")
		(net 1)
	)
	(via
		(at 182.5 145.5)
		(size 0.45)
		(drill 0.1)
		(layers "F.Cu" "B.Cu")
		(remove_unused_layers yes)
		(keep_end_layers yes)
		(zone_layer_connections "In1.Cu" "In3.Cu" "In5.Cu" "In7.Cu" "In10.Cu")
		(net 1)
	)
	(via
		(at 193.5 158.5)
		(size 0.45)
		(drill 0.1)
		(layers "F.Cu" "B.Cu")
		(remove_unused_layers yes)
		(keep_end_layers yes)
		(zone_layer_connections "In1.Cu" "In3.Cu" "In5.Cu" "In7.Cu" "In10.Cu")
		(net 1)
	)
	(via
		(at 155.584499 188.474)
		(size 0.45)
		(drill 0.1)
		(layers "F.Cu" "B.Cu")
		(remove_unused_layers yes)
		(keep_end_layers yes)
		(zone_layer_connections "In1.Cu" "In3.Cu" "In5.Cu" "In7.Cu" "In10.Cu")
		(net 1)
	)
	(via
		(at 209.9 158.2)
		(size 0.45)
		(drill 0.1)
		(layers "F.Cu" "B.Cu")
		(remove_unused_layers yes)
		(keep_end_layers yes)
		(zone_layer_connections "In1.Cu" "In3.Cu" "In5.Cu" "In7.Cu" "In10.Cu")
		(net 1)
	)
	(via
		(at 173.1995 194.849501)
		(size 0.45)
		(drill 0.1)
		(layers "F.Cu" "B.Cu")
		(remove_unused_layers yes)
		(keep_end_layers yes)
		(zone_layer_connections "In1.Cu" "In3.Cu" "In5.Cu" "In7.Cu" "In10.Cu")
		(net 1)
	)
	(via
		(at 124.326 181.303)
		(size 0.45)
		(drill 0.1)
		(layers "F.Cu" "B.Cu")
		(remove_unused_layers yes)
		(keep_end_layers yes)
		(zone_layer_connections "In1.Cu" "In3.Cu" "In5.Cu" "In7.Cu" "In10.Cu")
		(net 1)
	)
	(via
		(at 116.435 105.5)
		(size 0.45)
		(drill 0.1)
		(layers "F.Cu" "B.Cu")
		(remove_unused_layers yes)
		(keep_end_layers yes)
		(zone_layer_connections "In1.Cu" "In3.Cu" "In5.Cu" "In7.Cu" "In10.Cu")
		(net 1)
	)
	(via
		(at 178.5 161.5)
		(size 0.45)
		(drill 0.1)
		(layers "F.Cu" "B.Cu")
		(remove_unused_layers yes)
		(keep_end_layers yes)
		(zone_layer_connections "In1.Cu" "In3.Cu" "In5.Cu" "In7.Cu" "In10.Cu")
		(net 1)
	)
	(via
		(at 254.65 115.385)
		(size 0.45)
		(drill 0.1)
		(layers "F.Cu" "B.Cu")
		(remove_unused_layers yes)
		(keep_end_layers yes)
		(zone_layer_connections "In1.Cu" "In3.Cu" "In5.Cu" "In7.Cu" "In10.Cu")
		(net 1)
	)
	(via
		(at 237.414665 130.464166)
		(size 0.45)
		(drill 0.1)
		(layers "F.Cu" "B.Cu")
		(remove_unused_layers yes)
		(keep_end_layers yes)
		(zone_layer_connections "In1.Cu" "In3.Cu" "In5.Cu" "In7.Cu" "In10.Cu")
		(net 1)
	)
	(via
		(at 190.5 146.5)
		(size 0.45)
		(drill 0.1)
		(layers "F.Cu" "B.Cu")
		(remove_unused_layers yes)
		(keep_end_layers yes)
		(zone_layer_connections "In1.Cu" "In3.Cu" "In5.Cu" "In7.Cu" "In10.Cu")
		(net 1)
	)
	(via
		(at 131.65 179.5785)
		(size 0.45)
		(drill 0.1)
		(layers "F.Cu" "B.Cu")
		(remove_unused_layers yes)
		(keep_end_layers yes)
		(zone_layer_connections "In1.Cu" "In3.Cu" "In5.Cu" "In7.Cu" "In10.Cu")
		(net 1)
	)
	(via
		(at 197.5 162.5)
		(size 0.45)
		(drill 0.1)
		(layers "F.Cu" "B.Cu")
		(remove_unused_layers yes)
		(keep_end_layers yes)
		(zone_layer_connections "In1.Cu" "In3.Cu" "In5.Cu" "In7.Cu" "In10.Cu")
		(net 1)
	)
	(via
		(at 154.7 186.65)
		(size 0.45)
		(drill 0.1)
		(layers "F.Cu" "B.Cu")
		(remove_unused_layers yes)
		(keep_end_layers yes)
		(zone_layer_connections "In1.Cu" "In3.Cu" "In5.Cu" "In7.Cu" "In10.Cu")
		(net 1)
	)
	(via
		(at 141.425499 167.649)
		(size 0.45)
		(drill 0.1)
		(layers "F.Cu" "B.Cu")
		(remove_unused_layers yes)
		(keep_end_layers yes)
		(zone_layer_connections "In1.Cu" "In3.Cu" "In5.Cu" "In7.Cu" "In10.Cu")
		(net 1)
	)
	(via
		(at 184.5 163.5)
		(size 0.45)
		(drill 0.1)
		(layers "F.Cu" "B.Cu")
		(remove_unused_layers yes)
		(keep_end_layers yes)
		(zone_layer_connections "In1.Cu" "In3.Cu" "In5.Cu" "In7.Cu" "In10.Cu")
		(net 1)
	)
	(via
		(at 126.224499 188.649)
		(size 0.45)
		(drill 0.1)
		(layers "F.Cu" "B.Cu")
		(remove_unused_layers yes)
		(keep_end_layers yes)
		(zone_layer_connections "In1.Cu" "In3.Cu" "In5.Cu" "In7.Cu" "In10.Cu")
		(net 1)
	)
	(via
		(at 140.249499 168.631)
		(size 0.45)
		(drill 0.1)
		(layers "F.Cu" "B.Cu")
		(remove_unused_layers yes)
		(keep_end_layers yes)
		(zone_layer_connections "In1.Cu" "In3.Cu" "In5.Cu" "In7.Cu" "In10.Cu")
		(net 1)
	)
	(via
		(at 241.9 118)
		(size 0.45)
		(drill 0.1)
		(layers "F.Cu" "B.Cu")
		(remove_unused_layers yes)
		(keep_end_layers yes)
		(zone_layer_connections "In1.Cu" "In3.Cu" "In5.Cu" "In7.Cu" "In10.Cu")
		(net 1)
	)
	(via
		(at 133.41 180.1985)
		(size 0.45)
		(drill 0.1)
		(layers "F.Cu" "B.Cu")
		(remove_unused_layers yes)
		(keep_end_layers yes)
		(zone_layer_connections "In1.Cu" "In3.Cu" "In5.Cu" "In7.Cu" "In10.Cu")
		(net 1)
	)
	(via
		(at 122.076 174.922)
		(size 0.45)
		(drill 0.1)
		(layers "F.Cu" "B.Cu")
		(remove_unused_layers yes)
		(keep_end_layers yes)
		(zone_layer_connections "In1.Cu" "In3.Cu" "In5.Cu" "In7.Cu" "In10.Cu")
		(net 1)
	)
	(via
		(at 136.945 164.084)
		(size 0.45)
		(drill 0.1)
		(layers "F.Cu" "B.Cu")
		(remove_unused_layers yes)
		(keep_end_layers yes)
		(zone_layer_connections "In1.Cu" "In3.Cu" "In5.Cu" "In7.Cu" "In10.Cu")
		(net 1)
	)
	(via
		(at 262.697999 100.510001)
		(size 0.45)
		(drill 0.1)
		(layers "F.Cu" "B.Cu")
		(remove_unused_layers yes)
		(keep_end_layers yes)
		(zone_layer_connections "In1.Cu" "In3.Cu" "In5.Cu" "In7.Cu" "In10.Cu")
		(net 1)
	)
	(via
		(at 188 165.575)
		(size 0.45)
		(drill 0.1)
		(layers "F.Cu" "B.Cu")
		(remove_unused_layers yes)
		(keep_end_layers yes)
		(zone_layer_connections "In1.Cu" "In3.Cu" "In5.Cu" "In7.Cu" "In10.Cu")
		(net 1)
	)
	(via
		(at 214.535 170.535)
		(size 0.45)
		(drill 0.1)
		(layers "F.Cu" "B.Cu")
		(remove_unused_layers yes)
		(keep_end_layers yes)
		(zone_layer_connections "In1.Cu" "In3.Cu" "In5.Cu" "In7.Cu" "In10.Cu")
		(net 1)
	)
	(via
		(at 149.046843 161.581328)
		(size 0.45)
		(drill 0.1)
		(layers "F.Cu" "B.Cu")
		(remove_unused_layers yes)
		(keep_end_layers yes)
		(zone_layer_connections "In1.Cu" "In3.Cu" "In5.Cu" "In7.Cu" "In10.Cu")
		(net 1)
	)
	(via
		(at 170.051 109.446)
		(size 0.45)
		(drill 0.1)
		(layers "F.Cu" "B.Cu")
		(remove_unused_layers yes)
		(keep_end_layers yes)
		(zone_layer_connections "In1.Cu" "In3.Cu" "In5.Cu" "In7.Cu" "In10.Cu")
		(net 1)
	)
	(via
		(at 125.16 104.11)
		(size 0.45)
		(drill 0.1)
		(layers "F.Cu" "B.Cu")
		(remove_unused_layers yes)
		(keep_end_layers yes)
		(zone_layer_connections "In1.Cu" "In3.Cu" "In5.Cu" "In7.Cu" "In10.Cu")
		(net 1)
	)
	(via
		(at 127.661328 139.882157)
		(size 0.45)
		(drill 0.1)
		(layers "F.Cu" "B.Cu")
		(remove_unused_layers yes)
		(keep_end_layers yes)
		(zone_layer_connections "In1.Cu" "In3.Cu" "In5.Cu" "In7.Cu" "In10.Cu")
		(net 1)
	)
	(via
		(at 176.5 147.499999)
		(size 0.45)
		(drill 0.1)
		(layers "F.Cu" "B.Cu")
		(remove_unused_layers yes)
		(keep_end_layers yes)
		(zone_layer_connections "In1.Cu" "In3.Cu" "In5.Cu" "In7.Cu" "In10.Cu")
		(net 1)
	)
	(via
		(at 199.4995 161.4995)
		(size 0.45)
		(drill 0.1)
		(layers "F.Cu" "B.Cu")
		(remove_unused_layers yes)
		(keep_end_layers yes)
		(zone_layer_connections "In1.Cu" "In3.Cu" "In5.Cu" "In7.Cu" "In10.Cu")
		(net 1)
	)
	(via
		(at 140.302 109.446)
		(size 0.45)
		(drill 0.1)
		(layers "F.Cu" "B.Cu")
		(remove_unused_layers yes)
		(keep_end_layers yes)
		(zone_layer_connections "In1.Cu" "In3.Cu" "In5.Cu" "In7.Cu" "In10.Cu")
		(net 1)
	)
	(via
		(at 186.5 142.5)
		(size 0.45)
		(drill 0.1)
		(layers "F.Cu" "B.Cu")
		(remove_unused_layers yes)
		(keep_end_layers yes)
		(zone_layer_connections "In1.Cu" "In3.Cu" "In5.Cu" "In7.Cu" "In10.Cu")
		(net 1)
	)
	(via
		(at 251.551499 168.65)
		(size 0.45)
		(drill 0.1)
		(layers "F.Cu" "B.Cu")
		(remove_unused_layers yes)
		(keep_end_layers yes)
		(zone_layer_connections "In1.Cu" "In2.Cu" "In3.Cu" "In4.Cu" "In5.Cu" "In6.Cu"
			"In7.Cu" "In10.Cu"
		)
		(net 1)
	)
	(via
		(at 184.5 158.5)
		(size 0.45)
		(drill 0.1)
		(layers "F.Cu" "B.Cu")
		(remove_unused_layers yes)
		(keep_end_layers yes)
		(zone_layer_connections "In1.Cu" "In3.Cu" "In5.Cu" "In7.Cu" "In10.Cu")
		(net 1)
	)
	(via
		(at 221.05 104.848)
		(size 0.45)
		(drill 0.1)
		(layers "F.Cu" "B.Cu")
		(remove_unused_layers yes)
		(keep_end_layers yes)
		(zone_layer_connections "In1.Cu" "In3.Cu" "In5.Cu" "In7.Cu" "In10.Cu")
		(net 1)
	)
	(via
		(at 124.326 179.727)
		(size 0.45)
		(drill 0.1)
		(layers "F.Cu" "B.Cu")
		(remove_unused_layers yes)
		(keep_end_layers yes)
		(zone_layer_connections "In1.Cu" "In3.Cu" "In5.Cu" "In7.Cu" "In10.Cu")
		(net 1)
	)
	(via
		(at 210.95 155.625)
		(size 0.45)
		(drill 0.1)
		(layers "F.Cu" "B.Cu")
		(remove_unused_layers yes)
		(keep_end_layers yes)
		(zone_layer_connections "In1.Cu" "In3.Cu" "In5.Cu" "In7.Cu" "In10.Cu")
		(net 1)
	)
	(via
		(at 248.91 189.46)
		(size 0.45)
		(drill 0.1)
		(layers "F.Cu" "B.Cu")
		(remove_unused_layers yes)
		(keep_end_layers yes)
		(zone_layer_connections "In1.Cu" "In3.Cu" "In5.Cu" "In7.Cu" "In10.Cu")
		(net 1)
	)
	(via
		(at 122.646 119.173)
		(size 0.45)
		(drill 0.1)
		(layers "F.Cu" "B.Cu")
		(remove_unused_layers yes)
		(keep_end_layers yes)
		(zone_layer_connections "In1.Cu" "In3.Cu" "In5.Cu" "In7.Cu" "In9.Cu" "In10.Cu")
		(net 1)
	)
	(via
		(at 106.627 157.119)
		(size 0.45)
		(drill 0.1)
		(layers "F.Cu" "B.Cu")
		(remove_unused_layers yes)
		(keep_end_layers yes)
		(zone_layer_connections "In1.Cu" "In3.Cu" "In5.Cu" "In7.Cu" "In10.Cu")
		(net 1)
	)
	(via
		(at 134.724499 143.249)
		(size 0.45)
		(drill 0.1)
		(layers "F.Cu" "B.Cu")
		(remove_unused_layers yes)
		(keep_end_layers yes)
		(zone_layer_connections "In1.Cu" "In3.Cu" "In5.Cu" "In7.Cu" "In10.Cu")
		(net 1)
	)
	(via
		(at 157.324499 190.274)
		(size 0.45)
		(drill 0.1)
		(layers "F.Cu" "B.Cu")
		(remove_unused_layers yes)
		(keep_end_layers yes)
		(zone_layer_connections "In1.Cu" "In3.Cu" "In5.Cu" "In7.Cu" "In10.Cu")
		(net 1)
	)
	(via
		(at 116.624499 118.149)
		(size 0.45)
		(drill 0.1)
		(layers "F.Cu" "B.Cu")
		(remove_unused_layers yes)
		(keep_end_layers yes)
		(zone_layer_connections "In1.Cu" "In3.Cu" "In5.Cu" "In7.Cu" "In10.Cu")
		(net 1)
	)
	(via
		(at 187.3 104.2)
		(size 0.45)
		(drill 0.1)
		(layers "F.Cu" "B.Cu")
		(remove_unused_layers yes)
		(keep_end_layers yes)
		(zone_layer_connections "In1.Cu" "In3.Cu" "In5.Cu" "In7.Cu" "In10.Cu")
		(net 1)
	)
	(via
		(at 109.824499 143.749)
		(size 0.45)
		(drill 0.1)
		(layers "F.Cu" "B.Cu")
		(remove_unused_layers yes)
		(keep_end_layers yes)
		(zone_layer_connections "In1.Cu" "In3.Cu" "In5.Cu" "In7.Cu" "In10.Cu")
		(net 1)
	)
	(via
		(at 251.324499 150.399)
		(size 0.45)
		(drill 0.1)
		(layers "F.Cu" "B.Cu")
		(remove_unused_layers yes)
		(keep_end_layers yes)
		(zone_layer_connections "In1.Cu" "In3.Cu" "In5.Cu" "In6.Cu" "In7.Cu" "In10.Cu")
		(net 1)
	)
	(via
		(at 187.500001 140.5)
		(size 0.45)
		(drill 0.1)
		(layers "F.Cu" "B.Cu")
		(remove_unused_layers yes)
		(keep_end_layers yes)
		(zone_layer_connections "In1.Cu" "In3.Cu" "In5.Cu" "In7.Cu" "In10.Cu")
		(net 1)
	)
	(via
		(at 204.05 104.848)
		(size 0.45)
		(drill 0.1)
		(layers "F.Cu" "B.Cu")
		(remove_unused_layers yes)
		(keep_end_layers yes)
		(zone_layer_connections "In1.Cu" "In3.Cu" "In5.Cu" "In7.Cu" "In10.Cu")
		(net 1)
	)
	(via
		(at 140.44 146.03)
		(size 0.45)
		(drill 0.1)
		(layers "F.Cu" "B.Cu")
		(remove_unused_layers yes)
		(keep_end_layers yes)
		(zone_layer_connections "In1.Cu" "In3.Cu" "In5.Cu" "In7.Cu" "In10.Cu")
		(net 1)
	)
	(via
		(at 189.098 100.510001)
		(size 0.45)
		(drill 0.1)
		(layers "F.Cu" "B.Cu")
		(remove_unused_layers yes)
		(keep_end_layers yes)
		(zone_layer_connections "In1.Cu" "In3.Cu" "In5.Cu" "In7.Cu" "In10.Cu")
		(net 1)
	)
	(via
		(at 198.5 156.5)
		(size 0.45)
		(drill 0.1)
		(layers "F.Cu" "B.Cu")
		(remove_unused_layers yes)
		(keep_end_layers yes)
		(zone_layer_connections "In1.Cu" "In3.Cu" "In5.Cu" "In7.Cu" "In10.Cu")
		(net 1)
	)
	(via
		(at 124.756 187.702)
		(size 0.45)
		(drill 0.1)
		(layers "F.Cu" "B.Cu")
		(remove_unused_layers yes)
		(keep_end_layers yes)
		(zone_layer_connections "In1.Cu" "In3.Cu" "In5.Cu" "In7.Cu" "In10.Cu")
		(net 1)
	)
	(via
		(at 147.1 109.446)
		(size 0.45)
		(drill 0.1)
		(layers "F.Cu" "B.Cu")
		(remove_unused_layers yes)
		(keep_end_layers yes)
		(zone_layer_connections "In1.Cu" "In3.Cu" "In5.Cu" "In7.Cu" "In10.Cu")
		(net 1)
	)
	(via
		(at 200.4995 160.4995)
		(size 0.45)
		(drill 0.1)
		(layers "F.Cu" "B.Cu")
		(remove_unused_layers yes)
		(keep_end_layers yes)
		(zone_layer_connections "In1.Cu" "In3.Cu" "In5.Cu" "In7.Cu" "In10.Cu")
		(net 1)
	)
	(via
		(at 185.5 158.5)
		(size 0.45)
		(drill 0.1)
		(layers "F.Cu" "B.Cu")
		(remove_unused_layers yes)
		(keep_end_layers yes)
		(zone_layer_connections "In1.Cu" "In3.Cu" "In5.Cu" "In7.Cu" "In10.Cu")
		(net 1)
	)
	(via
		(at 122.75 182.879)
		(size 0.45)
		(drill 0.1)
		(layers "F.Cu" "B.Cu")
		(remove_unused_layers yes)
		(keep_end_layers yes)
		(zone_layer_connections "In1.Cu" "In3.Cu" "In5.Cu" "In7.Cu" "In10.Cu")
		(net 1)
	)
	(via
		(at 105.8866 100.498601)
		(size 0.45)
		(drill 0.1)
		(layers "F.Cu" "B.Cu")
		(remove_unused_layers yes)
		(keep_end_layers yes)
		(zone_layer_connections "In1.Cu" "In3.Cu" "In5.Cu" "In7.Cu" "In10.Cu")
		(net 1)
	)
	(via
		(at 218.502 109.446)
		(size 0.45)
		(drill 0.1)
		(layers "F.Cu" "B.Cu")
		(remove_unused_layers yes)
		(keep_end_layers yes)
		(zone_layer_connections "In1.Cu" "In3.Cu" "In5.Cu" "In7.Cu" "In10.Cu")
		(net 1)
	)
	(via
		(at 113.847537 168.265)
		(size 0.45)
		(drill 0.1)
		(layers "F.Cu" "B.Cu")
		(remove_unused_layers yes)
		(keep_end_layers yes)
		(zone_layer_connections "In1.Cu" "In3.Cu" "In5.Cu" "In7.Cu" "In10.Cu")
		(net 1)
	)
	(via
		(at 223.735 173.61)
		(size 0.45)
		(drill 0.1)
		(layers "F.Cu" "B.Cu")
		(remove_unused_layers yes)
		(keep_end_layers yes)
		(zone_layer_connections "In1.Cu" "In3.Cu" "In5.Cu" "In7.Cu" "In10.Cu")
		(net 1)
	)
	(via
		(at 179.5 166.45)
		(size 0.45)
		(drill 0.1)
		(layers "F.Cu" "B.Cu")
		(remove_unused_layers yes)
		(keep_end_layers yes)
		(zone_layer_connections "In1.Cu" "In3.Cu" "In5.Cu" "In7.Cu" "In10.Cu")
		(net 1)
	)
	(via
		(at 151.5995 194.149501)
		(size 0.45)
		(drill 0.1)
		(layers "F.Cu" "B.Cu")
		(remove_unused_layers yes)
		(keep_end_layers yes)
		(zone_layer_connections "In1.Cu" "In3.Cu" "In5.Cu" "In7.Cu" "In10.Cu")
		(net 1)
	)
	(via
		(at 225.235 168.36)
		(size 0.45)
		(drill 0.1)
		(layers "F.Cu" "B.Cu")
		(remove_unused_layers yes)
		(keep_end_layers yes)
		(zone_layer_connections "In1.Cu" "In3.Cu" "In5.Cu" "In7.Cu" "In10.Cu")
		(net 1)
	)
	(via
		(at 262.79 112.62)
		(size 0.45)
		(drill 0.1)
		(layers "F.Cu" "B.Cu")
		(remove_unused_layers yes)
		(keep_end_layers yes)
		(zone_layer_connections "In1.Cu" "In3.Cu" "In5.Cu" "In7.Cu" "In10.Cu")
		(net 1)
	)
	(via
		(at 132.926 172.113)
		(size 0.45)
		(drill 0.1)
		(layers "F.Cu" "B.Cu")
		(remove_unused_layers yes)
		(keep_end_layers yes)
		(zone_layer_connections "In1.Cu" "In3.Cu" "In5.Cu" "In7.Cu" "In10.Cu")
		(net 1)
	)
	(via
		(at 131.4866 100.498601)
		(size 0.45)
		(drill 0.1)
		(layers "F.Cu" "B.Cu")
		(remove_unused_layers yes)
		(keep_end_layers yes)
		(zone_layer_connections "In1.Cu" "In3.Cu" "In5.Cu" "In7.Cu" "In10.Cu")
		(net 1)
	)
	(via
		(at 183.5 163.5)
		(size 0.45)
		(drill 0.1)
		(layers "F.Cu" "B.Cu")
		(remove_unused_layers yes)
		(keep_end_layers yes)
		(zone_layer_connections "In1.Cu" "In3.Cu" "In5.Cu" "In7.Cu" "In10.Cu")
		(net 1)
	)
	(via
		(at 191.301 109.446)
		(size 0.45)
		(drill 0.1)
		(layers "F.Cu" "B.Cu")
		(remove_unused_layers yes)
		(keep_end_layers yes)
		(zone_layer_connections "In1.Cu" "In3.Cu" "In5.Cu" "In7.Cu" "In10.Cu")
		(net 1)
	)
	(via
		(at 105.775 156.369)
		(size 0.45)
		(drill 0.1)
		(layers "F.Cu" "B.Cu")
		(remove_unused_layers yes)
		(keep_end_layers yes)
		(zone_layer_connections "In1.Cu" "In3.Cu" "In5.Cu" "In7.Cu" "In10.Cu")
		(net 1)
	)
	(via
		(at 186.5 151.5)
		(size 0.45)
		(drill 0.1)
		(layers "F.Cu" "B.Cu")
		(remove_unused_layers yes)
		(keep_end_layers yes)
		(zone_layer_connections "In1.Cu" "In3.Cu" "In5.Cu" "In7.Cu" "In10.Cu")
		(net 1)
	)
	(via
		(at 247.749499 155.924)
		(size 0.45)
		(drill 0.1)
		(layers "F.Cu" "B.Cu")
		(remove_unused_layers yes)
		(keep_end_layers yes)
		(zone_layer_connections "In1.Cu" "In2.Cu" "In3.Cu" "In4.Cu" "In5.Cu" "In6.Cu"
			"In7.Cu" "In10.Cu"
		)
		(net 1)
	)
	(via
		(at 197.5 158.5)
		(size 0.45)
		(drill 0.1)
		(layers "F.Cu" "B.Cu")
		(remove_unused_layers yes)
		(keep_end_layers yes)
		(zone_layer_connections "In1.Cu" "In3.Cu" "In5.Cu" "In7.Cu" "In10.Cu")
		(net 1)
	)
	(via
		(at 194.499999 160.5)
		(size 0.45)
		(drill 0.1)
		(layers "F.Cu" "B.Cu")
		(remove_unused_layers yes)
		(keep_end_layers yes)
		(zone_layer_connections "In1.Cu" "In3.Cu" "In5.Cu" "In7.Cu" "In10.Cu")
		(net 1)
	)
	(via
		(at 256.4785 156.171)
		(size 0.45)
		(drill 0.1)
		(layers "F.Cu" "B.Cu")
		(remove_unused_layers yes)
		(keep_end_layers yes)
		(zone_layer_connections "In1.Cu" "In2.Cu" "In3.Cu" "In4.Cu" "In5.Cu" "In6.Cu"
			"In7.Cu" "In10.Cu"
		)
		(net 1)
	)
	(via
		(at 169.8866 100.498601)
		(size 0.45)
		(drill 0.1)
		(layers "F.Cu" "B.Cu")
		(remove_unused_layers yes)
		(keep_end_layers yes)
		(zone_layer_connections "In1.Cu" "In3.Cu" "In5.Cu" "In7.Cu" "In10.Cu")
		(net 1)
	)
	(via
		(at 150.7995 194.049501)
		(size 0.45)
		(drill 0.1)
		(layers "F.Cu" "B.Cu")
		(remove_unused_layers yes)
		(keep_end_layers yes)
		(zone_layer_connections "In1.Cu" "In3.Cu" "In5.Cu" "In7.Cu" "In10.Cu")
		(net 1)
	)
	(via
		(at 158.124499 188.474)
		(size 0.45)
		(drill 0.1)
		(layers "F.Cu" "B.Cu")
		(remove_unused_layers yes)
		(keep_end_layers yes)
		(zone_layer_connections "In1.Cu" "In3.Cu" "In5.Cu" "In7.Cu" "In10.Cu")
		(net 1)
	)
	(via
		(at 195.551 104.848)
		(size 0.45)
		(drill 0.1)
		(layers "F.Cu" "B.Cu")
		(remove_unused_layers yes)
		(keep_end_layers yes)
		(zone_layer_connections "In1.Cu" "In3.Cu" "In5.Cu" "In7.Cu" "In10.Cu")
		(net 1)
	)
	(via
		(at 204.875 169.1)
		(size 0.45)
		(drill 0.1)
		(layers "F.Cu" "B.Cu")
		(remove_unused_layers yes)
		(keep_end_layers yes)
		(zone_layer_connections "In1.Cu" "In3.Cu" "In5.Cu" "In7.Cu" "In10.Cu")
		(net 1)
	)
	(via
		(at 197.5 153.5)
		(size 0.45)
		(drill 0.1)
		(layers "F.Cu" "B.Cu")
		(remove_unused_layers yes)
		(keep_end_layers yes)
		(zone_layer_connections "In1.Cu" "In3.Cu" "In5.Cu" "In7.Cu" "In10.Cu")
		(net 1)
	)
	(via
		(at 175.5 165.5)
		(size 0.45)
		(drill 0.1)
		(layers "F.Cu" "B.Cu")
		(remove_unused_layers yes)
		(keep_end_layers yes)
		(zone_layer_connections "In1.Cu" "In3.Cu" "In5.Cu" "In7.Cu" "In10.Cu")
		(net 1)
	)
	(via
		(at 112.430499 182.5525)
		(size 0.45)
		(drill 0.1)
		(layers "F.Cu" "B.Cu")
		(remove_unused_layers yes)
		(keep_end_layers yes)
		(zone_layer_connections "In1.Cu" "In3.Cu" "In5.Cu" "In7.Cu" "In10.Cu")
		(net 1)
	)
	(via
		(at 225.235 170.51)
		(size 0.45)
		(drill 0.1)
		(layers "F.Cu" "B.Cu")
		(remove_unused_layers yes)
		(keep_end_layers yes)
		(zone_layer_connections "In1.Cu" "In3.Cu" "In5.Cu" "In7.Cu" "In10.Cu")
		(net 1)
	)
	(via
		(at 122.63 129.456)
		(size 0.45)
		(drill 0.1)
		(layers "F.Cu" "B.Cu")
		(remove_unused_layers yes)
		(keep_end_layers yes)
		(zone_layer_connections "In1.Cu" "In3.Cu" "In5.Cu" "In7.Cu" "In9.Cu" "In10.Cu")
		(net 1)
	)
	(via
		(at 189.5 162.5)
		(size 0.45)
		(drill 0.1)
		(layers "F.Cu" "B.Cu")
		(remove_unused_layers yes)
		(keep_end_layers yes)
		(zone_layer_connections "In1.Cu" "In3.Cu" "In5.Cu" "In7.Cu" "In10.Cu")
		(net 1)
	)
	(via
		(at 118.1 139.55)
		(size 0.45)
		(drill 0.1)
		(layers "F.Cu" "B.Cu")
		(net 1)
	)
	(via
		(at 190.5 160.5)
		(size 0.45)
		(drill 0.1)
		(layers "F.Cu" "B.Cu")
		(remove_unused_layers yes)
		(keep_end_layers yes)
		(zone_layer_connections "In1.Cu" "In3.Cu" "In5.Cu" "In7.Cu" "In10.Cu")
		(net 1)
	)
	(via
		(at 146.724499 183.749)
		(size 0.45)
		(drill 0.1)
		(layers "F.Cu" "B.Cu")
		(remove_unused_layers yes)
		(keep_end_layers yes)
		(zone_layer_connections "In1.Cu" "In3.Cu" "In5.Cu" "In7.Cu" "In10.Cu")
		(net 1)
	)
	(via
		(at 158.924499 190.849)
		(size 0.45)
		(drill 0.1)
		(layers "F.Cu" "B.Cu")
		(remove_unused_layers yes)
		(keep_end_layers yes)
		(zone_layer_connections "In1.Cu" "In3.Cu" "In5.Cu" "In7.Cu" "In10.Cu")
		(net 1)
	)
	(via
		(at 262.79 115.48)
		(size 0.45)
		(drill 0.1)
		(layers "F.Cu" "B.Cu")
		(remove_unused_layers yes)
		(keep_end_layers yes)
		(zone_layer_connections "In1.Cu" "In3.Cu" "In5.Cu" "In7.Cu" "In10.Cu")
		(net 1)
	)
	(via
		(at 254.8 106.35)
		(size 0.45)
		(drill 0.1)
		(layers "F.Cu" "B.Cu")
		(remove_unused_layers yes)
		(keep_end_layers yes)
		(zone_layer_connections "In1.Cu" "In3.Cu" "In5.Cu" "In7.Cu" "In10.Cu")
		(net 1)
	)
	(via
		(at 142.224499 188.649)
		(size 0.45)
		(drill 0.1)
		(layers "F.Cu" "B.Cu")
		(remove_unused_layers yes)
		(keep_end_layers yes)
		(zone_layer_connections "In1.Cu" "In3.Cu" "In5.Cu" "In7.Cu" "In10.Cu")
		(net 1)
	)
	(via
		(at 123.056 173.832)
		(size 0.45)
		(drill 0.1)
		(layers "F.Cu" "B.Cu")
		(remove_unused_layers yes)
		(keep_end_layers yes)
		(zone_layer_connections "In1.Cu" "In3.Cu" "In5.Cu" "In7.Cu" "In10.Cu")
		(net 1)
	)
	(via
		(at 200.651 104.848)
		(size 0.45)
		(drill 0.1)
		(layers "F.Cu" "B.Cu")
		(remove_unused_layers yes)
		(keep_end_layers yes)
		(zone_layer_connections "In1.Cu" "In3.Cu" "In5.Cu" "In7.Cu" "In10.Cu")
		(net 1)
	)
	(via
		(at 176.5 161.5)
		(size 0.45)
		(drill 0.1)
		(layers "F.Cu" "B.Cu")
		(remove_unused_layers yes)
		(keep_end_layers yes)
		(zone_layer_connections "In1.Cu" "In3.Cu" "In5.Cu" "In7.Cu" "In10.Cu")
		(net 1)
	)
	(via
		(at 135.201 104.848)
		(size 0.45)
		(drill 0.1)
		(layers "F.Cu" "B.Cu")
		(remove_unused_layers yes)
		(keep_end_layers yes)
		(zone_layer_connections "In1.Cu" "In3.Cu" "In5.Cu" "In7.Cu" "In10.Cu")
		(net 1)
	)
	(via
		(at 215.875 155.6)
		(size 0.45)
		(drill 0.1)
		(layers "F.Cu" "B.Cu")
		(remove_unused_layers yes)
		(keep_end_layers yes)
		(zone_layer_connections "In1.Cu" "In3.Cu" "In5.Cu" "In7.Cu" "In10.Cu")
		(net 1)
	)
	(via
		(at 174.71 102.73)
		(size 0.45)
		(drill 0.1)
		(layers "F.Cu" "B.Cu")
		(remove_unused_layers yes)
		(keep_end_layers yes)
		(zone_layer_connections "In1.Cu" "In3.Cu" "In5.Cu" "In7.Cu" "In10.Cu")
		(net 1)
	)
	(via
		(at 189.5005 164.4995)
		(size 0.45)
		(drill 0.1)
		(layers "F.Cu" "B.Cu")
		(remove_unused_layers yes)
		(keep_end_layers yes)
		(zone_layer_connections "In1.Cu" "In3.Cu" "In5.Cu" "In7.Cu" "In10.Cu")
		(net 1)
	)
	(via
		(at 201.5 139.5)
		(size 0.45)
		(drill 0.1)
		(layers "F.Cu" "B.Cu")
		(remove_unused_layers yes)
		(keep_end_layers yes)
		(zone_layer_connections "In1.Cu" "In3.Cu" "In5.Cu" "In7.Cu" "In10.Cu")
		(net 1)
	)
	(via
		(at 197.5 163.5)
		(size 0.45)
		(drill 0.1)
		(layers "F.Cu" "B.Cu")
		(remove_unused_layers yes)
		(keep_end_layers yes)
		(zone_layer_connections "In1.Cu" "In3.Cu" "In5.Cu" "In7.Cu" "In10.Cu")
		(net 1)
	)
	(via
		(at 140.349499 171.649)
		(size 0.45)
		(drill 0.1)
		(layers "F.Cu" "B.Cu")
		(remove_unused_layers yes)
		(keep_end_layers yes)
		(zone_layer_connections "In1.Cu" "In3.Cu" "In5.Cu" "In7.Cu" "In10.Cu")
		(net 1)
	)
	(via
		(at 242.09 123.07)
		(size 0.45)
		(drill 0.1)
		(layers "F.Cu" "B.Cu")
		(remove_unused_layers yes)
		(keep_end_layers yes)
		(zone_layer_connections "In1.Cu" "In3.Cu" "In5.Cu" "In7.Cu" "In10.Cu")
		(net 1)
	)
	(via
		(at 209.35 189.46)
		(size 0.45)
		(drill 0.1)
		(layers "F.Cu" "B.Cu")
		(remove_unused_layers yes)
		(keep_end_layers yes)
		(zone_layer_connections "In1.Cu" "In3.Cu" "In5.Cu" "In7.Cu" "In10.Cu")
		(net 1)
	)
	(via
		(at 123.9014 130.1374)
		(size 0.45)
		(drill 0.1)
		(layers "F.Cu" "B.Cu")
		(remove_unused_layers yes)
		(keep_end_layers yes)
		(zone_layer_connections "In1.Cu" "In3.Cu" "In5.Cu" "In7.Cu" "In9.Cu" "In10.Cu")
		(net 1)
	)
	(via
		(at 263.924499 127.949)
		(size 0.45)
		(drill 0.1)
		(layers "F.Cu" "B.Cu")
		(remove_unused_layers yes)
		(keep_end_layers yes)
		(zone_layer_connections "In1.Cu" "In3.Cu" "In5.Cu" "In7.Cu" "In10.Cu")
		(net 1)
	)
	(via
		(at 167.6 152)
		(size 0.45)
		(drill 0.1)
		(layers "F.Cu" "B.Cu")
		(remove_unused_layers yes)
		(keep_end_layers yes)
		(zone_layer_connections "In1.Cu" "In3.Cu" "In5.Cu" "In7.Cu" "In10.Cu")
		(net 1)
	)
	(via
		(at 263.924499 101.64)
		(size 0.45)
		(drill 0.1)
		(layers "F.Cu" "B.Cu")
		(remove_unused_layers yes)
		(keep_end_layers yes)
		(zone_layer_connections "In1.Cu" "In3.Cu" "In5.Cu" "In7.Cu" "In10.Cu")
		(net 1)
	)
	(via
		(at 225.635 177.96)
		(size 0.45)
		(drill 0.1)
		(layers "F.Cu" "B.Cu")
		(remove_unused_layers yes)
		(keep_end_layers yes)
		(zone_layer_connections "In1.Cu" "In3.Cu" "In5.Cu" "In7.Cu" "In10.Cu")
		(net 1)
	)
	(via
		(at 194.5 158.5)
		(size 0.45)
		(drill 0.1)
		(layers "F.Cu" "B.Cu")
		(remove_unused_layers yes)
		(keep_end_layers yes)
		(zone_layer_connections "In1.Cu" "In3.Cu" "In5.Cu" "In7.Cu" "In10.Cu")
		(net 1)
	)
	(via
		(at 198.4995 158.4995)
		(size 0.45)
		(drill 0.1)
		(layers "F.Cu" "B.Cu")
		(remove_unused_layers yes)
		(keep_end_layers yes)
		(zone_layer_connections "In1.Cu" "In3.Cu" "In5.Cu" "In7.Cu" "In10.Cu")
		(net 1)
	)
	(via
		(at 235.57 131.361001)
		(size 0.45)
		(drill 0.1)
		(layers "F.Cu" "B.Cu")
		(remove_unused_layers yes)
		(keep_end_layers yes)
		(zone_layer_connections "In1.Cu" "In3.Cu" "In5.Cu" "In7.Cu" "In10.Cu")
		(net 1)
	)
	(via
		(at 203.601 140.013268)
		(size 0.45)
		(drill 0.1)
		(layers "F.Cu" "B.Cu")
		(net 1)
	)
	(via
		(at 181.5 163.5)
		(size 0.45)
		(drill 0.1)
		(layers "F.Cu" "B.Cu")
		(remove_unused_layers yes)
		(keep_end_layers yes)
		(zone_layer_connections "In1.Cu" "In3.Cu" "In5.Cu" "In7.Cu" "In10.Cu")
		(net 1)
	)
	(via
		(at 176.002 109.446)
		(size 0.45)
		(drill 0.1)
		(layers "F.Cu" "B.Cu")
		(remove_unused_layers yes)
		(keep_end_layers yes)
		(zone_layer_connections "In1.Cu" "In3.Cu" "In5.Cu" "In7.Cu" "In10.Cu")
		(net 1)
	)
	(via
		(at 241.7 126.65)
		(size 0.45)
		(drill 0.1)
		(layers "F.Cu" "B.Cu")
		(remove_unused_layers yes)
		(keep_end_layers yes)
		(zone_layer_connections "In1.Cu" "In3.Cu" "In5.Cu" "In7.Cu" "In10.Cu")
		(net 1)
	)
	(via
		(at 100.624499 106.949)
		(size 0.45)
		(drill 0.1)
		(layers "F.Cu" "B.Cu")
		(remove_unused_layers yes)
		(keep_end_layers yes)
		(zone_layer_connections "In1.Cu" "In3.Cu" "In5.Cu" "In7.Cu" "In10.Cu")
		(net 1)
	)
	(via
		(at 257.37 114.105)
		(size 0.45)
		(drill 0.1)
		(layers "F.Cu" "B.Cu")
		(remove_unused_layers yes)
		(keep_end_layers yes)
		(zone_layer_connections "In1.Cu" "In3.Cu" "In5.Cu" "In7.Cu" "In10.Cu")
		(net 1)
	)
	(via
		(at 213.4 104.848)
		(size 0.45)
		(drill 0.1)
		(layers "F.Cu" "B.Cu")
		(remove_unused_layers yes)
		(keep_end_layers yes)
		(zone_layer_connections "In1.Cu" "In3.Cu" "In5.Cu" "In7.Cu" "In10.Cu")
		(net 1)
	)
	(via
		(at 251.524499 151.199)
		(size 0.45)
		(drill 0.1)
		(layers "F.Cu" "B.Cu")
		(remove_unused_layers yes)
		(keep_end_layers yes)
		(zone_layer_connections "In1.Cu" "In2.Cu" "In3.Cu" "In4.Cu" "In5.Cu" "In6.Cu"
			"In7.Cu" "In10.Cu"
		)
		(net 1)
	)
	(via
		(at 263.924499 131.149)
		(size 0.45)
		(drill 0.1)
		(layers "F.Cu" "B.Cu")
		(remove_unused_layers yes)
		(keep_end_layers yes)
		(zone_layer_connections "In1.Cu" "In3.Cu" "In5.Cu" "In7.Cu" "In10.Cu")
		(net 1)
	)
	(via
		(at 204.5 159.5)
		(size 0.45)
		(drill 0.1)
		(layers "F.Cu" "B.Cu")
		(remove_unused_layers yes)
		(keep_end_layers yes)
		(zone_layer_connections "In1.Cu" "In3.Cu" "In5.Cu" "In7.Cu" "In10.Cu")
		(net 1)
	)
	(via
		(at 193.5 162.5)
		(size 0.45)
		(drill 0.1)
		(layers "F.Cu" "B.Cu")
		(remove_unused_layers yes)
		(keep_end_layers yes)
		(zone_layer_connections "In1.Cu" "In3.Cu" "In5.Cu" "In7.Cu" "In10.Cu")
		(net 1)
	)
	(via
		(at 114.632499 179.551)
		(size 0.45)
		(drill 0.1)
		(layers "F.Cu" "B.Cu")
		(remove_unused_layers yes)
		(keep_end_layers yes)
		(zone_layer_connections "In1.Cu" "In3.Cu" "In5.Cu" "In7.Cu" "In10.Cu")
		(net 1)
	)
	(via
		(at 112.466 175.7685)
		(size 0.45)
		(drill 0.1)
		(layers "F.Cu" "B.Cu")
		(remove_unused_layers yes)
		(keep_end_layers yes)
		(zone_layer_connections "In1.Cu" "In3.Cu" "In5.Cu" "In7.Cu" "In10.Cu")
		(net 1)
	)
	(via
		(at 191.1995 194.849501)
		(size 0.45)
		(drill 0.1)
		(layers "F.Cu" "B.Cu")
		(remove_unused_layers yes)
		(keep_end_layers yes)
		(zone_layer_connections "In1.Cu" "In3.Cu" "In5.Cu" "In7.Cu" "In10.Cu")
		(net 1)
	)
	(via
		(at 263.424499 159.349)
		(size 0.45)
		(drill 0.1)
		(layers "F.Cu" "B.Cu")
		(remove_unused_layers yes)
		(keep_end_layers yes)
		(zone_layer_connections "In1.Cu" "In3.Cu" "In5.Cu" "In6.Cu" "In7.Cu" "In10.Cu")
		(net 1)
	)
	(via
		(at 215.95 104.848)
		(size 0.45)
		(drill 0.1)
		(layers "F.Cu" "B.Cu")
		(remove_unused_layers yes)
		(keep_end_layers yes)
		(zone_layer_connections "In1.Cu" "In3.Cu" "In5.Cu" "In7.Cu" "In10.Cu")
		(net 1)
	)
	(via
		(at 233.95 181.215)
		(size 0.45)
		(drill 0.1)
		(layers "F.Cu" "B.Cu")
		(remove_unused_layers yes)
		(keep_end_layers yes)
		(zone_layer_connections "In1.Cu" "In3.Cu" "In5.Cu" "In7.Cu" "In10.Cu")
		(net 1)
	)
	(via
		(at 263.924499 134.349)
		(size 0.45)
		(drill 0.1)
		(layers "F.Cu" "B.Cu")
		(remove_unused_layers yes)
		(keep_end_layers yes)
		(zone_layer_connections "In1.Cu" "In3.Cu" "In5.Cu" "In7.Cu" "In10.Cu")
		(net 1)
	)
	(via
		(at 218.475 157.125)
		(size 0.45)
		(drill 0.1)
		(layers "F.Cu" "B.Cu")
		(remove_unused_layers yes)
		(keep_end_layers yes)
		(zone_layer_connections "In1.Cu" "In3.Cu" "In5.Cu" "In7.Cu" "In10.Cu")
		(net 1)
	)
	(via
		(at 116.435 108.2)
		(size 0.45)
		(drill 0.1)
		(layers "F.Cu" "B.Cu")
		(remove_unused_layers yes)
		(keep_end_layers yes)
		(zone_layer_connections "In1.Cu" "In3.Cu" "In5.Cu" "In7.Cu" "In10.Cu")
		(net 1)
	)
	(via
		(at 263.51 113.35)
		(size 0.45)
		(drill 0.1)
		(layers "F.Cu" "B.Cu")
		(remove_unused_layers yes)
		(keep_end_layers yes)
		(zone_layer_connections "In1.Cu" "In3.Cu" "In5.Cu" "In7.Cu" "In10.Cu")
		(net 1)
	)
	(via
		(at 252.224499 159.849)
		(size 0.45)
		(drill 0.1)
		(layers "F.Cu" "B.Cu")
		(remove_unused_layers yes)
		(keep_end_layers yes)
		(zone_layer_connections "In1.Cu" "In2.Cu" "In3.Cu" "In5.Cu" "In6.Cu" "In7.Cu"
			"In10.Cu"
		)
		(net 1)
	)
	(via
		(at 117.08 146.61)
		(size 0.45)
		(drill 0.1)
		(layers "F.Cu" "B.Cu")
		(remove_unused_layers yes)
		(keep_end_layers yes)
		(zone_layer_connections "In1.Cu" "In3.Cu" "In5.Cu" "In7.Cu" "In10.Cu")
		(net 1)
	)
	(via
		(at 215.385 188.635)
		(size 0.45)
		(drill 0.1)
		(layers "F.Cu" "B.Cu")
		(remove_unused_layers yes)
		(keep_end_layers yes)
		(zone_layer_connections "In1.Cu" "In3.Cu" "In5.Cu" "In7.Cu" "In10.Cu")
		(net 1)
	)
	(via
		(at 140.224499 186.349)
		(size 0.45)
		(drill 0.1)
		(layers "F.Cu" "B.Cu")
		(remove_unused_layers yes)
		(keep_end_layers yes)
		(zone_layer_connections "In1.Cu" "In3.Cu" "In5.Cu" "In7.Cu" "In10.Cu")
		(net 1)
	)
	(via
		(at 188.75 109.446)
		(size 0.45)
		(drill 0.1)
		(layers "F.Cu" "B.Cu")
		(remove_unused_layers yes)
		(keep_end_layers yes)
		(zone_layer_connections "In1.Cu" "In3.Cu" "In5.Cu" "In7.Cu" "In10.Cu")
		(net 1)
	)
	(via
		(at 194.499999 155.5)
		(size 0.45)
		(drill 0.1)
		(layers "F.Cu" "B.Cu")
		(remove_unused_layers yes)
		(keep_end_layers yes)
		(zone_layer_connections "In1.Cu" "In3.Cu" "In5.Cu" "In7.Cu" "In10.Cu")
		(net 1)
	)
	(via
		(at 234.785 173.66)
		(size 0.45)
		(drill 0.1)
		(layers "F.Cu" "B.Cu")
		(remove_unused_layers yes)
		(keep_end_layers yes)
		(zone_layer_connections "In1.Cu" "In3.Cu" "In5.Cu" "In7.Cu" "In10.Cu")
		(net 1)
	)
	(via
		(at 213.585 169.46)
		(size 0.45)
		(drill 0.1)
		(layers "F.Cu" "B.Cu")
		(remove_unused_layers yes)
		(keep_end_layers yes)
		(zone_layer_connections "In1.Cu" "In3.Cu" "In5.Cu" "In7.Cu" "In10.Cu")
		(net 1)
	)
	(via
		(at 201.5 144.5)
		(size 0.45)
		(drill 0.1)
		(layers "F.Cu" "B.Cu")
		(remove_unused_layers yes)
		(keep_end_layers yes)
		(zone_layer_connections "In1.Cu" "In3.Cu" "In5.Cu" "In7.Cu" "In10.Cu")
		(net 1)
	)
	(via
		(at 118.6866 100.498601)
		(size 0.45)
		(drill 0.1)
		(layers "F.Cu" "B.Cu")
		(remove_unused_layers yes)
		(keep_end_layers yes)
		(zone_layer_connections "In1.Cu" "In3.Cu" "In5.Cu" "In7.Cu" "In10.Cu")
		(net 1)
	)
	(via
		(at 190.5 155.5)
		(size 0.45)
		(drill 0.1)
		(layers "F.Cu" "B.Cu")
		(remove_unused_layers yes)
		(keep_end_layers yes)
		(zone_layer_connections "In1.Cu" "In3.Cu" "In5.Cu" "In7.Cu" "In10.Cu")
		(net 1)
	)
	(via
		(at 251.024499 172.649)
		(size 0.45)
		(drill 0.1)
		(layers "F.Cu" "B.Cu")
		(remove_unused_layers yes)
		(keep_end_layers yes)
		(zone_layer_connections "In1.Cu" "In2.Cu" "In3.Cu" "In4.Cu" "In5.Cu" "In6.Cu"
			"In7.Cu" "In10.Cu"
		)
		(net 1)
	)
	(via
		(at 201.4995 163.4995)
		(size 0.45)
		(drill 0.1)
		(layers "F.Cu" "B.Cu")
		(remove_unused_layers yes)
		(keep_end_layers yes)
		(zone_layer_connections "In1.Cu" "In3.Cu" "In5.Cu" "In7.Cu" "In10.Cu")
		(net 1)
	)
	(via
		(at 256.65 115.525)
		(size 0.45)
		(drill 0.1)
		(layers "F.Cu" "B.Cu")
		(remove_unused_layers yes)
		(keep_end_layers yes)
		(zone_layer_connections "In1.Cu" "In3.Cu" "In5.Cu" "In7.Cu" "In10.Cu")
		(net 1)
	)
	(via
		(at 201.5 149.5)
		(size 0.45)
		(drill 0.1)
		(layers "F.Cu" "B.Cu")
		(remove_unused_layers yes)
		(keep_end_layers yes)
		(zone_layer_connections "In1.Cu" "In3.Cu" "In5.Cu" "In7.Cu" "In10.Cu")
		(net 1)
	)
	(via
		(at 160.81 165.519999)
		(size 0.45)
		(drill 0.1)
		(layers "F.Cu" "B.Cu")
		(remove_unused_layers yes)
		(keep_end_layers yes)
		(zone_layer_connections "In1.Cu" "In3.Cu" "In5.Cu" "In7.Cu" "In10.Cu")
		(net 1)
	)
	(via
		(at 146.241843 160.079157)
		(size 0.45)
		(drill 0.1)
		(layers "F.Cu" "B.Cu")
		(remove_unused_layers yes)
		(keep_end_layers yes)
		(zone_layer_connections "In1.Cu" "In3.Cu" "In5.Cu" "In7.Cu" "In10.Cu")
		(net 1)
	)
	(via
		(at 191.5005 165.4995)
		(size 0.45)
		(drill 0.1)
		(layers "F.Cu" "B.Cu")
		(remove_unused_layers yes)
		(keep_end_layers yes)
		(zone_layer_connections "In1.Cu" "In3.Cu" "In5.Cu" "In7.Cu" "In10.Cu")
		(net 1)
	)
	(via
		(at 217.898 100.510001)
		(size 0.45)
		(drill 0.1)
		(layers "F.Cu" "B.Cu")
		(remove_unused_layers yes)
		(keep_end_layers yes)
		(zone_layer_connections "In1.Cu" "In3.Cu" "In5.Cu" "In7.Cu" "In10.Cu")
		(net 1)
	)
	(via
		(at 261.4 115.48)
		(size 0.45)
		(drill 0.1)
		(layers "F.Cu" "B.Cu")
		(remove_unused_layers yes)
		(keep_end_layers yes)
		(zone_layer_connections "In1.Cu" "In3.Cu" "In5.Cu" "In7.Cu" "In10.Cu")
		(net 1)
	)
	(via
		(at 105.824499 125.01)
		(size 0.45)
		(drill 0.1)
		(layers "F.Cu" "B.Cu")
		(remove_unused_layers yes)
		(keep_end_layers yes)
		(zone_layer_connections "In1.Cu" "In3.Cu" "In5.Cu" "In7.Cu" "In10.Cu")
		(net 1)
	)
	(via
		(at 170.9 104.848)
		(size 0.45)
		(drill 0.1)
		(layers "F.Cu" "B.Cu")
		(remove_unused_layers yes)
		(keep_end_layers yes)
		(zone_layer_connections "In1.Cu" "In3.Cu" "In5.Cu" "In7.Cu" "In10.Cu")
		(net 1)
	)
	(via
		(at 229.222 144.851)
		(size 0.45)
		(drill 0.1)
		(layers "F.Cu" "B.Cu")
		(remove_unused_layers yes)
		(keep_end_layers yes)
		(zone_layer_connections "In1.Cu" "In3.Cu" "In5.Cu" "In7.Cu" "In10.Cu")
		(net 1)
	)
	(via
		(at 135.624499 179.449)
		(size 0.45)
		(drill 0.1)
		(layers "F.Cu" "B.Cu")
		(remove_unused_layers yes)
		(keep_end_layers yes)
		(zone_layer_connections "In1.Cu" "In3.Cu" "In5.Cu" "In7.Cu" "In10.Cu")
		(net 1)
	)
	(via
		(at 200.5 151.5)
		(size 0.45)
		(drill 0.1)
		(layers "F.Cu" "B.Cu")
		(remove_unused_layers yes)
		(keep_end_layers yes)
		(zone_layer_connections "In1.Cu" "In3.Cu" "In5.Cu" "In7.Cu" "In10.Cu")
		(net 1)
	)
	(via
		(at 257.79 146.701001)
		(size 0.45)
		(drill 0.1)
		(layers "F.Cu" "B.Cu")
		(remove_unused_layers yes)
		(keep_end_layers yes)
		(zone_layer_connections "In1.Cu" "In3.Cu" "In5.Cu" "In7.Cu" "In10.Cu")
		(net 1)
	)
	(via
		(at 261.4 112.62)
		(size 0.45)
		(drill 0.1)
		(layers "F.Cu" "B.Cu")
		(remove_unused_layers yes)
		(keep_end_layers yes)
		(zone_layer_connections "In1.Cu" "In3.Cu" "In5.Cu" "In7.Cu" "In10.Cu")
		(net 1)
	)
	(via
		(at 112.2866 100.498601)
		(size 0.45)
		(drill 0.1)
		(layers "F.Cu" "B.Cu")
		(remove_unused_layers yes)
		(keep_end_layers yes)
		(zone_layer_connections "In1.Cu" "In3.Cu" "In5.Cu" "In7.Cu" "In10.Cu")
		(net 1)
	)
	(via
		(at 100.624499 110.149)
		(size 0.45)
		(drill 0.1)
		(layers "F.Cu" "B.Cu")
		(remove_unused_layers yes)
		(keep_end_layers yes)
		(zone_layer_connections "In1.Cu" "In3.Cu" "In5.Cu" "In7.Cu" "In10.Cu")
		(net 1)
	)
	(via
		(at 233.185 176.96)
		(size 0.45)
		(drill 0.1)
		(layers "F.Cu" "B.Cu")
		(remove_unused_layers yes)
		(keep_end_layers yes)
		(zone_layer_connections "In1.Cu" "In3.Cu" "In5.Cu" "In7.Cu" "In10.Cu")
		(net 1)
	)
	(via
		(at 251.551499 176.6)
		(size 0.45)
		(drill 0.1)
		(layers "F.Cu" "B.Cu")
		(remove_unused_layers yes)
		(keep_end_layers yes)
		(zone_layer_connections "In1.Cu" "In2.Cu" "In3.Cu" "In4.Cu" "In5.Cu" "In6.Cu"
			"In7.Cu" "In10.Cu"
		)
		(net 1)
	)
	(via
		(at 241.54 122.72)
		(size 0.45)
		(drill 0.1)
		(layers "F.Cu" "B.Cu")
		(remove_unused_layers yes)
		(keep_end_layers yes)
		(zone_layer_connections "In1.Cu" "In3.Cu" "In5.Cu" "In7.Cu" "In10.Cu")
		(net 1)
	)
	(via
		(at 121.036 168.6935)
		(size 0.45)
		(drill 0.1)
		(layers "F.Cu" "B.Cu")
		(remove_unused_layers yes)
		(keep_end_layers yes)
		(zone_layer_connections "In1.Cu" "In3.Cu" "In5.Cu" "In7.Cu" "In10.Cu")
		(net 1)
	)
	(via
		(at 114.586 175.867)
		(size 0.45)
		(drill 0.1)
		(layers "F.Cu" "B.Cu")
		(remove_unused_layers yes)
		(keep_end_layers yes)
		(zone_layer_connections "In1.Cu" "In3.Cu" "In5.Cu" "In7.Cu" "In10.Cu")
		(net 1)
	)
	(via
		(at 213.525 158.2)
		(size 0.45)
		(drill 0.1)
		(layers "F.Cu" "B.Cu")
		(remove_unused_layers yes)
		(keep_end_layers yes)
		(zone_layer_connections "In1.Cu" "In3.Cu" "In5.Cu" "In7.Cu" "In10.Cu")
		(net 1)
	)
	(via
		(at 128.306 174.912)
		(size 0.45)
		(drill 0.1)
		(layers "F.Cu" "B.Cu")
		(remove_unused_layers yes)
		(keep_end_layers yes)
		(zone_layer_connections "In1.Cu" "In3.Cu" "In5.Cu" "In7.Cu" "In10.Cu")
		(net 1)
	)
	(via
		(at 180.5 139.5)
		(size 0.45)
		(drill 0.1)
		(layers "F.Cu" "B.Cu")
		(remove_unused_layers yes)
		(keep_end_layers yes)
		(zone_layer_connections "In1.Cu" "In3.Cu" "In5.Cu" "In7.Cu" "In10.Cu")
		(net 1)
	)
	(via
		(at 251.2 116.5)
		(size 0.45)
		(drill 0.1)
		(layers "F.Cu" "B.Cu")
		(remove_unused_layers yes)
		(keep_end_layers yes)
		(zone_layer_connections "In1.Cu" "In3.Cu" "In5.Cu" "In7.Cu" "In10.Cu")
		(net 1)
	)
	(via
		(at 161.3 175.33)
		(size 0.45)
		(drill 0.1)
		(layers "F.Cu" "B.Cu")
		(remove_unused_layers yes)
		(keep_end_layers yes)
		(zone_layer_connections "In1.Cu" "In3.Cu" "In5.Cu" "In7.Cu" "In10.Cu")
		(net 1)
	)
	(via
		(at 206.15 189.46)
		(size 0.45)
		(drill 0.1)
		(layers "F.Cu" "B.Cu")
		(remove_unused_layers yes)
		(keep_end_layers yes)
		(zone_layer_connections "In1.Cu" "In3.Cu" "In5.Cu" "In7.Cu" "In10.Cu")
		(net 1)
	)
	(via
		(at 225.301 104.848)
		(size 0.45)
		(drill 0.1)
		(layers "F.Cu" "B.Cu")
		(remove_unused_layers yes)
		(keep_end_layers yes)
		(zone_layer_connections "In1.Cu" "In3.Cu" "In5.Cu" "In7.Cu" "In10.Cu")
		(net 1)
	)
	(via
		(at 138.35 154.95)
		(size 0.45)
		(drill 0.1)
		(layers "F.Cu" "B.Cu")
		(remove_unused_layers yes)
		(keep_end_layers yes)
		(zone_layer_connections "In1.Cu" "In3.Cu" "In5.Cu" "In7.Cu" "In10.Cu")
		(net 1)
	)
	(via
		(at 221.485 176.11)
		(size 0.45)
		(drill 0.1)
		(layers "F.Cu" "B.Cu")
		(remove_unused_layers yes)
		(keep_end_layers yes)
		(zone_layer_connections)
		(net 1)
	)
	(via
		(at 234.8 175.8)
		(size 0.45)
		(drill 0.1)
		(layers "F.Cu" "B.Cu")
		(remove_unused_layers yes)
		(keep_end_layers yes)
		(zone_layer_connections "In1.Cu" "In3.Cu" "In5.Cu" "In7.Cu" "In10.Cu")
		(net 1)
	)
	(via
		(at 254.7 128.925)
		(size 0.45)
		(drill 0.1)
		(layers "F.Cu" "B.Cu")
		(remove_unused_layers yes)
		(keep_end_layers yes)
		(zone_layer_connections "In1.Cu" "In3.Cu" "In5.Cu" "In7.Cu" "In10.Cu")
		(net 1)
	)
	(via
		(at 198.5 145.5)
		(size 0.45)
		(drill 0.1)
		(layers "F.Cu" "B.Cu")
		(remove_unused_layers yes)
		(keep_end_layers yes)
		(zone_layer_connections "In1.Cu" "In3.Cu" "In5.Cu" "In7.Cu" "In10.Cu")
		(net 1)
	)
	(via
		(at 115.75 117.1)
		(size 0.45)
		(drill 0.1)
		(layers "F.Cu" "B.Cu")
		(remove_unused_layers yes)
		(keep_end_layers yes)
		(zone_layer_connections "In1.Cu" "In3.Cu" "In5.Cu" "In7.Cu" "In10.Cu")
		(net 1)
	)
	(via
		(at 255.618 155.3085)
		(size 0.45)
		(drill 0.1)
		(layers "F.Cu" "B.Cu")
		(remove_unused_layers yes)
		(keep_end_layers yes)
		(zone_layer_connections "In1.Cu" "In2.Cu" "In3.Cu" "In4.Cu" "In5.Cu" "In6.Cu"
			"In7.Cu" "In10.Cu"
		)
		(net 1)
	)
	(via
		(at 263.924499 108.039999)
		(size 0.45)
		(drill 0.1)
		(layers "F.Cu" "B.Cu")
		(remove_unused_layers yes)
		(keep_end_layers yes)
		(zone_layer_connections "In1.Cu" "In3.Cu" "In5.Cu" "In7.Cu" "In10.Cu")
		(net 1)
	)
	(via
		(at 199.8 109.446)
		(size 0.45)
		(drill 0.1)
		(layers "F.Cu" "B.Cu")
		(remove_unused_layers yes)
		(keep_end_layers yes)
		(zone_layer_connections "In1.Cu" "In3.Cu" "In5.Cu" "In7.Cu" "In10.Cu")
		(net 1)
	)
	(via
		(at 252.251499 167.95)
		(size 0.45)
		(drill 0.1)
		(layers "F.Cu" "B.Cu")
		(remove_unused_layers yes)
		(keep_end_layers yes)
		(zone_layer_connections "In1.Cu" "In2.Cu" "In3.Cu" "In5.Cu" "In6.Cu" "In7.Cu"
			"In10.Cu"
		)
		(net 1)
	)
	(via
		(at 180.5 158.5)
		(size 0.45)
		(drill 0.1)
		(layers "F.Cu" "B.Cu")
		(remove_unused_layers yes)
		(keep_end_layers yes)
		(zone_layer_connections "In1.Cu" "In3.Cu" "In5.Cu" "In7.Cu" "In10.Cu")
		(net 1)
	)
	(via
		(at 212.551 109.446)
		(size 0.45)
		(drill 0.1)
		(layers "F.Cu" "B.Cu")
		(remove_unused_layers yes)
		(keep_end_layers yes)
		(zone_layer_connections "In1.Cu" "In3.Cu" "In5.Cu" "In7.Cu" "In10.Cu")
		(net 1)
	)
	(via
		(at 123.024499 188.649)
		(size 0.45)
		(drill 0.1)
		(layers "F.Cu" "B.Cu")
		(remove_unused_layers yes)
		(keep_end_layers yes)
		(zone_layer_connections "In1.Cu" "In3.Cu" "In5.Cu" "In7.Cu" "In10.Cu")
		(net 1)
	)
	(via
		(at 243.498 100.510001)
		(size 0.45)
		(drill 0.1)
		(layers "F.Cu" "B.Cu")
		(remove_unused_layers yes)
		(keep_end_layers yes)
		(zone_layer_connections "In1.Cu" "In3.Cu" "In5.Cu" "In7.Cu" "In10.Cu")
		(net 1)
	)
	(via
		(at 187.5 148.5)
		(size 0.45)
		(drill 0.1)
		(layers "F.Cu" "B.Cu")
		(remove_unused_layers yes)
		(keep_end_layers yes)
		(zone_layer_connections "In1.Cu" "In3.Cu" "In5.Cu" "In7.Cu" "In10.Cu")
		(net 1)
	)
	(via
		(at 211.498 100.510001)
		(size 0.45)
		(drill 0.1)
		(layers "F.Cu" "B.Cu")
		(remove_unused_layers yes)
		(keep_end_layers yes)
		(zone_layer_connections "In1.Cu" "In3.Cu" "In5.Cu" "In7.Cu" "In10.Cu")
		(net 1)
	)
	(via
		(at 196.5 157.500001)
		(size 0.45)
		(drill 0.1)
		(layers "F.Cu" "B.Cu")
		(remove_unused_layers yes)
		(keep_end_layers yes)
		(zone_layer_connections "In1.Cu" "In3.Cu" "In5.Cu" "In7.Cu" "In10.Cu")
		(net 1)
	)
	(via
		(at 204.875 164.4)
		(size 0.45)
		(drill 0.1)
		(layers "F.Cu" "B.Cu")
		(remove_unused_layers yes)
		(keep_end_layers yes)
		(zone_layer_connections "In1.Cu" "In3.Cu" "In5.Cu" "In7.Cu" "In10.Cu")
		(net 1)
	)
	(via
		(at 192.298 100.510001)
		(size 0.45)
		(drill 0.1)
		(layers "F.Cu" "B.Cu")
		(remove_unused_layers yes)
		(keep_end_layers yes)
		(zone_layer_connections "In1.Cu" "In3.Cu" "In5.Cu" "In7.Cu" "In10.Cu")
		(net 1)
	)
	(via
		(at 226.685 187.73)
		(size 0.45)
		(drill 0.1)
		(layers "F.Cu" "B.Cu")
		(remove_unused_layers yes)
		(keep_end_layers yes)
		(zone_layer_connections "In1.Cu" "In3.Cu" "In5.Cu" "In7.Cu" "In10.Cu")
		(net 1)
	)
	(via
		(at 213.585 181.285)
		(size 0.45)
		(drill 0.1)
		(layers "F.Cu" "B.Cu")
		(remove_unused_layers yes)
		(keep_end_layers yes)
		(zone_layer_connections "In1.Cu" "In3.Cu" "In5.Cu" "In7.Cu" "In10.Cu")
		(net 1)
	)
	(via
		(at 229.222 148.85)
		(size 0.45)
		(drill 0.1)
		(layers "F.Cu" "B.Cu")
		(remove_unused_layers yes)
		(keep_end_layers yes)
		(zone_layer_connections "In1.Cu" "In3.Cu" "In5.Cu" "In7.Cu" "In10.Cu")
		(net 1)
	)
	(via
		(at 240.7795 137.102499)
		(size 0.45)
		(drill 0.1)
		(layers "F.Cu" "B.Cu")
		(remove_unused_layers yes)
		(keep_end_layers yes)
		(zone_layer_connections "In1.Cu" "In3.Cu" "In5.Cu" "In7.Cu" "In10.Cu")
		(net 1)
	)
	(via
		(at 175.5 160.5)
		(size 0.45)
		(drill 0.1)
		(layers "F.Cu" "B.Cu")
		(remove_unused_layers yes)
		(keep_end_layers yes)
		(zone_layer_connections "In1.Cu" "In3.Cu" "In5.Cu" "In7.Cu" "In10.Cu")
		(net 1)
	)
	(via
		(at 254.7 128.225)
		(size 0.45)
		(drill 0.1)
		(layers "F.Cu" "B.Cu")
		(remove_unused_layers yes)
		(keep_end_layers yes)
		(zone_layer_connections "In1.Cu" "In3.Cu" "In5.Cu" "In7.Cu" "In10.Cu")
		(net 1)
	)
	(via
		(at 259.724499 155.649)
		(size 0.45)
		(drill 0.1)
		(layers "F.Cu" "B.Cu")
		(remove_unused_layers yes)
		(keep_end_layers yes)
		(zone_layer_connections "In1.Cu" "In3.Cu" "In4.Cu" "In5.Cu" "In6.Cu" "In7.Cu"
			"In10.Cu"
		)
		(net 1)
	)
	(via
		(at 240.7795 146.1005)
		(size 0.45)
		(drill 0.1)
		(layers "F.Cu" "B.Cu")
		(remove_unused_layers yes)
		(keep_end_layers yes)
		(zone_layer_connections "In1.Cu" "In3.Cu" "In5.Cu" "In7.Cu" "In10.Cu")
		(net 1)
	)
	(via
		(at 122.7 164.75)
		(size 0.45)
		(drill 0.1)
		(layers "F.Cu" "B.Cu")
		(remove_unused_layers yes)
		(keep_end_layers yes)
		(zone_layer_connections "In1.Cu" "In3.Cu" "In5.Cu" "In7.Cu" "In10.Cu")
		(net 1)
	)
	(via
		(at 195.5 158.5)
		(size 0.45)
		(drill 0.1)
		(layers "F.Cu" "B.Cu")
		(remove_unused_layers yes)
		(keep_end_layers yes)
		(zone_layer_connections "In1.Cu" "In3.Cu" "In5.Cu" "In7.Cu" "In10.Cu")
		(net 1)
	)
	(via
		(at 213.585 170.535)
		(size 0.45)
		(drill 0.1)
		(layers "F.Cu" "B.Cu")
		(remove_unused_layers yes)
		(keep_end_layers yes)
		(zone_layer_connections "In1.Cu" "In3.Cu" "In5.Cu" "In7.Cu" "In10.Cu")
		(net 1)
	)
	(via
		(at 210.735 182.385)
		(size 0.45)
		(drill 0.1)
		(layers "F.Cu" "B.Cu")
		(remove_unused_layers yes)
		(keep_end_layers yes)
		(free yes)
		(zone_layer_connections "In1.Cu" "In3.Cu" "In5.Cu" "In7.Cu" "In10.Cu")
		(net 1)
	)
	(via
		(at 185.5 150.5)
		(size 0.45)
		(drill 0.1)
		(layers "F.Cu" "B.Cu")
		(remove_unused_layers yes)
		(keep_end_layers yes)
		(zone_layer_connections "In1.Cu" "In3.Cu" "In5.Cu" "In7.Cu" "In10.Cu")
		(net 1)
	)
	(via
		(at 239.1 120.94)
		(size 0.45)
		(drill 0.1)
		(layers "F.Cu" "B.Cu")
		(remove_unused_layers yes)
		(keep_end_layers yes)
		(zone_layer_connections "In1.Cu" "In3.Cu" "In5.Cu" "In7.Cu" "In10.Cu")
		(net 1)
	)
	(via
		(at 256.298 100.510001)
		(size 0.45)
		(drill 0.1)
		(layers "F.Cu" "B.Cu")
		(remove_unused_layers yes)
		(keep_end_layers yes)
		(zone_layer_connections "In1.Cu" "In3.Cu" "In5.Cu" "In7.Cu" "In10.Cu")
		(net 1)
	)
	(via
		(at 199.75 189.46)
		(size 0.45)
		(drill 0.1)
		(layers "F.Cu" "B.Cu")
		(remove_unused_layers yes)
		(keep_end_layers yes)
		(zone_layer_connections "In1.Cu" "In3.Cu" "In5.Cu" "In7.Cu" "In10.Cu")
		(net 1)
	)
	(via
		(at 237.025999 164.3995)
		(size 0.45)
		(drill 0.1)
		(layers "F.Cu" "B.Cu")
		(remove_unused_layers yes)
		(keep_end_layers yes)
		(zone_layer_connections "In1.Cu" "In3.Cu" "In5.Cu" "In7.Cu" "In10.Cu")
		(net 1)
	)
	(via
		(at 146.4 155.95)
		(size 0.45)
		(drill 0.1)
		(layers "F.Cu" "B.Cu")
		(remove_unused_layers yes)
		(keep_end_layers yes)
		(zone_layer_connections "In1.Cu" "In3.Cu" "In5.Cu" "In7.Cu" "In10.Cu")
		(net 1)
	)
	(via
		(at 187.5 150.5)
		(size 0.45)
		(drill 0.1)
		(layers "F.Cu" "B.Cu")
		(remove_unused_layers yes)
		(keep_end_layers yes)
		(zone_layer_connections "In1.Cu" "In3.Cu" "In5.Cu" "In7.Cu" "In10.Cu")
		(net 1)
	)
	(via
		(at 158.31 158.1)
		(size 0.45)
		(drill 0.1)
		(layers "F.Cu" "B.Cu")
		(remove_unused_layers yes)
		(keep_end_layers yes)
		(zone_layer_connections "In1.Cu" "In3.Cu" "In5.Cu" "In7.Cu" "In10.Cu")
		(net 1)
	)
	(via
		(at 116.435 116.3)
		(size 0.45)
		(drill 0.1)
		(layers "F.Cu" "B.Cu")
		(remove_unused_layers yes)
		(keep_end_layers yes)
		(zone_layer_connections "In1.Cu" "In3.Cu" "In5.Cu" "In7.Cu" "In10.Cu")
		(net 1)
	)
	(via
		(at 251.224499 160.249)
		(size 0.45)
		(drill 0.1)
		(layers "F.Cu" "B.Cu")
		(remove_unused_layers yes)
		(keep_end_layers yes)
		(zone_layer_connections "In1.Cu" "In2.Cu" "In3.Cu" "In5.Cu" "In6.Cu" "In7.Cu"
			"In10.Cu"
		)
		(net 1)
	)
	(via
		(at 154.3 167.57)
		(size 0.45)
		(drill 0.1)
		(layers "F.Cu" "B.Cu")
		(remove_unused_layers yes)
		(keep_end_layers yes)
		(zone_layer_connections "In1.Cu" "In3.Cu" "In5.Cu" "In7.Cu" "In10.Cu")
		(net 1)
	)
	(via
		(at 210.735 188.835)
		(size 0.45)
		(drill 0.1)
		(layers "F.Cu" "B.Cu")
		(remove_unused_layers yes)
		(keep_end_layers yes)
		(zone_layer_connections "In1.Cu" "In3.Cu" "In5.Cu" "In7.Cu" "In10.Cu")
		(net 1)
	)
	(via
		(at 224.298 100.510001)
		(size 0.45)
		(drill 0.1)
		(layers "F.Cu" "B.Cu")
		(remove_unused_layers yes)
		(keep_end_layers yes)
		(zone_layer_connections "In1.Cu" "In3.Cu" "In5.Cu" "In7.Cu" "In10.Cu")
		(net 1)
	)
	(via
		(at 198.5 157.5)
		(size 0.45)
		(drill 0.1)
		(layers "F.Cu" "B.Cu")
		(remove_unused_layers yes)
		(keep_end_layers yes)
		(zone_layer_connections "In1.Cu" "In3.Cu" "In5.Cu" "In7.Cu" "In10.Cu")
		(net 1)
	)
	(via
		(at 193.500001 151.5)
		(size 0.45)
		(drill 0.1)
		(layers "F.Cu" "B.Cu")
		(remove_unused_layers yes)
		(keep_end_layers yes)
		(zone_layer_connections "In1.Cu" "In3.Cu" "In5.Cu" "In7.Cu" "In10.Cu")
		(net 1)
	)
	(via
		(at 142.25 155.9)
		(size 0.45)
		(drill 0.1)
		(layers "F.Cu" "B.Cu")
		(remove_unused_layers yes)
		(keep_end_layers yes)
		(zone_layer_connections "In1.Cu" "In3.Cu" "In5.Cu" "In7.Cu" "In10.Cu")
		(net 1)
	)
	(via
		(at 229.551 109.446)
		(size 0.45)
		(drill 0.1)
		(layers "F.Cu" "B.Cu")
		(remove_unused_layers yes)
		(keep_end_layers yes)
		(zone_layer_connections "In1.Cu" "In3.Cu" "In5.Cu" "In7.Cu" "In10.Cu")
		(net 1)
	)
	(via
		(at 184.5 141.5)
		(size 0.45)
		(drill 0.1)
		(layers "F.Cu" "B.Cu")
		(remove_unused_layers yes)
		(keep_end_layers yes)
		(zone_layer_connections "In1.Cu" "In3.Cu" "In5.Cu" "In7.Cu" "In10.Cu")
		(net 1)
	)
	(via
		(at 263.924499 182.27)
		(size 0.45)
		(drill 0.1)
		(layers "F.Cu" "B.Cu")
		(remove_unused_layers yes)
		(keep_end_layers yes)
		(zone_layer_connections "In1.Cu" "In3.Cu" "In5.Cu" "In6.Cu" "In7.Cu" "In10.Cu")
		(net 1)
	)
	(via
		(at 252.75 121.3)
		(size 0.45)
		(drill 0.1)
		(layers "F.Cu" "B.Cu")
		(net 1)
	)
	(via
		(at 109.0866 100.498601)
		(size 0.45)
		(drill 0.1)
		(layers "F.Cu" "B.Cu")
		(remove_unused_layers yes)
		(keep_end_layers yes)
		(zone_layer_connections "In1.Cu" "In3.Cu" "In5.Cu" "In7.Cu" "In10.Cu")
		(net 1)
	)
	(via
		(at 256.4785 154.448)
		(size 0.45)
		(drill 0.1)
		(layers "F.Cu" "B.Cu")
		(remove_unused_layers yes)
		(keep_end_layers yes)
		(zone_layer_connections "In1.Cu" "In2.Cu" "In3.Cu" "In4.Cu" "In5.Cu" "In6.Cu"
			"In7.Cu" "In10.Cu"
		)
		(net 1)
	)
	(via
		(at 240.05 118.18)
		(size 0.45)
		(drill 0.1)
		(layers "F.Cu" "B.Cu")
		(remove_unused_layers yes)
		(keep_end_layers yes)
		(zone_layer_connections "In1.Cu" "In3.Cu" "In5.Cu" "In7.Cu" "In10.Cu")
		(net 1)
	)
	(via
		(at 212.485 183.31)
		(size 0.45)
		(drill 0.1)
		(layers "F.Cu" "B.Cu")
		(remove_unused_layers yes)
		(keep_end_layers yes)
		(zone_layer_connections "In1.Cu" "In3.Cu" "In5.Cu" "In7.Cu" "In10.Cu")
		(net 1)
	)
	(via
		(at 263.424499 175.699)
		(size 0.45)
		(drill 0.1)
		(layers "F.Cu" "B.Cu")
		(remove_unused_layers yes)
		(keep_end_layers yes)
		(zone_layer_connections "In1.Cu" "In3.Cu" "In5.Cu" "In6.Cu" "In7.Cu" "In10.Cu")
		(net 1)
	)
	(via
		(at 163.51 159.799999)
		(size 0.45)
		(drill 0.1)
		(layers "F.Cu" "B.Cu")
		(remove_unused_layers yes)
		(keep_end_layers yes)
		(zone_layer_connections "In1.Cu" "In3.Cu" "In5.Cu" "In7.Cu" "In10.Cu")
		(net 1)
	)
	(via
		(at 122.75 179.727)
		(size 0.45)
		(drill 0.1)
		(layers "F.Cu" "B.Cu")
		(remove_unused_layers yes)
		(keep_end_layers yes)
		(zone_layer_connections "In1.Cu" "In3.Cu" "In5.Cu" "In7.Cu" "In10.Cu")
		(net 1)
	)
	(via
		(at 220.725 155.55)
		(size 0.45)
		(drill 0.1)
		(layers "F.Cu" "B.Cu")
		(remove_unused_layers yes)
		(keep_end_layers yes)
		(zone_layer_connections "In1.Cu" "In3.Cu" "In5.Cu" "In7.Cu" "In10.Cu")
		(net 1)
	)
	(via
		(at 194.7 109.446)
		(size 0.45)
		(drill 0.1)
		(layers "F.Cu" "B.Cu")
		(remove_unused_layers yes)
		(keep_end_layers yes)
		(zone_layer_connections "In1.Cu" "In3.Cu" "In5.Cu" "In7.Cu" "In10.Cu")
		(net 1)
	)
	(via
		(at 105.824499 180.649)
		(size 0.45)
		(drill 0.1)
		(layers "F.Cu" "B.Cu")
		(remove_unused_layers yes)
		(keep_end_layers yes)
		(zone_layer_connections "In1.Cu" "In3.Cu" "In5.Cu" "In7.Cu" "In10.Cu")
		(net 1)
	)
	(via
		(at 120.096 174.922)
		(size 0.45)
		(drill 0.1)
		(layers "F.Cu" "B.Cu")
		(remove_unused_layers yes)
		(keep_end_layers yes)
		(zone_layer_connections "In1.Cu" "In3.Cu" "In5.Cu" "In7.Cu" "In10.Cu")
		(net 1)
	)
	(via
		(at 249.898 100.510001)
		(size 0.45)
		(drill 0.1)
		(layers "F.Cu" "B.Cu")
		(remove_unused_layers yes)
		(keep_end_layers yes)
		(zone_layer_connections "In1.Cu" "In3.Cu" "In5.Cu" "In7.Cu" "In10.Cu")
		(net 1)
	)
	(via
		(at 254.48 113.395)
		(size 0.45)
		(drill 0.1)
		(layers "F.Cu" "B.Cu")
		(remove_unused_layers yes)
		(keep_end_layers yes)
		(zone_layer_connections "In1.Cu" "In3.Cu" "In5.Cu" "In7.Cu" "In10.Cu")
		(net 1)
	)
	(via
		(at 160.702 109.446)
		(size 0.45)
		(drill 0.1)
		(layers "F.Cu" "B.Cu")
		(remove_unused_layers yes)
		(keep_end_layers yes)
		(zone_layer_connections "In1.Cu" "In3.Cu" "In5.Cu" "In7.Cu" "In10.Cu")
		(net 1)
	)
	(via
		(at 107.33 147.56)
		(size 0.45)
		(drill 0.1)
		(layers "F.Cu" "B.Cu")
		(remove_unused_layers yes)
		(keep_end_layers yes)
		(zone_layer_connections "In1.Cu" "In3.Cu" "In5.Cu" "In7.Cu" "In10.Cu")
		(net 1)
	)
	(via
		(at 222.635 174.81)
		(size 0.45)
		(drill 0.1)
		(layers "F.Cu" "B.Cu")
		(remove_unused_layers yes)
		(keep_end_layers yes)
		(zone_layer_connections "In1.Cu" "In3.Cu" "In5.Cu" "In7.Cu" "In10.Cu")
		(net 1)
	)
	(via
		(at 134.173 157.599)
		(size 0.45)
		(drill 0.1)
		(layers "F.Cu" "B.Cu")
		(remove_unused_layers yes)
		(keep_end_layers yes)
		(zone_layer_connections "In1.Cu" "In3.Cu" "In5.Cu" "In7.Cu" "In10.Cu")
		(net 1)
	)
	(via
		(at 178.5 154.5)
		(size 0.45)
		(drill 0.1)
		(layers "F.Cu" "B.Cu")
		(remove_unused_layers yes)
		(keep_end_layers yes)
		(zone_layer_connections "In1.Cu" "In3.Cu" "In5.Cu" "In7.Cu" "In10.Cu")
		(net 1)
	)
	(via
		(at 213.035 188.785)
		(size 0.45)
		(drill 0.1)
		(layers "F.Cu" "B.Cu")
		(remove_unused_layers yes)
		(keep_end_layers yes)
		(zone_layer_connections "In1.Cu" "In3.Cu" "In5.Cu" "In7.Cu" "In10.Cu")
		(net 1)
	)
	(via
		(at 224.2 155.95)
		(size 0.45)
		(drill 0.1)
		(layers "F.Cu" "B.Cu")
		(remove_unused_layers yes)
		(keep_end_layers yes)
		(zone_layer_connections "In1.Cu" "In3.Cu" "In5.Cu" "In7.Cu" "In10.Cu")
		(net 1)
	)
	(via
		(at 259.724499 153.649)
		(size 0.45)
		(drill 0.1)
		(layers "F.Cu" "B.Cu")
		(remove_unused_layers yes)
		(keep_end_layers yes)
		(zone_layer_connections "In1.Cu" "In3.Cu" "In4.Cu" "In5.Cu" "In6.Cu" "In7.Cu"
			"In10.Cu"
		)
		(net 1)
	)
	(via
		(at 160.2866 100.498601)
		(size 0.45)
		(drill 0.1)
		(layers "F.Cu" "B.Cu")
		(remove_unused_layers yes)
		(keep_end_layers yes)
		(zone_layer_connections "In1.Cu" "In3.Cu" "In5.Cu" "In7.Cu" "In10.Cu")
		(net 1)
	)
	(via
		(at 153.79 172.88)
		(size 0.45)
		(drill 0.1)
		(layers "F.Cu" "B.Cu")
		(remove_unused_layers yes)
		(keep_end_layers yes)
		(zone_layer_connections "In1.Cu" "In3.Cu" "In5.Cu" "In7.Cu" "In10.Cu")
		(net 1)
	)
	(via
		(at 246.698 100.510001)
		(size 0.45)
		(drill 0.1)
		(layers "F.Cu" "B.Cu")
		(remove_unused_layers yes)
		(keep_end_layers yes)
		(zone_layer_connections "In1.Cu" "In3.Cu" "In5.Cu" "In7.Cu" "In10.Cu")
		(net 1)
	)
	(via
		(at 147.214499 164.999)
		(size 0.45)
		(drill 0.1)
		(layers "F.Cu" "B.Cu")
		(remove_unused_layers yes)
		(keep_end_layers yes)
		(zone_layer_connections "In1.Cu" "In3.Cu" "In5.Cu" "In7.Cu" "In10.Cu")
		(net 1)
	)
	(via
		(at 256.894999 155.3005)
		(size 0.45)
		(drill 0.1)
		(layers "F.Cu" "B.Cu")
		(remove_unused_layers yes)
		(keep_end_layers yes)
		(zone_layer_connections "In1.Cu" "In2.Cu" "In3.Cu" "In4.Cu" "In5.Cu" "In6.Cu"
			"In7.Cu" "In10.Cu"
		)
		(net 1)
	)
	(via
		(at 196.499999 149.5)
		(size 0.45)
		(drill 0.1)
		(layers "F.Cu" "B.Cu")
		(remove_unused_layers yes)
		(keep_end_layers yes)
		(zone_layer_connections "In1.Cu" "In3.Cu" "In5.Cu" "In7.Cu" "In10.Cu")
		(net 1)
	)
	(via
		(at 251.524499 159.149)
		(size 0.45)
		(drill 0.1)
		(layers "F.Cu" "B.Cu")
		(remove_unused_layers yes)
		(keep_end_layers yes)
		(zone_layer_connections "In1.Cu" "In2.Cu" "In3.Cu" "In4.Cu" "In5.Cu" "In6.Cu"
			"In7.Cu" "In10.Cu"
		)
		(net 1)
	)
	(via
		(at 247.1245 146.0975)
		(size 0.45)
		(drill 0.1)
		(layers "F.Cu" "B.Cu")
		(remove_unused_layers yes)
		(keep_end_layers yes)
		(zone_layer_connections "In1.Cu" "In3.Cu" "In5.Cu" "In7.Cu" "In10.Cu")
		(net 1)
	)
	(via
		(at 193.5 154.5)
		(size 0.45)
		(drill 0.1)
		(layers "F.Cu" "B.Cu")
		(remove_unused_layers yes)
		(keep_end_layers yes)
		(zone_layer_connections "In1.Cu" "In3.Cu" "In5.Cu" "In7.Cu" "In10.Cu")
		(net 1)
	)
	(via
		(at 247.65 123.75)
		(size 0.45)
		(drill 0.1)
		(layers "F.Cu" "B.Cu")
		(net 1)
	)
	(via
		(at 134.675 181.5)
		(size 0.45)
		(drill 0.1)
		(layers "F.Cu" "B.Cu")
		(remove_unused_layers yes)
		(keep_end_layers yes)
		(zone_layer_connections "In1.Cu" "In3.Cu" "In5.Cu" "In7.Cu" "In10.Cu")
		(net 1)
	)
	(via
		(at 125.144 129.456)
		(size 0.45)
		(drill 0.1)
		(layers "F.Cu" "B.Cu")
		(remove_unused_layers yes)
		(keep_end_layers yes)
		(zone_layer_connections "In1.Cu" "In3.Cu" "In5.Cu" "In7.Cu" "In9.Cu" "In10.Cu")
		(net 1)
	)
	(via
		(at 178.1025 194.849501)
		(size 0.45)
		(drill 0.1)
		(layers "F.Cu" "B.Cu")
		(remove_unused_layers yes)
		(keep_end_layers yes)
		(zone_layer_connections "In1.Cu" "In3.Cu" "In5.Cu" "In7.Cu" "In10.Cu")
		(net 1)
	)
	(via
		(at 201.898 100.510001)
		(size 0.45)
		(drill 0.1)
		(layers "F.Cu" "B.Cu")
		(remove_unused_layers yes)
		(keep_end_layers yes)
		(zone_layer_connections "In1.Cu" "In3.Cu" "In5.Cu" "In7.Cu" "In10.Cu")
		(net 1)
	)
	(via
		(at 186.5 162.5)
		(size 0.45)
		(drill 0.1)
		(layers "F.Cu" "B.Cu")
		(remove_unused_layers yes)
		(keep_end_layers yes)
		(zone_layer_connections "In1.Cu" "In3.Cu" "In5.Cu" "In7.Cu" "In10.Cu")
		(net 1)
	)
	(via
		(at 229.222 146.85)
		(size 0.45)
		(drill 0.1)
		(layers "F.Cu" "B.Cu")
		(remove_unused_layers yes)
		(keep_end_layers yes)
		(zone_layer_connections "In1.Cu" "In3.Cu" "In5.Cu" "In7.Cu" "In10.Cu")
		(net 1)
	)
	(via
		(at 128.826 186.1375)
		(size 0.45)
		(drill 0.1)
		(layers "F.Cu" "B.Cu")
		(remove_unused_layers yes)
		(keep_end_layers yes)
		(zone_layer_connections "In1.Cu" "In3.Cu" "In5.Cu" "In7.Cu" "In10.Cu")
		(net 1)
	)
	(via
		(at 176.5 162.5)
		(size 0.45)
		(drill 0.1)
		(layers "F.Cu" "B.Cu")
		(remove_unused_layers yes)
		(keep_end_layers yes)
		(zone_layer_connections "In1.Cu" "In3.Cu" "In5.Cu" "In7.Cu" "In10.Cu")
		(net 1)
	)
	(via
		(at 183.5 160.5)
		(size 0.45)
		(drill 0.1)
		(layers "F.Cu" "B.Cu")
		(remove_unused_layers yes)
		(keep_end_layers yes)
		(zone_layer_connections "In1.Cu" "In3.Cu" "In5.Cu" "In7.Cu" "In10.Cu")
		(net 1)
	)
	(via
		(at 211.7 104.848)
		(size 0.45)
		(drill 0.1)
		(layers "F.Cu" "B.Cu")
		(remove_unused_layers yes)
		(keep_end_layers yes)
		(zone_layer_connections "In1.Cu" "In3.Cu" "In5.Cu" "In7.Cu" "In10.Cu")
		(net 1)
	)
	(via
		(at 263.924499 137.549)
		(size 0.45)
		(drill 0.1)
		(layers "F.Cu" "B.Cu")
		(remove_unused_layers yes)
		(keep_end_layers yes)
		(zone_layer_connections "In1.Cu" "In3.Cu" "In5.Cu" "In7.Cu" "In10.Cu")
		(net 1)
	)
	(via
		(at 152.25 179.75)
		(size 0.45)
		(drill 0.1)
		(layers "F.Cu" "B.Cu")
		(remove_unused_layers yes)
		(keep_end_layers yes)
		(zone_layer_connections "In1.Cu" "In3.Cu" "In5.Cu" "In7.Cu" "In10.Cu")
		(net 1)
	)
	(via
		(at 257.25 115.325)
		(size 0.45)
		(drill 0.1)
		(layers "F.Cu" "B.Cu")
		(remove_unused_layers yes)
		(keep_end_layers yes)
		(zone_layer_connections "In1.Cu" "In3.Cu" "In5.Cu" "In7.Cu" "In10.Cu")
		(net 1)
	)
	(via
		(at 257.121999 171.3515)
		(size 0.45)
		(drill 0.1)
		(layers "F.Cu" "B.Cu")
		(remove_unused_layers yes)
		(keep_end_layers yes)
		(zone_layer_connections "In1.Cu" "In2.Cu" "In3.Cu" "In4.Cu" "In5.Cu" "In6.Cu"
			"In7.Cu" "In10.Cu"
		)
		(net 1)
	)
	(via
		(at 244.25 187.404)
		(size 0.45)
		(drill 0.1)
		(layers "F.Cu" "B.Cu")
		(remove_unused_layers yes)
		(keep_end_layers yes)
		(zone_layer_connections "In1.Cu" "In3.Cu" "In5.Cu" "In7.Cu" "In10.Cu")
		(net 1)
	)
	(via
		(at 224.685 171.535)
		(size 0.45)
		(drill 0.1)
		(layers "F.Cu" "B.Cu")
		(remove_unused_layers yes)
		(keep_end_layers yes)
		(zone_layer_connections "In1.Cu" "In3.Cu" "In5.Cu" "In7.Cu" "In10.Cu")
		(net 1)
	)
	(via
		(at 185.5005 164.4995)
		(size 0.45)
		(drill 0.1)
		(layers "F.Cu" "B.Cu")
		(remove_unused_layers yes)
		(keep_end_layers yes)
		(zone_layer_connections "In1.Cu" "In3.Cu" "In5.Cu" "In7.Cu" "In10.Cu")
		(net 1)
	)
	(via
		(at 223.51 181.235)
		(size 0.45)
		(drill 0.1)
		(layers "F.Cu" "B.Cu")
		(remove_unused_layers yes)
		(keep_end_layers yes)
		(zone_layer_connections "In1.Cu" "In3.Cu" "In5.Cu" "In7.Cu" "In10.Cu")
		(net 1)
	)
	(via
		(at 125.902 182.879)
		(size 0.45)
		(drill 0.1)
		(layers "F.Cu" "B.Cu")
		(remove_unused_layers yes)
		(keep_end_layers yes)
		(zone_layer_connections "In1.Cu" "In3.Cu" "In5.Cu" "In7.Cu" "In10.Cu")
		(net 1)
	)
	(via
		(at 177.5 161.5)
		(size 0.45)
		(drill 0.1)
		(layers "F.Cu" "B.Cu")
		(remove_unused_layers yes)
		(keep_end_layers yes)
		(zone_layer_connections "In1.Cu" "In3.Cu" "In5.Cu" "In7.Cu" "In10.Cu")
		(net 1)
	)
	(via
		(at 123.9114 122.8114)
		(size 0.45)
		(drill 0.1)
		(layers "F.Cu" "B.Cu")
		(remove_unused_layers yes)
		(keep_end_layers yes)
		(zone_layer_connections "In1.Cu" "In3.Cu" "In5.Cu" "In7.Cu" "In9.Cu" "In10.Cu")
		(net 1)
	)
	(via
		(at 223.125 158.2)
		(size 0.45)
		(drill 0.1)
		(layers "F.Cu" "B.Cu")
		(remove_unused_layers yes)
		(keep_end_layers yes)
		(zone_layer_connections "In1.Cu" "In3.Cu" "In5.Cu" "In7.Cu" "In10.Cu")
		(net 1)
	)
	(via
		(at 254.7 130.225)
		(size 0.45)
		(drill 0.1)
		(layers "F.Cu" "B.Cu")
		(remove_unused_layers yes)
		(keep_end_layers yes)
		(zone_layer_connections "In1.Cu" "In3.Cu" "In5.Cu" "In7.Cu" "In10.Cu")
		(net 1)
	)
	(via
		(at 224.385 187.78)
		(size 0.45)
		(drill 0.1)
		(layers "F.Cu" "B.Cu")
		(remove_unused_layers yes)
		(keep_end_layers yes)
		(zone_layer_connections "In1.Cu" "In3.Cu" "In5.Cu" "In7.Cu" "In10.Cu")
		(net 1)
	)
	(via
		(at 114.030348 128.312)
		(size 0.45)
		(drill 0.1)
		(layers "F.Cu" "B.Cu")
		(remove_unused_layers yes)
		(keep_end_layers yes)
		(zone_layer_connections "In1.Cu" "In3.Cu" "In5.Cu" "In7.Cu" "In10.Cu")
		(net 1)
	)
	(via
		(at 145.635 142.835)
		(size 0.45)
		(drill 0.1)
		(layers "F.Cu" "B.Cu")
		(remove_unused_layers yes)
		(keep_end_layers yes)
		(zone_layer_connections "In1.Cu" "In3.Cu" "In5.Cu" "In7.Cu" "In10.Cu")
		(net 1)
	)
	(via
		(at 134.874499 169.599)
		(size 0.45)
		(drill 0.1)
		(layers "F.Cu" "B.Cu")
		(remove_unused_layers yes)
		(keep_end_layers yes)
		(zone_layer_connections "In1.Cu" "In3.Cu" "In5.Cu" "In7.Cu" "In10.Cu")
		(net 1)
	)
	(via
		(at 247.401 104.848)
		(size 0.45)
		(drill 0.1)
		(layers "F.Cu" "B.Cu")
		(remove_unused_layers yes)
		(keep_end_layers yes)
		(zone_layer_connections "In1.Cu" "In3.Cu" "In5.Cu" "In7.Cu" "In10.Cu")
		(net 1)
	)
	(via
		(at 262.08 115.48)
		(size 0.45)
		(drill 0.1)
		(layers "F.Cu" "B.Cu")
		(remove_unused_layers yes)
		(keep_end_layers yes)
		(zone_layer_connections "In1.Cu" "In3.Cu" "In5.Cu" "In7.Cu" "In10.Cu")
		(net 1)
	)
	(via
		(at 252.224499 151.799)
		(size 0.45)
		(drill 0.1)
		(layers "F.Cu" "B.Cu")
		(remove_unused_layers yes)
		(keep_end_layers yes)
		(zone_layer_connections "In1.Cu" "In2.Cu" "In3.Cu" "In4.Cu" "In5.Cu" "In6.Cu"
			"In7.Cu" "In10.Cu"
		)
		(net 1)
	)
	(via
		(at 105.95 166.27)
		(size 0.45)
		(drill 0.1)
		(layers "F.Cu" "B.Cu")
		(remove_unused_layers yes)
		(keep_end_layers yes)
		(zone_layer_connections "In1.Cu" "In3.Cu" "In5.Cu" "In7.Cu" "In10.Cu")
		(net 1)
	)
	(via
		(at 141.15 104.848)
		(size 0.45)
		(drill 0.1)
		(layers "F.Cu" "B.Cu")
		(remove_unused_layers yes)
		(keep_end_layers yes)
		(zone_layer_connections "In1.Cu" "In3.Cu" "In5.Cu" "In7.Cu" "In10.Cu")
		(net 1)
	)
	(via
		(at 254.624499 151.149)
		(size 0.45)
		(drill 0.1)
		(layers "F.Cu" "B.Cu")
		(remove_unused_layers yes)
		(keep_end_layers yes)
		(zone_layer_connections "In1.Cu" "In3.Cu" "In4.Cu" "In5.Cu" "In6.Cu" "In7.Cu"
			"In10.Cu"
		)
		(net 1)
	)
	(via
		(at 154.3995 194.749501)
		(size 0.45)
		(drill 0.1)
		(layers "F.Cu" "B.Cu")
		(remove_unused_layers yes)
		(keep_end_layers yes)
		(zone_layer_connections "In1.Cu" "In3.Cu" "In5.Cu" "In7.Cu" "In10.Cu")
		(net 1)
	)
	(via
		(at 149.6995 194.749501)
		(size 0.45)
		(drill 0.1)
		(layers "F.Cu" "B.Cu")
		(remove_unused_layers yes)
		(keep_end_layers yes)
		(zone_layer_connections "In1.Cu" "In3.Cu" "In5.Cu" "In7.Cu" "In10.Cu")
		(net 1)
	)
	(via
		(at 237.276998 171.197501)
		(size 0.45)
		(drill 0.1)
		(layers "F.Cu" "B.Cu")
		(remove_unused_layers yes)
		(keep_end_layers yes)
		(zone_layer_connections "In1.Cu" "In3.Cu" "In5.Cu" "In7.Cu" "In10.Cu")
		(net 1)
	)
	(via
		(at 125.16 122.124)
		(size 0.45)
		(drill 0.1)
		(layers "F.Cu" "B.Cu")
		(remove_unused_layers yes)
		(keep_end_layers yes)
		(zone_layer_connections "In1.Cu" "In3.Cu" "In5.Cu" "In7.Cu" "In9.Cu" "In10.Cu")
		(net 1)
	)
	(via
		(at 192.5 148.5)
		(size 0.45)
		(drill 0.1)
		(layers "F.Cu" "B.Cu")
		(remove_unused_layers yes)
		(keep_end_layers yes)
		(zone_layer_connections "In1.Cu" "In3.Cu" "In5.Cu" "In7.Cu" "In10.Cu")
		(net 1)
	)
	(via
		(at 216.801 109.446)
		(size 0.45)
		(drill 0.1)
		(layers "F.Cu" "B.Cu")
		(remove_unused_layers yes)
		(keep_end_layers yes)
		(zone_layer_connections "In1.Cu" "In3.Cu" "In5.Cu" "In7.Cu" "In10.Cu")
		(net 1)
	)
	(via
		(at 123.9204 104.7884)
		(size 0.45)
		(drill 0.1)
		(layers "F.Cu" "B.Cu")
		(remove_unused_layers yes)
		(keep_end_layers yes)
		(zone_layer_connections "In1.Cu" "In3.Cu" "In5.Cu" "In7.Cu" "In10.Cu")
		(net 1)
	)
	(via
		(at 212.025 155.625)
		(size 0.45)
		(drill 0.1)
		(layers "F.Cu" "B.Cu")
		(remove_unused_layers yes)
		(keep_end_layers yes)
		(zone_layer_connections "In1.Cu" "In3.Cu" "In5.Cu" "In7.Cu" "In10.Cu")
		(net 1)
	)
	(via
		(at 179.4 109.446)
		(size 0.45)
		(drill 0.1)
		(layers "F.Cu" "B.Cu")
		(remove_unused_layers yes)
		(keep_end_layers yes)
		(zone_layer_connections "In1.Cu" "In3.Cu" "In5.Cu" "In7.Cu" "In10.Cu")
		(net 1)
	)
	(via
		(at 226.585 176.885)
		(size 0.45)
		(drill 0.1)
		(layers "F.Cu" "B.Cu")
		(remove_unused_layers yes)
		(keep_end_layers yes)
		(zone_layer_connections "In1.Cu" "In3.Cu" "In5.Cu" "In7.Cu" "In10.Cu")
		(net 1)
	)
	(via
		(at 152.544499 194.249501)
		(size 0.45)
		(drill 0.1)
		(layers "F.Cu" "B.Cu")
		(remove_unused_layers yes)
		(keep_end_layers yes)
		(zone_layer_connections "In1.Cu" "In3.Cu" "In5.Cu" "In7.Cu" "In10.Cu")
		(net 1)
	)
	(via
		(at 178.5 158.5)
		(size 0.45)
		(drill 0.1)
		(layers "F.Cu" "B.Cu")
		(remove_unused_layers yes)
		(keep_end_layers yes)
		(zone_layer_connections "In1.Cu" "In3.Cu" "In5.Cu" "In7.Cu" "In10.Cu")
		(net 1)
	)
	(via
		(at 256.921999 172.7515)
		(size 0.45)
		(drill 0.1)
		(layers "F.Cu" "B.Cu")
		(remove_unused_layers yes)
		(keep_end_layers yes)
		(zone_layer_connections "In1.Cu" "In2.Cu" "In3.Cu" "In4.Cu" "In5.Cu" "In6.Cu"
			"In7.Cu" "In10.Cu"
		)
		(net 1)
	)
	(via
		(at 211.935 182.235)
		(size 0.45)
		(drill 0.1)
		(layers "F.Cu" "B.Cu")
		(remove_unused_layers yes)
		(keep_end_layers yes)
		(free yes)
		(zone_layer_connections "In1.Cu" "In3.Cu" "In5.Cu" "In7.Cu" "In10.Cu")
		(net 1)
	)
	(via
		(at 132.652 109.446)
		(size 0.45)
		(drill 0.1)
		(layers "F.Cu" "B.Cu")
		(remove_unused_layers yes)
		(keep_end_layers yes)
		(zone_layer_connections "In1.Cu" "In3.Cu" "In5.Cu" "In7.Cu" "In10.Cu")
		(net 1)
	)
	(via
		(at 185.898 100.510001)
		(size 0.45)
		(drill 0.1)
		(layers "F.Cu" "B.Cu")
		(remove_unused_layers yes)
		(keep_end_layers yes)
		(zone_layer_connections "In1.Cu" "In3.Cu" "In5.Cu" "In7.Cu" "In10.Cu")
		(net 1)
	)
	(via
		(at 247.904 145.1)
		(size 0.45)
		(drill 0.1)
		(layers "F.Cu" "B.Cu")
		(remove_unused_layers yes)
		(keep_end_layers yes)
		(zone_layer_connections "In1.Cu" "In3.Cu" "In5.Cu" "In7.Cu" "In10.Cu")
		(net 1)
	)
	(via
		(at 124.5616 149.0472)
		(size 0.45)
		(drill 0.1)
		(layers "F.Cu" "B.Cu")
		(remove_unused_layers yes)
		(keep_end_layers yes)
		(zone_layer_connections "In1.Cu" "In3.Cu" "In5.Cu" "In7.Cu" "In10.Cu")
		(net 1)
	)
	(via
		(at 261.71 189.46)
		(size 0.45)
		(drill 0.1)
		(layers "F.Cu" "B.Cu")
		(remove_unused_layers yes)
		(keep_end_layers yes)
		(zone_layer_connections "In1.Cu" "In3.Cu" "In5.Cu" "In7.Cu" "In10.Cu")
		(net 1)
	)
	(via
		(at 255.26 112.665)
		(size 0.45)
		(drill 0.1)
		(layers "F.Cu" "B.Cu")
		(remove_unused_layers yes)
		(keep_end_layers yes)
		(zone_layer_connections "In1.Cu" "In3.Cu" "In5.Cu" "In7.Cu" "In10.Cu")
		(net 1)
	)
	(via
		(at 182.698 100.510001)
		(size 0.45)
		(drill 0.1)
		(layers "F.Cu" "B.Cu")
		(remove_unused_layers yes)
		(keep_end_layers yes)
		(zone_layer_connections "In1.Cu" "In3.Cu" "In5.Cu" "In7.Cu" "In10.Cu")
		(net 1)
	)
	(via
		(at 256.651499 168.6)
		(size 0.45)
		(drill 0.1)
		(layers "F.Cu" "B.Cu")
		(remove_unused_layers yes)
		(keep_end_layers yes)
		(zone_layer_connections "In1.Cu" "In3.Cu" "In4.Cu" "In5.Cu" "In6.Cu" "In7.Cu"
			"In10.Cu"
		)
		(net 1)
	)
	(via
		(at 164.125 194.824501)
		(size 0.45)
		(drill 0.1)
		(layers "F.Cu" "B.Cu")
		(remove_unused_layers yes)
		(keep_end_layers yes)
		(zone_layer_connections "In1.Cu" "In3.Cu" "In5.Cu" "In7.Cu" "In10.Cu")
		(net 1)
	)
	(via
		(at 146.25 104.848)
		(size 0.45)
		(drill 0.1)
		(layers "F.Cu" "B.Cu")
		(remove_unused_layers yes)
		(keep_end_layers yes)
		(zone_layer_connections "In1.Cu" "In3.Cu" "In5.Cu" "In7.Cu" "In10.Cu")
		(net 1)
	)
	(via
		(at 135.824499 188.649)
		(size 0.45)
		(drill 0.1)
		(layers "F.Cu" "B.Cu")
		(remove_unused_layers yes)
		(keep_end_layers yes)
		(zone_layer_connections "In1.Cu" "In3.Cu" "In5.Cu" "In7.Cu" "In10.Cu")
		(net 1)
	)
	(via
		(at 195.5005 164.4995)
		(size 0.45)
		(drill 0.1)
		(layers "F.Cu" "B.Cu")
		(remove_unused_layers yes)
		(keep_end_layers yes)
		(zone_layer_connections "In1.Cu" "In3.Cu" "In5.Cu" "In7.Cu" "In10.Cu")
		(net 1)
	)
	(via
		(at 252.224499 150.499)
		(size 0.45)
		(drill 0.1)
		(layers "F.Cu" "B.Cu")
		(remove_unused_layers yes)
		(keep_end_layers yes)
		(zone_layer_connections "In1.Cu" "In3.Cu" "In5.Cu" "In6.Cu" "In7.Cu" "In10.Cu")
		(net 1)
	)
	(via
		(at 159.125 194.849501)
		(size 0.45)
		(drill 0.1)
		(layers "F.Cu" "B.Cu")
		(remove_unused_layers yes)
		(keep_end_layers yes)
		(zone_layer_connections "In1.Cu" "In3.Cu" "In5.Cu" "In7.Cu" "In10.Cu")
		(net 1)
	)
	(via
		(at 169.375 156.25)
		(size 0.45)
		(drill 0.1)
		(layers "F.Cu" "B.Cu")
		(remove_unused_layers yes)
		(keep_end_layers yes)
		(zone_layer_connections "In1.Cu" "In3.Cu" "In5.Cu" "In7.Cu" "In10.Cu")
		(net 1)
	)
	(via
		(at 214.185 188.785)
		(size 0.45)
		(drill 0.1)
		(layers "F.Cu" "B.Cu")
		(remove_unused_layers yes)
		(keep_end_layers yes)
		(zone_layer_connections "In1.Cu" "In3.Cu" "In5.Cu" "In7.Cu" "In10.Cu")
		(net 1)
	)
	(via
		(at 251.085744 185.667621)
		(size 0.45)
		(drill 0.1)
		(layers "F.Cu" "B.Cu")
		(remove_unused_layers yes)
		(keep_end_layers yes)
		(zone_layer_connections "In1.Cu" "In3.Cu" "In5.Cu" "In7.Cu" "In10.Cu")
		(net 1)
	)
	(via
		(at 214.535 168.385)
		(size 0.45)
		(drill 0.1)
		(layers "F.Cu" "B.Cu")
		(remove_unused_layers yes)
		(keep_end_layers yes)
		(zone_layer_connections "In1.Cu" "In3.Cu" "In5.Cu" "In7.Cu" "In10.Cu")
		(net 1)
	)
	(via
		(at 253.85 106.25)
		(size 0.45)
		(drill 0.1)
		(layers "F.Cu" "B.Cu")
		(remove_unused_layers yes)
		(keep_end_layers yes)
		(zone_layer_connections "In1.Cu" "In3.Cu" "In5.Cu" "In7.Cu" "In10.Cu")
		(net 1)
	)
	(via
		(at 235.1 176.9)
		(size 0.45)
		(drill 0.1)
		(layers "F.Cu" "B.Cu")
		(remove_unused_layers yes)
		(keep_end_layers yes)
		(zone_layer_connections "In1.Cu" "In3.Cu" "In5.Cu" "In7.Cu" "In10.Cu")
		(net 1)
	)
	(via
		(at 206.725 155.65)
		(size 0.45)
		(drill 0.1)
		(layers "F.Cu" "B.Cu")
		(remove_unused_layers yes)
		(keep_end_layers yes)
		(zone_layer_connections "In1.Cu" "In3.Cu" "In5.Cu" "In7.Cu" "In10.Cu")
		(net 1)
	)
	(via
		(at 124.326 182.879)
		(size 0.45)
		(drill 0.1)
		(layers "F.Cu" "B.Cu")
		(remove_unused_layers yes)
		(keep_end_layers yes)
		(zone_layer_connections "In1.Cu" "In3.Cu" "In5.Cu" "In7.Cu" "In10.Cu")
		(net 1)
	)
	(via
		(at 184.5 149.5)
		(size 0.45)
		(drill 0.1)
		(layers "F.Cu" "B.Cu")
		(remove_unused_layers yes)
		(keep_end_layers yes)
		(zone_layer_connections "In1.Cu" "In3.Cu" "In5.Cu" "In7.Cu" "In10.Cu")
		(net 1)
	)
	(via
		(at 176.852 104.848)
		(size 0.45)
		(drill 0.1)
		(layers "F.Cu" "B.Cu")
		(remove_unused_layers yes)
		(keep_end_layers yes)
		(zone_layer_connections "In1.Cu" "In3.Cu" "In5.Cu" "In7.Cu" "In10.Cu")
		(net 1)
	)
	(via
		(at 232.1 176.6)
		(size 0.45)
		(drill 0.1)
		(layers "F.Cu" "B.Cu")
		(remove_unused_layers yes)
		(keep_end_layers yes)
		(zone_layer_connections "In1.Cu" "In3.Cu" "In5.Cu" "In7.Cu" "In10.Cu")
		(net 1)
	)
	(via
		(at 182.5 162.5)
		(size 0.45)
		(drill 0.1)
		(layers "F.Cu" "B.Cu")
		(remove_unused_layers yes)
		(keep_end_layers yes)
		(zone_layer_connections "In1.Cu" "In3.Cu" "In5.Cu" "In7.Cu" "In10.Cu")
		(net 1)
	)
	(via
		(at 180.5 163.5)
		(size 0.45)
		(drill 0.1)
		(layers "F.Cu" "B.Cu")
		(remove_unused_layers yes)
		(keep_end_layers yes)
		(zone_layer_connections "In1.Cu" "In3.Cu" "In5.Cu" "In7.Cu" "In10.Cu")
		(net 1)
	)
	(via
		(at 100.624499 100.549)
		(size 0.45)
		(drill 0.1)
		(layers "F.Cu" "B.Cu")
		(remove_unused_layers yes)
		(keep_end_layers yes)
		(zone_layer_connections "In1.Cu" "In3.Cu" "In5.Cu" "In7.Cu" "In10.Cu")
		(net 1)
	)
	(via
		(at 214.075 180.15)
		(size 0.45)
		(drill 0.1)
		(layers "F.Cu" "B.Cu")
		(remove_unused_layers yes)
		(keep_end_layers yes)
		(zone_layer_connections "In1.Cu" "In3.Cu" "In5.Cu" "In7.Cu" "In10.Cu")
		(net 1)
	)
	(via
		(at 260.62 114.06)
		(size 0.45)
		(drill 0.1)
		(layers "F.Cu" "B.Cu")
		(remove_unused_layers yes)
		(keep_end_layers yes)
		(zone_layer_connections "In1.Cu" "In3.Cu" "In5.Cu" "In7.Cu" "In10.Cu")
		(net 1)
	)
	(via
		(at 216.899 150.609501)
		(size 0.45)
		(drill 0.1)
		(layers "F.Cu" "B.Cu")
		(remove_unused_layers yes)
		(keep_end_layers yes)
		(zone_layer_connections "In1.Cu" "In3.Cu" "In5.Cu" "In7.Cu" "In10.Cu")
		(net 1)
	)
	(via
		(at 245.7 104.848)
		(size 0.45)
		(drill 0.1)
		(layers "F.Cu" "B.Cu")
		(remove_unused_layers yes)
		(keep_end_layers yes)
		(zone_layer_connections "In1.Cu" "In3.Cu" "In5.Cu" "In7.Cu" "In10.Cu")
		(net 1)
	)
	(via
		(at 218.645 182.64)
		(size 0.45)
		(drill 0.1)
		(layers "F.Cu" "B.Cu")
		(remove_unused_layers yes)
		(keep_end_layers yes)
		(zone_layer_connections "In1.Cu" "In3.Cu" "In5.Cu" "In7.Cu" "In10.Cu")
		(net 1)
	)
	(via
		(at 199.5 156.5)
		(size 0.45)
		(drill 0.1)
		(layers "F.Cu" "B.Cu")
		(remove_unused_layers yes)
		(keep_end_layers yes)
		(zone_layer_connections "In1.Cu" "In3.Cu" "In5.Cu" "In7.Cu" "In10.Cu")
		(net 1)
	)
	(via
		(at 204.5 163.5)
		(size 0.45)
		(drill 0.1)
		(layers "F.Cu" "B.Cu")
		(remove_unused_layers yes)
		(keep_end_layers yes)
		(zone_layer_connections "In1.Cu" "In3.Cu" "In5.Cu" "In7.Cu" "In10.Cu")
		(net 1)
	)
	(via
		(at 159.85 104.848)
		(size 0.45)
		(drill 0.1)
		(layers "F.Cu" "B.Cu")
		(remove_unused_layers yes)
		(keep_end_layers yes)
		(zone_layer_connections "In1.Cu" "In3.Cu" "In5.Cu" "In7.Cu" "In10.Cu")
		(net 1)
	)
	(via
		(at 238.051 104.848)
		(size 0.45)
		(drill 0.1)
		(layers "F.Cu" "B.Cu")
		(remove_unused_layers yes)
		(keep_end_layers yes)
		(zone_layer_connections "In1.Cu" "In3.Cu" "In5.Cu" "In7.Cu" "In10.Cu")
		(net 1)
	)
	(via
		(at 256.837998 129.999)
		(size 0.45)
		(drill 0.1)
		(layers "F.Cu" "B.Cu")
		(remove_unused_layers yes)
		(keep_end_layers yes)
		(zone_layer_connections "In1.Cu" "In3.Cu" "In5.Cu" "In7.Cu" "In10.Cu")
		(net 1)
	)
	(via
		(at 189.5005 165.4995)
		(size 0.45)
		(drill 0.1)
		(layers "F.Cu" "B.Cu")
		(remove_unused_layers yes)
		(keep_end_layers yes)
		(zone_layer_connections "In1.Cu" "In3.Cu" "In5.Cu" "In7.Cu" "In10.Cu")
		(net 1)
	)
	(via
		(at 243.458998 131.84)
		(size 0.45)
		(drill 0.1)
		(layers "F.Cu" "B.Cu")
		(remove_unused_layers yes)
		(keep_end_layers yes)
		(zone_layer_connections "In1.Cu" "In3.Cu" "In5.Cu" "In7.Cu" "In10.Cu")
		(net 1)
	)
	(via
		(at 106.275 169.265)
		(size 0.45)
		(drill 0.1)
		(layers "F.Cu" "B.Cu")
		(remove_unused_layers yes)
		(keep_end_layers yes)
		(zone_layer_connections "In1.Cu" "In3.Cu" "In5.Cu" "In7.Cu" "In10.Cu")
		(net 1)
	)
	(via
		(at 218.375 158.2)
		(size 0.45)
		(drill 0.1)
		(layers "F.Cu" "B.Cu")
		(remove_unused_layers yes)
		(keep_end_layers yes)
		(zone_layer_connections "In1.Cu" "In3.Cu" "In5.Cu" "In7.Cu" "In10.Cu")
		(net 1)
	)
	(via
		(at 197.5 142.5)
		(size 0.45)
		(drill 0.1)
		(layers "F.Cu" "B.Cu")
		(remove_unused_layers yes)
		(keep_end_layers yes)
		(zone_layer_connections "In1.Cu" "In3.Cu" "In5.Cu" "In7.Cu" "In10.Cu")
		(net 1)
	)
	(via
		(at 177.701 109.446)
		(size 0.45)
		(drill 0.1)
		(layers "F.Cu" "B.Cu")
		(remove_unused_layers yes)
		(keep_end_layers yes)
		(zone_layer_connections "In1.Cu" "In3.Cu" "In5.Cu" "In7.Cu" "In10.Cu")
		(net 1)
	)
	(via
		(at 186.5 156.5)
		(size 0.45)
		(drill 0.1)
		(layers "F.Cu" "B.Cu")
		(remove_unused_layers yes)
		(keep_end_layers yes)
		(zone_layer_connections "In1.Cu" "In3.Cu" "In5.Cu" "In7.Cu" "In10.Cu")
		(net 1)
	)
	(via
		(at 255.93 187.77)
		(size 0.45)
		(drill 0.1)
		(layers "F.Cu" "B.Cu")
		(remove_unused_layers yes)
		(keep_end_layers yes)
		(zone_layer_connections "In1.Cu" "In3.Cu" "In5.Cu" "In7.Cu" "In10.Cu")
		(net 1)
	)
	(via
		(at 213.035 180.185)
		(size 0.45)
		(drill 0.1)
		(layers "F.Cu" "B.Cu")
		(remove_unused_layers yes)
		(keep_end_layers yes)
		(free yes)
		(zone_layer_connections "In1.Cu" "In3.Cu" "In5.Cu" "In7.Cu" "In10.Cu")
		(net 1)
	)
	(via
		(at 168.636499 104.1385)
		(size 0.45)
		(drill 0.1)
		(layers "F.Cu" "B.Cu")
		(remove_unused_layers yes)
		(keep_end_layers yes)
		(zone_layer_connections "In1.Cu" "In3.Cu" "In5.Cu" "In7.Cu" "In10.Cu")
		(net 1)
	)
	(via
		(at 190.5 153.5)
		(size 0.45)
		(drill 0.1)
		(layers "F.Cu" "B.Cu")
		(remove_unused_layers yes)
		(keep_end_layers yes)
		(zone_layer_connections "In1.Cu" "In3.Cu" "In5.Cu" "In7.Cu" "In10.Cu")
		(net 1)
	)
	(via
		(at 167.125 194.849501)
		(size 0.45)
		(drill 0.1)
		(layers "F.Cu" "B.Cu")
		(remove_unused_layers yes)
		(keep_end_layers yes)
		(zone_layer_connections "In1.Cu" "In3.Cu" "In5.Cu" "In7.Cu" "In10.Cu")
		(net 1)
	)
	(via
		(at 258.51 189.46)
		(size 0.45)
		(drill 0.1)
		(layers "F.Cu" "B.Cu")
		(remove_unused_layers yes)
		(keep_end_layers yes)
		(zone_layer_connections "In1.Cu" "In3.Cu" "In5.Cu" "In7.Cu" "In10.Cu")
		(net 1)
	)
	(via
		(at 109.273499 140.6)
		(size 0.45)
		(drill 0.1)
		(layers "F.Cu" "B.Cu")
		(remove_unused_layers yes)
		(keep_end_layers yes)
		(zone_layer_connections "In1.Cu" "In3.Cu" "In5.Cu" "In7.Cu" "In10.Cu")
		(net 1)
	)
	(via
		(at 257.8 137.7)
		(size 0.45)
		(drill 0.1)
		(layers "F.Cu" "B.Cu")
		(remove_unused_layers yes)
		(keep_end_layers yes)
		(zone_layer_connections "In1.Cu" "In3.Cu" "In5.Cu" "In7.Cu" "In10.Cu")
		(net 1)
	)
	(via
		(at 191.5 139.5)
		(size 0.45)
		(drill 0.1)
		(layers "F.Cu" "B.Cu")
		(remove_unused_layers yes)
		(keep_end_layers yes)
		(zone_layer_connections "In1.Cu" "In3.Cu" "In5.Cu" "In7.Cu" "In10.Cu")
		(net 1)
	)
	(via
		(at 254.294999 155.3005)
		(size 0.45)
		(drill 0.1)
		(layers "F.Cu" "B.Cu")
		(remove_unused_layers yes)
		(keep_end_layers yes)
		(zone_layer_connections "In1.Cu" "In2.Cu" "In3.Cu" "In4.Cu" "In5.Cu" "In6.Cu"
			"In7.Cu" "In10.Cu"
		)
		(net 1)
	)
	(via
		(at 183.5005 164.4995)
		(size 0.45)
		(drill 0.1)
		(layers "F.Cu" "B.Cu")
		(remove_unused_layers yes)
		(keep_end_layers yes)
		(zone_layer_connections "In1.Cu" "In3.Cu" "In5.Cu" "In7.Cu" "In10.Cu")
		(net 1)
	)
	(via
		(at 154.26 162.19)
		(size 0.45)
		(drill 0.1)
		(layers "F.Cu" "B.Cu")
		(remove_unused_layers yes)
		(keep_end_layers yes)
		(zone_layer_connections "In1.Cu" "In3.Cu" "In5.Cu" "In7.Cu" "In10.Cu")
		(net 1)
	)
	(via
		(at 100.63 103.59)
		(size 0.45)
		(drill 0.1)
		(layers "F.Cu" "B.Cu")
		(remove_unused_layers yes)
		(keep_end_layers yes)
		(zone_layer_connections "In1.Cu" "In3.Cu" "In5.Cu" "In7.Cu" "In10.Cu")
		(net 1)
	)
	(via
		(at 164.6 155)
		(size 0.45)
		(drill 0.1)
		(layers "F.Cu" "B.Cu")
		(remove_unused_layers yes)
		(keep_end_layers yes)
		(zone_layer_connections "In1.Cu" "In3.Cu" "In5.Cu" "In7.Cu" "In10.Cu")
		(net 1)
	)
	(via
		(at 125.902 179.727)
		(size 0.45)
		(drill 0.1)
		(layers "F.Cu" "B.Cu")
		(remove_unused_layers yes)
		(keep_end_layers yes)
		(zone_layer_connections "In1.Cu" "In3.Cu" "In5.Cu" "In7.Cu" "In10.Cu")
		(net 1)
	)
	(via
		(at 142 109.446)
		(size 0.45)
		(drill 0.1)
		(layers "F.Cu" "B.Cu")
		(remove_unused_layers yes)
		(keep_end_layers yes)
		(zone_layer_connections "In1.Cu" "In3.Cu" "In5.Cu" "In7.Cu" "In10.Cu")
		(net 1)
	)
	(via
		(at 217.3 129.17)
		(size 0.45)
		(drill 0.1)
		(layers "F.Cu" "B.Cu")
		(remove_unused_layers yes)
		(keep_end_layers yes)
		(zone_layer_connections "In1.Cu" "In3.Cu" "In5.Cu" "In7.Cu" "In10.Cu")
		(net 1)
	)
	(via
		(at 221.314596 179.876834)
		(size 0.45)
		(drill 0.1)
		(layers "F.Cu" "B.Cu")
		(remove_unused_layers yes)
		(keep_end_layers yes)
		(zone_layer_connections "In1.Cu" "In3.Cu" "In5.Cu" "In7.Cu" "In10.Cu")
		(net 1)
	)
	(via
		(at 184.5 162.5)
		(size 0.45)
		(drill 0.1)
		(layers "F.Cu" "B.Cu")
		(remove_unused_layers yes)
		(keep_end_layers yes)
		(zone_layer_connections "In1.Cu" "In3.Cu" "In5.Cu" "In7.Cu" "In10.Cu")
		(net 1)
	)
	(via
		(at 234.61 168.86)
		(size 0.45)
		(drill 0.1)
		(layers "F.Cu" "B.Cu")
		(remove_unused_layers yes)
		(keep_end_layers yes)
		(zone_layer_connections "In1.Cu" "In3.Cu" "In5.Cu" "In7.Cu" "In10.Cu")
		(net 1)
	)
	(via
		(at 255.621999 171.5515)
		(size 0.45)
		(drill 0.1)
		(layers "F.Cu" "B.Cu")
		(remove_unused_layers yes)
		(keep_end_layers yes)
		(zone_layer_connections "In1.Cu" "In2.Cu" "In3.Cu" "In4.Cu" "In5.Cu" "In6.Cu"
			"In7.Cu" "In10.Cu"
		)
		(net 1)
	)
	(via
		(at 257.22 112.805)
		(size 0.45)
		(drill 0.1)
		(layers "F.Cu" "B.Cu")
		(remove_unused_layers yes)
		(keep_end_layers yes)
		(zone_layer_connections "In1.Cu" "In3.Cu" "In5.Cu" "In7.Cu" "In10.Cu")
		(net 1)
	)
	(via
		(at 141.684 162.835)
		(size 0.45)
		(drill 0.1)
		(layers "F.Cu" "B.Cu")
		(remove_unused_layers yes)
		(keep_end_layers yes)
		(zone_layer_connections "In1.Cu" "In3.Cu" "In5.Cu" "In7.Cu" "In10.Cu")
		(net 1)
	)
	(via
		(at 218.375 156.1)
		(size 0.45)
		(drill 0.1)
		(layers "F.Cu" "B.Cu")
		(remove_unused_layers yes)
		(keep_end_layers yes)
		(zone_layer_connections "In1.Cu" "In3.Cu" "In5.Cu" "In7.Cu" "In10.Cu")
		(net 1)
	)
	(via
		(at 192.5 155.5)
		(size 0.45)
		(drill 0.1)
		(layers "F.Cu" "B.Cu")
		(remove_unused_layers yes)
		(keep_end_layers yes)
		(zone_layer_connections "In1.Cu" "In3.Cu" "In5.Cu" "In7.Cu" "In10.Cu")
		(net 1)
	)
	(via
		(at 128.2866 100.498601)
		(size 0.45)
		(drill 0.1)
		(layers "F.Cu" "B.Cu")
		(remove_unused_layers yes)
		(keep_end_layers yes)
		(zone_layer_connections "In1.Cu" "In3.Cu" "In5.Cu" "In7.Cu" "In10.Cu")
		(net 1)
	)
	(via
		(at 223.125 156.05)
		(size 0.45)
		(drill 0.1)
		(layers "F.Cu" "B.Cu")
		(remove_unused_layers yes)
		(keep_end_layers yes)
		(zone_layer_connections "In1.Cu" "In3.Cu" "In5.Cu" "In7.Cu" "In10.Cu")
		(net 1)
	)
	(via
		(at 191.5 154.5)
		(size 0.45)
		(drill 0.1)
		(layers "F.Cu" "B.Cu")
		(remove_unused_layers yes)
		(keep_end_layers yes)
		(zone_layer_connections "In1.Cu" "In3.Cu" "In5.Cu" "In7.Cu" "In10.Cu")
		(net 1)
	)
	(via
		(at 226.585 177.935)
		(size 0.45)
		(drill 0.1)
		(layers "F.Cu" "B.Cu")
		(remove_unused_layers yes)
		(keep_end_layers yes)
		(zone_layer_connections "In1.Cu" "In3.Cu" "In5.Cu" "In7.Cu" "In10.Cu")
		(net 1)
	)
	(via
		(at 242.51 189.46)
		(size 0.45)
		(drill 0.1)
		(layers "F.Cu" "B.Cu")
		(remove_unused_layers yes)
		(keep_end_layers yes)
		(zone_layer_connections "In1.Cu" "In3.Cu" "In5.Cu" "In7.Cu" "In10.Cu")
		(net 1)
	)
	(via
		(at 204.875 178.325)
		(size 0.45)
		(drill 0.1)
		(layers "F.Cu" "B.Cu")
		(remove_unused_layers yes)
		(keep_end_layers yes)
		(zone_layer_connections "In1.Cu" "In3.Cu" "In5.Cu" "In7.Cu" "In10.Cu")
		(net 1)
	)
	(via
		(at 171.751 109.446)
		(size 0.45)
		(drill 0.1)
		(layers "F.Cu" "B.Cu")
		(remove_unused_layers yes)
		(keep_end_layers yes)
		(zone_layer_connections "In1.Cu" "In3.Cu" "In5.Cu" "In7.Cu" "In10.Cu")
		(net 1)
	)
	(via
		(at 193.5005 165.4995)
		(size 0.45)
		(drill 0.1)
		(layers "F.Cu" "B.Cu")
		(remove_unused_layers yes)
		(keep_end_layers yes)
		(zone_layer_connections "In1.Cu" "In3.Cu" "In5.Cu" "In7.Cu" "In10.Cu")
		(net 1)
	)
	(via
		(at 263.424499 175.024)
		(size 0.45)
		(drill 0.1)
		(layers "F.Cu" "B.Cu")
		(remove_unused_layers yes)
		(keep_end_layers yes)
		(zone_layer_connections "In1.Cu" "In3.Cu" "In5.Cu" "In6.Cu" "In7.Cu" "In10.Cu")
		(net 1)
	)
	(via
		(at 208.9 157.125)
		(size 0.45)
		(drill 0.1)
		(layers "F.Cu" "B.Cu")
		(remove_unused_layers yes)
		(keep_end_layers yes)
		(zone_layer_connections "In1.Cu" "In3.Cu" "In5.Cu" "In7.Cu" "In10.Cu")
		(net 1)
	)
	(via
		(at 129.424499 188.649)
		(size 0.45)
		(drill 0.1)
		(layers "F.Cu" "B.Cu")
		(remove_unused_layers yes)
		(keep_end_layers yes)
		(zone_layer_connections "In1.Cu" "In3.Cu" "In5.Cu" "In7.Cu" "In10.Cu")
		(net 1)
	)
	(via
		(at 246.8 155.925)
		(size 0.45)
		(drill 0.1)
		(layers "F.Cu" "B.Cu")
		(remove_unused_layers yes)
		(keep_end_layers yes)
		(zone_layer_connections "In1.Cu" "In2.Cu" "In3.Cu" "In4.Cu" "In5.Cu" "In6.Cu"
			"In7.Cu" "In10.Cu"
		)
		(net 1)
	)
	(via
		(at 247.904 141.101)
		(size 0.45)
		(drill 0.1)
		(layers "F.Cu" "B.Cu")
		(remove_unused_layers yes)
		(keep_end_layers yes)
		(zone_layer_connections "In1.Cu" "In3.Cu" "In5.Cu" "In7.Cu" "In10.Cu")
		(net 1)
	)
	(via
		(at 247.949499 172.149)
		(size 0.45)
		(drill 0.1)
		(layers "F.Cu" "B.Cu")
		(remove_unused_layers yes)
		(keep_end_layers yes)
		(zone_layer_connections "In1.Cu" "In2.Cu" "In3.Cu" "In4.Cu" "In5.Cu" "In6.Cu"
			"In7.Cu" "In10.Cu"
		)
		(net 1)
	)
	(via
		(at 180.5 149.5)
		(size 0.45)
		(drill 0.1)
		(layers "F.Cu" "B.Cu")
		(remove_unused_layers yes)
		(keep_end_layers yes)
		(zone_layer_connections "In1.Cu" "In3.Cu" "In5.Cu" "In7.Cu" "In10.Cu")
		(net 1)
	)
	(via
		(at 184.5 154.5)
		(size 0.45)
		(drill 0.1)
		(layers "F.Cu" "B.Cu")
		(remove_unused_layers yes)
		(keep_end_layers yes)
		(zone_layer_connections "In1.Cu" "In3.Cu" "In5.Cu" "In7.Cu" "In10.Cu")
		(net 1)
	)
	(via
		(at 222.635 172.66)
		(size 0.45)
		(drill 0.1)
		(layers "F.Cu" "B.Cu")
		(remove_unused_layers yes)
		(keep_end_layers yes)
		(zone_layer_connections "In1.Cu" "In3.Cu" "In5.Cu" "In7.Cu" "In10.Cu")
		(net 1)
	)
	(via
		(at 210.735 180.235)
		(size 0.45)
		(drill 0.1)
		(layers "F.Cu" "B.Cu")
		(remove_unused_layers yes)
		(keep_end_layers yes)
		(zone_layer_connections "In1.Cu" "In3.Cu" "In5.Cu" "In7.Cu" "In10.Cu")
		(net 1)
	)
	(via
		(at 137.75 109.446)
		(size 0.45)
		(drill 0.1)
		(layers "F.Cu" "B.Cu")
		(remove_unused_layers yes)
		(keep_end_layers yes)
		(zone_layer_connections "In1.Cu" "In3.Cu" "In5.Cu" "In7.Cu" "In10.Cu")
		(net 1)
	)
	(via
		(at 177.1975 194.849501)
		(size 0.45)
		(drill 0.1)
		(layers "F.Cu" "B.Cu")
		(remove_unused_layers yes)
		(keep_end_layers yes)
		(zone_layer_connections "In1.Cu" "In3.Cu" "In5.Cu" "In7.Cu" "In10.Cu")
		(net 1)
	)
	(segment
		(start 114.043811 127.564)
		(end 114.043811 128.298537)
		(width 0.4)
		(layer "B.Cu")
		(net 1)
	)
	(segment
		(start 180.8 152.7875)
		(end 180.8 152.525)
		(width 0.4)
		(layer "B.Cu")
		(net 1)
	)
	(segment
		(start 108.189 163.868)
		(end 108.797 163.868)
		(width 0.201)
		(layer "B.Cu")
		(net 1)
	)
	(segment
		(start 251.72 187.338)
		(end 251.156 187.338)
		(width 0.182)
		(layer "B.Cu")
		(net 1)
	)
	(segment
		(start 237.276998 171.197501)
		(end 237.554497 171.475)
		(width 0.256)
		(layer "B.Cu")
		(net 1)
	)
	(segment
		(start 185 148)
		(end 185.5 148.5)
		(width 0.256)
		(layer "B.Cu")
		(net 1)
	)
	(segment
		(start 135.97266 137.947161)
		(end 136.024499 137.999)
		(width 0.2)
		(layer "B.Cu")
		(net 1)
	)
	(segment
		(start 203.1 135.2)
		(end 203.55 135.2)
		(width 0.256)
		(layer "B.Cu")
		(net 1)
	)
	(segment
		(start 186 151)
		(end 186.5 151.5)
		(width 0.256)
		(layer "B.Cu")
		(net 1)
	)
	(segment
		(start 188.5 153.15)
		(end 189.3 153.95)
		(width 0.256)
		(layer "B.Cu")
		(net 1)
	)
	(segment
		(start 173.1995 194.849501)
		(end 173.65 195.300001)
		(width 0.22)
		(layer "B.Cu")
		(net 1)
	)
	(segment
		(start 244.21 121.326)
		(end 243.484 121.326)
		(width 0.4)
		(layer "B.Cu")
		(net 1)
	)
	(segment
		(start 126.805 145.452149)
		(end 126.875 145.522149)
		(width 0.2)
		(layer "B.Cu")
		(net 1)
	)
	(segment
		(start 253.4 121.326)
		(end 252.776 121.326)
		(width 0.198)
		(layer "B.Cu")
		(net 1)
	)
	(segment
		(start 125.16 119.173)
		(end 123.903 119.173)
		(width 0.4)
		(layer "B.Cu")
		(net 1)
	)
	(segment
		(start 149.084499 160.917)
		(end 149.084499 161.543672)
		(width 0.15)
		(layer "B.Cu")
		(net 1)
	)
	(segment
		(start 205.95 151.15)
		(end 206.34 151.15)
		(width 0.114)
		(layer "B.Cu")
		(net 1)
	)
	(segment
		(start 188.45 155.5)
		(end 187.5 155.5)
		(width 0.4)
		(layer "B.Cu")
		(net 1)
	)
	(segment
		(start 184.5 154.500001)
		(end 184 155.000001)
		(width 0.256)
		(layer "B.Cu")
		(net 1)
	)
	(segment
		(start 181.5 153.4875)
		(end 180.8 152.7875)
		(width 0.4)
		(layer "B.Cu")
		(net 1)
	)
	(segment
		(start 193.5 145.5)
		(end 194 146)
		(width 0.256)
		(layer "B.Cu")
		(net 1)
	)
	(segment
		(start 253.024499 134.699)
		(end 252.999499 134.674)
		(width 0.256)
		(layer "B.Cu")
		(net 1)
	)
	(segment
		(start 140.44 146.03)
		(end 140.14 146.33)
		(width 0.256)
		(layer "B.Cu")
		(net 1)
	)
	(segment
		(start 190.5 155.5)
		(end 191 155)
		(width 0.256)
		(layer "B.Cu")
		(net 1)
	)
	(segment
		(start 221.635 176.26)
		(end 221.485 176.11)
		(width 0.15)
		(layer "B.Cu")
		(net 1)
	)
	(segment
		(start 183.5 148.5)
		(end 184 149)
		(width 0.256)
		(layer "B.Cu")
		(net 1)
	)
	(segment
		(start 169.901 101.18)
		(end 169.898001 101.183)
		(width 0.4)
		(layer "B.Cu")
		(net 1)
	)
	(segment
		(start 180 159)
		(end 180.5 158.5)
		(width 0.256)
		(layer "B.Cu")
		(net 1)
	)
	(segment
		(start 188.88 108.3)
		(end 188.88 107.755)
		(width 0.4)
		(layer "B.Cu")
		(net 1)
	)
	(segment
		(start 183 148)
		(end 183.5 148.5)
		(width 0.256)
		(layer "B.Cu")
		(net 1)
	)
	(segment
		(start 120.901 166.36)
		(end 120.901 167.34)
		(width 0.256)
		(layer "B.Cu")
		(net 1)
	)
	(segment
		(start 183.175 194.849501)
		(end 183.65 195.324501)
		(width 0.22)
		(layer "B.Cu")
		(net 1)
	)
	(segment
		(start 212.025 154.875)
		(end 212.394 154.506)
		(width 0.177)
		(layer "B.Cu")
		(net 1)
	)
	(segment
		(start 185.5005 160.5005)
		(end 186 161)
		(width 0.256)
		(layer "B.Cu")
		(net 1)
	)
	(segment
		(start 259.774499 159.124)
		(end 260.4735 159.124)
		(width 0.256)
		(layer "B.Cu")
		(net 1)
	)
	(segment
		(start 133.433171 145.890328)
		(end 133.924499 145.399)
		(width 0.4)
		(layer "B.Cu")
		(net 1)
	)
	(segment
		(start 188.55 155.55)
		(end 189.5 156.5)
		(width 0.4)
		(layer "B.Cu")
		(net 1)
	)
	(segment
		(start 123.893 126.499)
		(end 123.896 126.496)
		(width 0.4)
		(layer "B.Cu")
		(net 1)
	)
	(segment
		(start 105.17 156.369)
		(end 105.775 156.369)
		(width 0.1)
		(layer "B.Cu")
		(net 1)
	)
	(segment
		(start 188.65 195.374501)
		(end 188.65 199.25)
		(width 0.22)
		(layer "B.Cu")
		(net 1)
	)
	(segment
		(start 193.125 194.849501)
		(end 192.65 195.324501)
		(width 0.22)
		(layer "B.Cu")
		(net 1)
	)
	(segment
		(start 201.7 149.5)
		(end 202.4 148.8)
		(width 0.4)
		(layer "B.Cu")
		(net 1)
	)
	(segment
		(start 176 159)
		(end 176.5 158.5)
		(width 0.256)
		(layer "B.Cu")
		(net 1)
	)
	(segment
		(start 193.999999 158.999999)
		(end 193.5 158.5)
		(width 0.256)
		(layer "B.Cu")
		(net 1)
	)
	(segment
		(start 187.55 145.5)
		(end 188.5 146.45)
		(width 0.4)
		(layer "B.Cu")
		(net 1)
	)
	(segment
		(start 105.17 160.869)
		(end 105.75 160.869)
		(width 0.1)
		(layer "B.Cu")
		(net 1)
	)
	(segment
		(start 167.6 152.516)
		(end 167.6 152)
		(width 0.4)
		(layer "B.Cu")
		(net 1)
	)
	(segment
		(start 190 148.998)
		(end 190.002 148.998)
		(width 0.256)
		(layer "B.Cu")
		(net 1)
	)
	(segment
		(start 192.5 160.498)
		(end 192.998 160)
		(width 0.256)
		(layer "B.Cu")
		(net 1)
	)
	(segment
		(start 169.902501 101.1785)
		(end 169.9055 101.1755)
		(width 0.4)
		(layer "B.Cu")
		(net 1)
	)
	(segment
		(start 193.499999 156.5)
		(end 193 156.999999)
		(width 0.256)
		(layer "B.Cu")
		(net 1)
	)
	(segment
		(start 240 120.915)
		(end 239.85 120.765)
		(width 0.4)
		(layer "B.Cu")
		(net 1)
	)
	(segment
		(start 184.002 158.002)
		(end 184.5 158.5)
		(width 0.256)
		(layer "B.Cu")
		(net 1)
	)
	(segment
		(start 239.675 120.94)
		(end 239.85 120.765)
		(width 0.4)
		(layer "B.Cu")
		(net 1)
	)
	(segment
		(start 260.433499 173.174)
		(end 259.825499 173.174)
		(width 0.256)
		(layer "B.Cu")
		(net 1)
	)
	(segment
		(start 159.125 194.849501)
		(end 158.65 195.324501)
		(width 0.22)
		(layer "B.Cu")
		(net 1)
	)
	(segment
		(start 193 146)
		(end 193.5 145.5)
		(width 0.198)
		(layer "B.Cu")
		(net 1)
	)
	(segment
		(start 204.5 107.755)
		(end 204.495 107.75)
		(width 0.4)
		(layer "B.Cu")
		(net 1)
	)
	(segment
		(start 135.433171 145.890328)
		(end 135.924499 145.399)
		(width 0.4)
		(layer "B.Cu")
		(net 1)
	)
	(segment
		(start 123.897 122.13)
		(end 123.894 122.133)
		(width 0.4)
		(layer "B.Cu")
		(net 1)
	)
	(segment
		(start 254.804499 139.25)
		(end 254.804499 139.38)
		(width 0.256)
		(layer "B.Cu")
		(net 1)
	)
	(segment
		(start 191 151)
		(end 190.5 150.5)
		(width 0.256)
		(layer "B.Cu")
		(net 1)
	)
	(segment
		(start 123.9015 101.1605)
		(end 123.8985 101.1635)
		(width 0.4)
		(layer "B.Cu")
		(net 1)
	)
	(segment
		(start 202.5 159.5)
		(end 204.5 159.5)
		(width 0.4)
		(layer "B.Cu")
		(net 1)
	)
	(segment
		(start 200.999 141.001)
		(end 200.5 141.5)
		(width 0.256)
		(layer "B.Cu")
		(net 1)
	)
	(segment
		(start 185.500001 158.5)
		(end 186 158.999999)
		(width 0.256)
		(layer "B.Cu")
		(net 1)
	)
	(segment
		(start 189 149)
		(end 189.5 149.5)
		(width 0.4)
		(layer "B.Cu")
		(net 1)
	)
	(segment
		(start 253.839499 176.812)
		(end 253.851499 176.8)
		(width 0.256)
		(layer "B.Cu")
		(net 1)
	)
	(segment
		(start 177.1975 194.849501)
		(end 177.1975 196.3975)
		(width 0.22)
		(layer "B.Cu")
		(net 1)
	)
	(segment
		(start 194.499 143.5)
		(end 194 143.001)
		(width 0.256)
		(layer "B.Cu")
		(net 1)
	)
	(segment
		(start 123.9075 101.1545)
		(end 123.9105 101.1515)
		(width 0.4)
		(layer "B.Cu")
		(net 1)
	)
	(segment
		(start 192.65 195.324501)
		(end 192.65 199.25)
		(width 0.22)
		(layer "B.Cu")
		(net 1)
	)
	(segment
		(start 202.5 163.5)
		(end 204.5 163.5)
		(width 0.4)
		(layer "B.Cu")
		(net 1)
	)
	(segment
		(start 183.998 158)
		(end 184 158.002)
		(width 0.256)
		(layer "B.Cu")
		(net 1)
	)
	(segment
		(start 149.084499 165.133)
		(end 149.084499 166.329984)
		(width 0.15)
		(layer "B.Cu")
		(net 1)
	)
	(segment
		(start 139.708499 145.6)
		(end 139.708499 144.515)
		(width 0.256)
		(layer "B.Cu")
		(net 1)
	)
	(segment
		(start 115.55 158.427)
		(end 115.4 158.277)
		(width 0.256)
		(layer "B.Cu")
		(net 1)
	)
	(segment
		(start 191 159)
		(end 191.5 158.5)
		(width 0.256)
		(layer "B.Cu")
		(net 1)
	)
	(segment
		(start 169.65 195.324501)
		(end 169.65 199.25)
		(width 0.22)
		(layer "B.Cu")
		(net 1)
	)
	(segment
		(start 169.907 101.174001)
		(end 169.91 101.171)
		(width 0.4)
		(layer "B.Cu")
		(net 1)
	)
	(segment
		(start 194 158)
		(end 194.5 158.5)
		(width 0.256)
		(layer "B.Cu")
		(net 1)
	)
	(segment
		(start 186 158.999999)
		(end 186.000001 158.999999)
		(width 0.256)
		(layer "B.Cu")
		(net 1)
	)
	(segment
		(start 171.175 194.849501)
		(end 170.65 195.374501)
		(width 0.22)
		(layer "B.Cu")
		(net 1)
	)
	(segment
		(start 113.431 167.848463)
		(end 113.847537 168.265)
		(width 0.201)
		(layer "B.Cu")
		(net 1)
	)
	(segment
		(start 189.5 156.500001)
		(end 190 157.000001)
		(width 0.256)
		(layer "B.Cu")
		(net 1)
	)
	(segment
		(start 243.484 121.326)
		(end 243.03 121.78)
		(width 0.4)
		(layer "B.Cu")
		(net 1)
	)
	(segment
		(start 149.084499 161.543672)
		(end 149.046843 161.581328)
		(width 0.15)
		(layer "B.Cu")
		(net 1)
	)
	(segment
		(start 260.574499 173.315)
		(end 260.433499 173.174)
		(width 0.256)
		(layer "B.Cu")
		(net 1)
	)
	(segment
		(start 120.125 158.97)
		(end 120.125 158.15)
		(width 0.182)
		(layer "B.Cu")
		(net 1)
	)
	(segment
		(start 123.8985 101.1635)
		(end 123.8985 100.4905)
		(width 0.4)
		(layer "B.Cu")
		(net 1)
	)
	(segment
		(start 184.5 158.5)
		(end 185 159)
		(width 0.256)
		(layer "B.Cu")
		(net 1)
	)
	(segment
		(start 123.9 122.127)
		(end 123.9 122.8)
		(width 0.4)
		(layer "B.Cu")
		(net 1)
	)
	(segment
		(start 206.841 137.0045)
		(end 206.841 138.7135)
		(width 0.256)
		(layer "B.Cu")
		(net 1)
	)
	(segment
		(start 115.705 110.9)
		(end 116.435 110.9)
		(width 0.15)
		(layer "B.Cu")
		(net 1)
	)
	(segment
		(start 180.999 149.001)
		(end 180.5 149.5)
		(width 0.198)
		(layer "B.Cu")
		(net 1)
	)
	(segment
		(start 191 160)
		(end 191 159)
		(width 0.256)
		(layer "B.Cu")
		(net 1)
	)
	(segment
		(start 181.5 153.475)
		(end 182.25 152.725)
		(width 0.4)
		(layer "B.Cu")
		(net 1)
	)
	(segment
		(start 115.705 108.2)
		(end 116.435 108.2)
		(width 0.15)
		(layer "B.Cu")
		(net 1)
	)
	(segment
		(start 193 154)
		(end 192.5 153.5)
		(width 0.256)
		(layer "B.Cu")
		(net 1)
	)
	(segment
		(start 104.883 152.685)
		(end 104.716 152.852)
		(width 0.4)
		(layer "B.Cu")
		(net 1)
	)
	(segment
		(start 185.499999 153.5)
		(end 185 153.999999)
		(width 0.256)
		(layer "B.Cu")
		(net 1)
	)
	(segment
		(start 127.661328 139.582157)
		(end 127.39632 139.317149)
		(width 0.2)
		(layer "B.Cu")
		(net 1)
	)
	(segment
		(start 171.1595 101.1785)
		(end 169.902501 101.1785)
		(width 0.4)
		(layer "B.Cu")
		(net 1)
	)
	(segment
		(start 131.36 141.466)
		(end 131.77 141.056)
		(width 0.256)
		(layer "B.Cu")
		(net 1)
	)
	(segment
		(start 175.5 158.5)
		(end 174.9 158.5)
		(width 0.4)
		(layer "B.Cu")
		(net 1)
	)
	(segment
		(start 212.475 151.875)
		(end 213.05 152.45)
		(width 0.177)
		(layer "B.Cu")
		(net 1)
	)
	(segment
		(start 142.49975 148.7445)
		(end 143.07425 148.17)
		(width 0.256)
		(layer "B.Cu")
		(net 1)
	)
	(segment
		(start 189 162.998)
		(end 189.002 162.998)
		(width 0.256)
		(layer "B.Cu")
		(net 1)
	)
	(segment
		(start 186.002 156.998)
		(end 186.5 156.5)
		(width 0.256)
		(layer "B.Cu")
		(net 1)
	)
	(segment
		(start 178 159)
		(end 178.5 158.5)
		(width 0.256)
		(layer "B.Cu")
		(net 1)
	)
	(segment
		(start 185.5 158.5)
		(end 185 159)
		(width 0.256)
		(layer "B.Cu")
		(net 1)
	)
	(segment
		(start 183.998 157)
		(end 183.998 158)
		(width 0.256)
		(layer "B.Cu")
		(net 1)
	)
	(segment
		(start 186.000001 158.999999)
		(end 186.5 158.5)
		(width 0.256)
		(layer "B.Cu")
		(net 1)
	)
	(segment
		(start 256.387998 132.699)
		(end 255.724499 132.699)
		(width 0.256)
		(layer "B.Cu")
		(net 1)
	)
	(segment
		(start 193.999999 159)
		(end 193.999999 158.999999)
		(width 0.256)
		(layer "B.Cu")
		(net 1)
	)
	(segment
		(start 238.297999 143.09)
		(end 237.74 143.09)
		(width 0.182)
		(layer "B.Cu")
		(net 1)
	)
	(segment
		(start 253.57 121.496)
		(end 253.4 121.326)
		(width 0.198)
		(layer "B.Cu")
		(net 1)
	)
	(segment
		(start 157.324499 190.274)
		(end 156.609499 190.274)
		(width 0.177)
		(layer "B.Cu")
		(net 1)
	)
	(segment
		(start 213.05 152.45)
		(end 213.05 153.7)
		(width 0.177)
		(layer "B.Cu")
		(net 1)
	)
	(segment
		(start 192.5 147.5)
		(end 193 148)
		(width 0.256)
		(layer "B.Cu")
		(net 1)
	)
	(segment
		(start 189.002 162.998)
		(end 189.5 162.5)
		(width 0.256)
		(layer "B.Cu")
		(net 1)
	)
	(segment
		(start 123.89 130.126)
		(end 123.9014 130.1374)
		(width 0.4)
		(layer "B.Cu")
		(net 1)
	)
	(segment
		(start 202.77 136.0045)
		(end 202.77 135.53)
		(width 0.256)
		(layer "B.Cu")
		(net 1)
	)
	(segment
		(start 185.5 158.5)
		(end 185.500001 158.5)
		(width 0.256)
		(layer "B.Cu")
		(net 1)
	)
	(segment
		(start 256.423998 132.663)
		(end 256.387998 132.699)
		(width 0.182)
		(layer "B.Cu")
		(net 1)
	)
	(segment
		(start 123.897 119.179)
		(end 123.894 119.182)
		(width 0.4)
		(layer "B.Cu")
		(net 1)
	)
	(segment
		(start 177.999999 157)
		(end 177.999999 156.999999)
		(width 0.4)
		(layer "B.Cu")
		(net 1)
	)
	(segment
		(start 205.7 138.8045)
		(end 204.95 138.8045)
		(width 0.256)
		(layer "B.Cu")
		(net 1)
	)
	(segment
		(start 185.5 152.85)
		(end 185.825 152.525)
		(width 0.4)
		(layer "B.Cu")
		(net 1)
	)
	(segment
		(start 134.724499 143.249)
		(end 135.048171 143.249)
		(width 0.256)
		(layer "B.Cu")
		(net 1)
	)
	(segment
		(start 105.545 152.685)
		(end 104.883 152.685)
		(width 0.4)
		(layer "B.Cu")
		(net 1)
	)
	(segment
		(start 260.499499 153.784)
		(end 260.364499 153.649)
		(width 0.256)
		(layer "B.Cu")
		(net 1)
	)
	(segment
		(start 192 149.999999)
		(end 191.500001 149.5)
		(width 0.256)
		(layer "B.Cu")
		(net 1)
	)
	(segment
		(start 146.598499 164.999)
		(end 146.464499 165.133)
		(width 0.15)
		(layer "B.Cu")
		(net 1)
	)
	(segment
		(start 123.903 119.173)
		(end 123.906 119.17)
		(width 0.4)
		(layer "B.Cu")
		(net 1)
	)
	(segment
		(start 131.211328 137.598157)
		(end 131.211328 137.0395)
		(width 0.256)
		(layer "B.Cu")
		(net 1)
	)
	(segment
		(start 114.043811 128.298537)
		(end 114.030348 128.312)
		(width 0.201)
		(layer "B.Cu")
		(net 1)
	)
	(segment
		(start 187.5 148.5)
		(end 187 148)
		(width 0.256)
		(layer "B.Cu")
		(net 1)
	)
	(segment
		(start 192 144.000001)
		(end 191.5 144.500001)
		(width 0.256)
		(layer "B.Cu")
		(net 1)
	)
	(segment
		(start 260.364499 153.649)
		(end 259.724499 153.649)
		(width 0.256)
		(layer "B.Cu")
		(net 1)
	)
	(segment
		(start 196 148.999)
		(end 195.001 148.999)
		(width 0.198)
		(layer "B.Cu")
		(net 1)
	)
	(segment
		(start 123.887 129.456)
		(end 123.89 129.453)
		(width 0.4)
		(layer "B.Cu")
		(net 1)
	)
	(segment
		(start 187.92 104.2)
		(end 187.3 104.2)
		(width 0.198)
		(layer "B.Cu")
		(net 1)
	)
	(segment
		(start 195.65 196.85)
		(end 195.65 199.25)
		(width 0.22)
		(layer "B.Cu")
		(net 1)
	)
	(segment
		(start 192 156)
		(end 192.5 155.5)
		(width 0.256)
		(layer "B.Cu")
		(net 1)
	)
	(segment
		(start 191 159)
		(end 190.5 158.5)
		(width 0.256)
		(layer "B.Cu")
		(net 1)
	)
	(segment
		(start 192.002 150.002)
		(end 192.5 150.5)
		(width 0.256)
		(layer "B.Cu")
		(net 1)
	)
	(segment
		(start 240.07 122.22)
		(end 240 122.15)
		(width 0.4)
		(layer "B.Cu")
		(net 1)
	)
	(segment
		(start 186.5 154.5)
		(end 186.5 154.499999)
		(width 0.256)
		(layer "B.Cu")
		(net 1)
	)
	(segment
		(start 115.897499 118.149)
		(end 115.897499 119.134)
		(width 0.4)
		(layer "B.Cu")
		(net 1)
	)
	(segment
		(start 182.25 152.725)
		(end 182.25 152.525)
		(width 0.4)
		(layer "B.Cu")
		(net 1)
	)
	(segment
		(start 184.65 195.324501)
		(end 184.65 199.25)
		(width 0.22)
		(layer "B.Cu")
		(net 1)
	)
	(segment
		(start 166.6 150)
		(end 166.6 150.424)
		(width 0.4)
		(layer "B.Cu")
		(net 1)
	)
	(segment
		(start 250.37 123.4)
		(end 252.4 123.4)
		(width 0.198)
		(layer "B.Cu")
		(net 1)
	)
	(segment
		(start 104.716 168.39)
		(end 102.43 168.39)
		(width 0.4)
		(layer "B.Cu")
		(net 1)
	)
	(segment
		(start 158.65 195.324501)
		(end 158.65 199.25)
		(width 0.22)
		(layer "B.Cu")
		(net 1)
	)
	(segment
		(start 180 163)
		(end 180.5 162.5)
		(width 0.256)
		(layer "B.Cu")
		(net 1)
	)
	(segment
		(start 190.5 155.5)
		(end 191 156)
		(width 0.256)
		(layer "B.Cu")
		(net 1)
	)
	(segment
		(start 136.124999 152.9)
		(end 136.124499 152.9005)
		(width 0.256)
		(layer "B.Cu")
		(net 1)
	)
	(segment
		(start 196 140)
		(end 196.5 139.5)
		(width 0.256)
		(layer "B.Cu")
		(net 1)
	)
	(segment
		(start 197 163)
		(end 197.5 162.5)
		(width 0.256)
		(layer "B.Cu")
		(net 1)
	)
	(segment
		(start 260.414499 171.199)
		(end 259.749499 171.199)
		(width 0.256)
		(layer "B.Cu")
		(net 1)
	)
	(segment
		(start 123.9075 101.1545)
		(end 123.9045 101.1575)
		(width 0.4)
		(layer "B.Cu")
		(net 1)
	)
	(segment
		(start 198 159)
		(end 197.5 158.5)
		(width 0.256)
		(layer "B.Cu")
		(net 1)
	)
	(segment
		(start 246.995 187.338)
		(end 246.431 187.338)
		(width 0.182)
		(layer "B.Cu")
		(net 1)
	)
	(segment
		(start 186.5 149.5)
		(end 187 150)
		(width 0.256)
		(layer "B.Cu")
		(net 1)
	)
	(segment
		(start 184 151)
		(end 184.5 151.5)
		(width 0.256)
		(layer "B.Cu")
		(net 1)
	)
	(segment
		(start 191.5 154.5)
		(end 191 155)
		(width 0.256)
		(layer "B.Cu")
		(net 1)
	)
	(segment
		(start 106.275 168.795)
		(end 106.275 169.265)
		(width 0.4)
		(layer "B.Cu")
		(net 1)
	)
	(segment
		(start 135.177656 138.257165)
		(end 135.262656 138.257165)
		(width 0.2)
		(layer "B.Cu")
		(net 1)
	)
	(segment
		(start 252.776 121.326)
		(end 252.75 121.3)
		(width 0.198)
		(layer "B.Cu")
		(net 1)
	)
	(segment
		(start 123.89 125.829)
		(end 123.8786 125.8176)
		(width 0.4)
		(layer "B.Cu")
		(net 1)
	)
	(segment
		(start 162.725 155)
		(end 164.014 155)
		(width 0.4)
		(layer "B.Cu")
		(net 1)
	)
	(segment
		(start 184.5 146.500001)
		(end 184.999999 147)
		(width 0.256)
		(layer "B.Cu")
		(net 1)
	)
	(segment
		(start 192.5 153.5)
		(end 192.45 153.45)
		(width 0.256)
		(layer "B.Cu")
		(net 1)
	)
	(segment
		(start 134.433171 145.969992)
		(end 134.433171 145.890328)
		(width 0.4)
		(layer "B.Cu")
		(net 1)
	)
	(segment
		(start 123.909 104.777)
		(end 123.9204 104.7884)
		(width 0.4)
		(layer "B.Cu")
		(net 1)
	)
	(segment
		(start 164.046 155)
		(end 164.030001 154.984)
		(width 0.4)
		(layer "B.Cu")
		(net 1)
	)
	(segment
		(start 187.5 150.5)
		(end 187.5 150.55)
		(width 0.4)
		(layer "B.Cu")
		(net 1)
	)
	(segment
		(start 188.5 149)
		(end 189 149)
		(width 0.4)
		(layer "B.Cu")
		(net 1)
	)
	(segment
		(start 196 149.000001)
		(end 196.499999 149.5)
		(width 0.198)
		(layer "B.Cu")
		(net 1)
	)
	(segment
		(start 169.902501 101.1785)
		(end 169.8995 101.1815)
		(width 0.4)
		(layer "B.Cu")
		(net 1)
	)
	(segment
		(start 164.65 199.255)
		(end 164.65 195.349501)
		(width 0.4)
		(layer "B.Cu")
		(net 1)
	)
	(segment
		(start 123.897 122.13)
		(end 123.9 122.127)
		(width 0.4)
		(layer "B.Cu")
		(net 1)
	)
	(segment
		(start 181 156)
		(end 180.5 155.5)
		(width 0.4)
		(layer "B.Cu")
		(net 1)
	)
	(segment
		(start 183 151.017)
		(end 183.983 151.017)
		(width 0.198)
		(layer "B.Cu")
		(net 1)
	)
	(segment
		(start 182.25 152.525)
		(end 180.8 152.525)
		(width 0.4)
		(layer "B.Cu")
		(net 1)
	)
	(segment
		(start 192.5 160.5)
		(end 192.5 160.498)
		(width 0.256)
		(layer "B.Cu")
		(net 1)
	)
	(segment
		(start 181.125 194.849501)
		(end 180.65 195.324501)
		(width 0.22)
		(layer "B.Cu")
		(net 1)
	)
	(segment
		(start 188.05 153.5)
		(end 187.500001 153.5)
		(width 0.4)
		(layer "B.Cu")
		(net 1)
	)
	(segment
		(start 194 159)
		(end 194.5 158.5)
		(width 0.256)
		(layer "B.Cu")
		(net 1)
	)
	(segment
		(start 114.52 167.95)
		(end 114.205 168.265)
		(width 0.201)
		(layer "B.Cu")
		(net 1)
	)
	(segment
		(start 123.903 104.11)
		(end 123.906 104.107)
		(width 0.4)
		(layer "B.Cu")
		(net 1)
	)
	(segment
		(start 184.5 162.5)
		(end 184 163)
		(width 0.256)
		(layer "B.Cu")
		(net 1)
	)
	(segment
		(start 193.5 154.5)
		(end 194 155)
		(width 0.256)
		(layer "B.Cu")
		(net 1)
	)
	(segment
		(start 189.175 194.849501)
		(end 188.65 195.374501)
		(width 0.22)
		(layer "B.Cu")
		(net 1)
	)
	(segment
		(start 189.5 156.5)
		(end 189.5 156.500001)
		(width 0.256)
		(layer "B.Cu")
		(net 1)
	)
	(segment
		(start 197.5 153.5)
		(end 197.5 153.501)
		(width 0.256)
		(layer "B.Cu")
		(net 1)
	)
	(segment
		(start 253.690499 134.699)
		(end 253.024499 134.699)
		(width 0.256)
		(layer "B.Cu")
		(net 1)
	)
	(segment
		(start 187.5 150.5)
		(end 187 150)
		(width 0.256)
		(layer "B.Cu")
		(net 1)
	)
	(segment
		(start 120.891 168.5485)
		(end 121.036 168.6935)
		(width 0.256)
		(layer "B.Cu")
		(net 1)
	)
	(segment
		(start 194 149)
		(end 194.5 148.5)
		(width 0.256)
		(layer "B.Cu")
		(net 1)
	)
	(segment
		(start 252.4 123.4)
		(end 253.57 122.23)
		(width 0.198)
		(layer "B.Cu")
		(net 1)
	)
	(segment
		(start 183.983 151.017)
		(end 184 151)
		(width 0.198)
		(layer "B.Cu")
		(net 1)
	)
	(segment
		(start 185.999 144.999)
		(end 185.5 144.5)
		(width 0.256)
		(layer "B.Cu")
		(net 1)
	)
	(segment
		(start 195.001 148.999)
		(end 195 148.998)
		(width 0.198)
		(layer "B.Cu")
		(net 1)
	)
	(segment
		(start 204.95 138.8045)
		(end 204.75 139.0045)
		(width 0.256)
		(layer "B.Cu")
		(net 1)
	)
	(segment
		(start 212.394 154.506)
		(end 212.394 154.425)
		(width 0.177)
		(layer "B.Cu")
		(net 1)
	)
	(segment
		(start 196 159)
		(end 195.5 158.5)
		(width 0.256)
		(layer "B.Cu")
		(net 1)
	)
	(segment
		(start 260.549499 171.334)
		(end 260.414499 171.199)
		(width 0.256)
		(layer "B.Cu")
		(net 1)
	)
	(segment
		(start 136.675 152.9)
		(end 136.124999 152.9)
		(width 0.256)
		(layer "B.Cu")
		(net 1)
	)
	(segment
		(start 184 158.002)
		(end 184.002 158.002)
		(width 0.256)
		(layer "B.Cu")
		(net 1)
	)
	(segment
		(start 186.5 156.5)
		(end 187 156)
		(width 0.256)
		(layer "B.Cu")
		(net 1)
	)
	(segment
		(start 194.999999 156)
		(end 194.499999 155.5)
		(width 0.256)
		(layer "B.Cu")
		(net 1)
	)
	(segment
		(start 120.891 167.35)
		(end 120.891 168.5485)
		(width 0.256)
		(layer "B.Cu")
		(net 1)
	)
	(segment
		(start 120.901 167.34)
		(end 120.891 167.35)
		(width 0.256)
		(layer "B.Cu")
		(net 1)
	)
	(segment
		(start 206.841 135.215503)
		(end 206.599 134.973503)
		(width 0.256)
		(layer "B.Cu")
		(net 1)
	)
	(segment
		(start 177.1975 196.3975)
		(end 177.65 196.85)
		(width 0.22)
		(layer "B.Cu")
		(net 1)
	)
	(segment
		(start 148.975 193.075)
		(end 148.725 193.325)
		(width 0.201)
		(layer "B.Cu")
		(net 1)
	)
	(segment
		(start 133.424499 137.999)
		(end 132.873656 137.999)
		(width 0.256)
		(layer "B.Cu")
		(net 1)
	)
	(segment
		(start 119.91 127.01692)
		(end 119.896537 127.030383)
		(width 0.201)
		(layer "B.Cu")
		(net 1)
	)
	(segment
		(start 244.21 122.055)
		(end 244.38 122.225)
		(width 0.4)
		(layer "B.Cu")
		(net 1)
	)
	(segment
		(start 113.219 163.32)
		(end 112.67 163.32)
		(width 0.201)
		(layer "B.Cu")
		(net 1)
	)
	(segment
		(start 187 153.999999)
		(end 187.000002 153.999999)
		(width 0.256)
		(layer "B.Cu")
		(net 1)
	)
	(segment
		(start 122.646 101.159)
		(end 123.903 101.159)
		(width 0.4)
		(layer "B.Cu")
		(net 1)
	)
	(segment
		(start 106.627 160.119)
		(end 108.189 160.119)
		(width 0.201)
		(layer "B.Cu")
		(net 1)
	)
	(segment
		(start 206.66 141.6045)
		(end 206.66 142.16)
		(width 0.256)
		(layer "B.Cu")
		(net 1)
	)
	(segment
		(start 125.16 122.124)
		(end 123.903 122.124)
		(width 0.4)
		(layer "B.Cu")
		(net 1)
	)
	(segment
		(start 182.5 145.5)
		(end 183 145)
		(width 0.256)
		(layer "B.Cu")
		(net 1)
	)
	(segment
		(start 129.359 102.638)
		(end 129.8296 102.638)
		(width 0.4)
		(layer "B.Cu")
		(net 1)
	)
	(segment
		(start 189.5 149.5)
		(end 189.5 149.498)
		(width 0.256)
		(layer "B.Cu")
		(net 1)
	)
	(segment
		(start 184.5 154.499999)
		(end 185 153.999999)
		(width 0.256)
		(layer "B.Cu")
		(net 1)
	)
	(segment
		(start 106.627 157.119)
		(end 108.189 157.119)
		(width 0.201)
		(layer "B.Cu")
		(net 1)
	)
	(segment
		(start 185.825 152.525)
		(end 185.825 152.175)
		(width 0.4)
		(layer "B.Cu")
		(net 1)
	)
	(segment
		(start 196.002 158.998)
		(end 196.5 158.5)
		(width 0.256)
		(layer "B.Cu")
		(net 1)
	)
	(segment
		(start 254.674499 151.099)
		(end 254.624499 151.149)
		(width 0.256)
		(layer "B.Cu")
		(net 1)
	)
	(segment
		(start 193.5 156.5)
		(end 193.499999 156.5)
		(width 0.256)
		(layer "B.Cu")
		(net 1)
	)
	(segment
		(start 114.205 168.265)
		(end 113.847537 168.265)
		(width 0.201)
		(layer "B.Cu")
		(net 1)
	)
	(segment
		(start 133.424499 137.999)
		(end 133.912171 137.999)
		(width 0.256)
		(layer "B.Cu")
		(net 1)
	)
	(segment
		(start 169.901 101.18)
		(end 169.904 101.177)
		(width 0.4)
		(layer "B.Cu")
		(net 1)
	)
	(segment
		(start 249.895 122.225)
		(end 249.895 121.496)
		(width 0.198)
		(layer "B.Cu")
		(net 1)
	)
	(segment
		(start 168.6455 101.1785)
		(end 169.902501 101.1785)
		(width 0.4)
		(layer "B.Cu")
		(net 1)
	)
	(segment
		(start 198 158.999)
		(end 198.4995 158.4995)
		(width 0.256)
		(layer "B.Cu")
		(net 1)
	)
	(segment
		(start 201 158)
		(end 201.4995 158.4995)
		(width 0.256)
		(layer "B.Cu")
		(net 1)
	)
	(segment
		(start 201 155)
		(end 201.5 155.5)
		(width 0.256)
		(layer "B.Cu")
		(net 1)
	)
	(segment
		(start 170.4 158.45)
		(end 170.42 158.43)
		(width 0.256)
		(layer "B.Cu")
		(net 1)
	)
	(segment
		(start 202.77 135.53)
		(end 203.1 135.2)
		(width 0.256)
		(layer "B.Cu")
		(net 1)
	)
	(segment
		(start 166.65 195.324501)
		(end 166.65 199.25)
		(width 0.22)
		(layer "B.Cu")
		(net 1)
	)
	(segment
		(start 164.014 155)
		(end 164.030001 154.984)
		(width 0.198)
		(layer "B.Cu")
		(net 1)
	)
	(segment
		(start 123.903 101.159)
		(end 123.906 101.156)
		(width 0.4)
		(layer "B.Cu")
		(net 1)
	)
	(segment
		(start 105.949 154.969)
		(end 105.95 154.97)
		(width 0.4)
		(layer "B.Cu")
		(net 1)
	)
	(segment
		(start 188.5 155.55)
		(end 188.45 155.5)
		(width 0.4)
		(layer "B.Cu")
		(net 1)
	)
	(segment
		(start 126.805 144.697149)
		(end 126.805 145.452149)
		(width 0.2)
		(layer "B.Cu")
		(net 1)
	)
	(segment
		(start 127.39632 139.317149)
		(end 126.805 139.317149)
		(width 0.2)
		(layer "B.Cu")
		(net 1)
	)
	(segment
		(start 194 155)
		(end 194 155.000001)
		(width 0.256)
		(layer "B.Cu")
		(net 1)
	)
	(segment
		(start 246.431 187.338)
		(end 246.365 187.404)
		(width 0.182)
		(layer "B.Cu")
		(net 1)
	)
	(segment
		(start 106.807 163.868)
		(end 107.417 163.868)
		(width 0.201)
		(layer "B.Cu")
		(net 1)
	)
	(segment
		(start 105.17 157.869)
		(end 105.775 157.869)
		(width 0.1)
		(layer "B.Cu")
		(net 1)
	)
	(segment
		(start 254.809499 167.849)
		(end 254.699499 167.959)
		(width 0.256)
		(layer "B.Cu")
		(net 1)
	)
	(segment
		(start 181.5 153.5)
		(end 181.5 153.4875)
		(width 0.4)
		(layer "B.Cu")
		(net 1)
	)
	(segment
		(start 206.773206 138.3)
		(end 206.841 138.232206)
		(width 0.256)
		(layer "B.Cu")
		(net 1)
	)
	(segment
		(start 259.749499 171.199)
		(end 259.699499 171.149)
		(width 0.256)
		(layer "B.Cu")
		(net 1)
	)
	(segment
		(start 170.65 195.374501)
		(end 170.65 199.25)
		(width 0.22)
		(layer "B.Cu")
		(net 1)
	)
	(segment
		(start 199 149)
		(end 199.5 148.5)
		(width 0.4)
		(layer "B.Cu")
		(net 1)
	)
	(segment
		(start 190 146)
		(end 188.95 146)
		(width 0.256)
		(layer "B.Cu")
		(net 1)
	)
	(segment
		(start 187.65 195.324501)
		(end 187.65 199.25)
		(width 0.22)
		(layer "B.Cu")
		(net 1)
	)
	(segment
		(start 192 147)
		(end 192.5 147.5)
		(width 0.256)
		(layer "B.Cu")
		(net 1)
	)
	(segment
		(start 148.975 192.625)
		(end 148.975 193.075)
		(width 0.201)
		(layer "B.Cu")
		(net 1)
	)
	(segment
		(start 105.87 168.39)
		(end 106.275 168.795)
		(width 0.4)
		(layer "B.Cu")
		(net 1)
	)
	(segment
		(start 186 155.000001)
		(end 186 155)
		(width 0.256)
		(layer "B.Cu")
		(net 1)
	)
	(segment
		(start 132.303507 145.969992)
		(end 132.874499 145.399)
		(width 0.4)
		(layer "B.Cu")
		(net 1)
	)
	(segment
		(start 206.841 138.7135)
		(end 206.75 138.8045)
		(width 0.256)
		(layer "B.Cu")
		(net 1)
	)
	(segment
		(start 161.65 195.324501)
		(end 161.65 199.25)
		(width 0.22)
		(layer "B.Cu")
		(net 1)
	)
	(segment
		(start 190.5 158.5)
		(end 190 159)
		(width 0.256)
		(layer "B.Cu")
		(net 1)
	)
	(segment
		(start 105.17 159.369)
		(end 105.775 159.369)
		(width 0.1)
		(layer "B.Cu")
		(net 1)
	)
	(segment
		(start 188.88 107.755)
		(end 188.875 107.75)
		(width 0.4)
		(layer "B.Cu")
		(net 1)
	)
	(segment
		(start 197 149)
		(end 196.999999 149)
		(width 0.256)
		(layer "B.Cu")
		(net 1)
	)
	(segment
		(start 206.841 138.232206)
		(end 206.841 137.0045)
		(width 0.256)
		(layer "B.Cu")
		(net 1)
	)
	(segment
		(start 179.5 146.5)
		(end 180 147)
		(width 0.256)
		(layer "B.Cu")
		(net 1)
	)
	(segment
		(start 104.634 152.77)
		(end 104.716 152.852)
		(width 0.4)
		(layer "B.Cu")
		(net 1)
	)
	(segment
		(start 123.89 129.453)
		(end 123.89 130.126)
		(width 0.4)
		(layer "B.Cu")
		(net 1)
	)
	(segment
		(start 254.784499 150.399)
		(end 254.674499 150.509)
		(width 0.256)
		(layer "B.Cu")
		(net 1)
	)
	(segment
		(start 105.17 163.868)
		(end 105.977 163.868)
		(width 0.201)
		(layer "B.Cu")
		(net 1)
	)
	(segment
		(start 135.262656 138.257165)
		(end 135.57266 137.947161)
		(width 0.2)
		(layer "B.Cu")
		(net 1)
	)
	(segment
		(start 201 158)
		(end 201.5 157.5)
		(width 0.256)
		(layer "B.Cu")
		(net 1)
	)
	(segment
		(start 204.5 108.3)
		(end 204.5 107.755)
		(width 0.4)
		(layer "B.Cu")
		(net 1)
	)
	(segment
		(start 251.156 187.338)
		(end 251.09 187.404)
		(width 0.182)
		(layer "B.Cu")
		(net 1)
	)
	(segment
		(start 182 163)
		(end 182.5 162.5)
		(width 0.256)
		(layer "B.Cu")
		(net 1)
	)
	(segment
		(start 190 150)
		(end 189.5 149.5)
		(width 0.256)
		(layer "B.Cu")
		(net 1)
	)
	(segment
		(start 190.5 148.5)
		(end 191 148)
		(width 0.256)
		(layer "B.Cu")
		(net 1)
	)
	(segment
		(start 194 149)
		(end 193.5 149.5)
		(width 0.256)
		(layer "B.Cu")
		(net 1)
	)
	(segment
		(start 259.842 176.599)
		(end 260.534499 176.599)
		(width 0.256)
		(layer "B.Cu")
		(net 1)
	)
	(segment
		(start 201 141.001)
		(end 200.999 141.001)
		(width 0.256)
		(layer "B.Cu")
		(net 1)
	)
	(segment
		(start 123.894 118.509)
		(end 123.8826 118.4976)
		(width 0.4)
		(layer "B.Cu")
		(net 1)
	)
	(segment
		(start 244.21 121.326)
		(end 244.21 122.055)
		(width 0.4)
		(layer "B.Cu")
		(net 1)
	)
	(segment
		(start 191.5 156.5)
		(end 192 156)
		(width 0.256)
		(layer "B.Cu")
		(net 1)
	)
	(segment
		(start 176.5 152.5)
		(end 176.5 153.5)
		(width 0.4)
		(layer "B.Cu")
		(net 1)
	)
	(segment
		(start 206.66 142.16)
		(end 207.292864 142.792864)
		(width 0.256)
		(layer "B.Cu")
		(net 1)
	)
	(segment
		(start 196.002 159)
		(end 196.002 158.998)
		(width 0.256)
		(layer "B.Cu")
		(net 1)
	)
	(segment
		(start 123.893 126.499)
		(end 123.89 126.502)
		(width 0.4)
		(layer "B.Cu")
		(net 1)
	)
	(segment
		(start 240 122.15)
		(end 240 120.915)
		(width 0.4)
		(layer "B.Cu")
		(net 1)
	)
	(segment
		(start 190 146)
		(end 190.5 146.5)
		(width 0.256)
		(layer "B.Cu")
		(net 1)
	)
	(segment
		(start 168.636499 104.1385)
		(end 169.8935 104.138501)
		(width 0.4)
		(layer "B.Cu")
		(net 1)
	)
	(segment
		(start 123.903 101.159)
		(end 123.9 101.162)
		(width 0.4)
		(layer "B.Cu")
		(net 1)
	)
	(segment
		(start 183.502 158.5)
		(end 184 158.002)
		(width 0.256)
		(layer "B.Cu")
		(net 1)
	)
	(segment
		(start 177.65 196.85)
		(end 177.65 199.25)
		(width 0.22)
		(layer "B.Cu")
		(net 1)
	)
	(segment
		(start 194 156)
		(end 194 155.999999)
		(width 0.201)
		(layer "B.Cu")
		(net 1)
	)
	(segment
		(start 253.839499 159.364)
		(end 253.824499 159.349)
		(width 0.256)
		(layer "B.Cu")
		(net 1)
	)
	(segment
		(start 136.433171 145.969992)
		(end 136.954163 145.449)
		(width 0.4)
		(layer "B.Cu")
		(net 1)
	)
	(segment
		(start 125.15 126.499)
		(end 123.893 126.499)
		(width 0.4)
		(layer "B.Cu")
		(net 1)
	)
	(segment
		(start 132.873656 137.999)
		(end 132.624499 138.248157)
		(width 0.256)
		(layer "B.Cu")
		(net 1)
	)
	(segment
		(start 195.1975 196.3975)
		(end 195.65 196.85)
		(width 0.22)
		(layer "B.Cu")
		(net 1)
	)
	(segment
		(start 139.708499 143.649)
		(end 139.708499 144.383)
		(width 0.256)
		(layer "B.Cu")
		(net 1)
	)
	(segment
		(start 204.75 139.0045)
		(end 204.0955 139.0045)
		(width 0.256)
		(layer "B.Cu")
		(net 1)
	)
	(segment
		(start 192 159)
		(end 191.5 158.5)
		(width 0.256)
		(layer "B.Cu")
		(net 1)
	)
	(segment
		(start 135.408499 152.9005)
		(end 136.124499 152.9005)
		(width 0.256)
		(layer "B.Cu")
		(net 1)
	)
	(segment
		(start 122.63 129.456)
		(end 123.887 129.456)
		(width 0.4)
		(layer "B.Cu")
		(net 1)
	)
	(segment
		(start 206.66 141.6045)
		(end 206.66 140.6045)
		(width 0.256)
		(layer "B.Cu")
		(net 1)
	)
	(segment
		(start 195.1975 194.849501)
		(end 195.1975 196.3975)
		(width 0.22)
		(layer "B.Cu")
		(net 1)
	)
	(segment
		(start 114.52 167.911)
		(end 114.52 167.95)
		(width 0.201)
		(layer "B.Cu")
		(net 1)
	)
	(segment
		(start 243.5 100.540001)
		(end 243.53 100.510001)
		(width 0.201)
		(layer "B.Cu")
		(net 1)
	)
	(segment
		(start 192 159)
		(end 192.5 158.5)
		(width 0.256)
		(layer "B.Cu")
		(net 1)
	)
	(segment
		(start 123.9015 101.1605)
		(end 123.9045 101.1575)
		(width 0.4)
		(layer "B.Cu")
		(net 1)
	)
	(segment
		(start 185.002 150.002)
		(end 185.5 150.5)
		(width 0.256)
		(layer "B.Cu")
		(net 1)
	)
	(segment
		(start 136.8925 101.1895)
		(end 136.8955 101.1865)
		(width 0.4)
		(layer "B.Cu")
		(net 1)
	)
	(segment
		(start 174.8 108.3)
		(end 174.8 107.755)
		(width 0.4)
		(layer "B.Cu")
		(net 1)
	)
	(segment
		(start 212.394 154.356)
		(end 212.394 154.425)
		(width 0.177)
		(layer "B.Cu")
		(net 1)
	)
	(segment
		(start 117.999 167.22)
		(end 117.34 167.22)
		(width 0.15)
		(layer "B.Cu")
		(net 1)
	)
	(segment
		(start 187.175 194.849501)
		(end 187.65 195.324501)
		(width 0.22)
		(layer "B.Cu")
		(net 1)
	)
	(segment
		(start 186 149)
		(end 186.5 149.5)
		(width 0.256)
		(layer "B.Cu")
		(net 1)
	)
	(segment
		(start 192.998 159.002)
		(end 193 159)
		(width 0.256)
		(layer "B.Cu")
		(net 1)
	)
	(segment
		(start 177.999999 156.999999)
		(end 177.5 156.5)
		(width 0.4)
		(layer "B.Cu")
		(net 1)
	)
	(segment
		(start 169.175 194.849501)
		(end 169.65 195.324501)
		(width 0.22)
		(layer "B.Cu")
		(net 1)
	)
	(segment
		(start 206.66 138.8945)
		(end 206.75 138.8045)
		(width 0.256)
		(layer "B.Cu")
		(net 1)
	)
	(segment
		(start 187 161)
		(end 187.5 160.5)
		(width 0.256)
		(layer "B.Cu")
		(net 1)
	)
	(segment
		(start 115.705 113.6)
		(end 116.435 113.6)
		(width 0.15)
		(layer "B.Cu")
		(net 1)
	)
	(segment
		(start 183.5 158.5)
		(end 183.502 158.5)
		(width 0.256)
		(layer "B.Cu")
		(net 1)
	)
	(segment
		(start 104.716 168.39)
		(end 105.87 168.39)
		(width 0.4)
		(layer "B.Cu")
		(net 1)
	)
	(segment
		(start 182 159)
		(end 182.5 158.5)
		(width 0.256)
		(layer "B.Cu")
		(net 1)
	)
	(segment
		(start 140.202656 139.267165)
		(end 140.227656 139.242165)
		(width 0.2)
		(layer "B.Cu")
		(net 1)
	)
	(segment
		(start 187.500001 145.5)
		(end 187.55 145.5)
		(width 0.4)
		(layer "B.Cu")
		(net 1)
	)
	(segment
		(start 115.55 159.266)
		(end 115.55 158.427)
		(width 0.256)
		(layer "B.Cu")
		(net 1)
	)
	(segment
		(start 185.5 153.5)
		(end 185.499999 153.5)
		(width 0.256)
		(layer "B.Cu")
		(net 1)
	)
	(segment
		(start 188.5 153.05)
		(end 188.05 153.5)
		(width 0.4)
		(layer "B.Cu")
		(net 1)
	)
	(segment
		(start 186 144.999)
		(end 185.999 144.999)
		(width 0.256)
		(layer "B.Cu")
		(net 1)
	)
	(segment
		(start 237.554497 177.025)
		(end 239.59 177.025)
		(width 0.256)
		(layer "B.Cu")
		(net 1)
	)
	(segment
		(start 196.002 159)
		(end 196 159)
		(width 0.256)
		(layer "B.Cu")
		(net 1)
	)
	(segment
		(start 174.65 195.324501)
		(end 174.65 199.25)
		(width 0.22)
		(layer "B.Cu")
		(net 1)
	)
	(segment
		(start 193 163)
		(end 193.5 162.5)
		(width 0.256)
		(layer "B.Cu")
		(net 1)
	)
	(segment
		(start 119.075 158.97)
		(end 119.075 158.3)
		(width 0.182)
		(layer "B.Cu")
		(net 1)
	)
	(segment
		(start 114.86 168.251)
		(end 114.52 167.911)
		(width 0.201)
		(layer "B.Cu")
		(net 1)
	)
	(segment
		(start 193.5 158.5)
		(end 194 158)
		(width 0.256)
		(layer "B.Cu")
		(net 1)
	)
	(segment
		(start 171.1505 104.1385)
		(end 169.8935 104.138501)
		(width 0.4)
		(layer "B.Cu")
		(net 1)
	)
	(segment
		(start 187.5 158.5)
		(end 189.5 158.5)
		(width 0.4)
		(layer "B.Cu")
		(net 1)
	)
	(segment
		(start 123.894 119.182)
		(end 123.894 118.509)
		(width 0.4)
		(layer "B.Cu")
		(net 1)
	)
	(segment
		(start 123.89 126.502)
		(end 123.89 125.829)
		(width 0.4)
		(layer "B.Cu")
		(net 1)
	)
	(segment
		(start 193.999999 159)
		(end 194 159)
		(width 0.256)
		(layer "B.Cu")
		(net 1)
	)
	(segment
		(start 237.554497 171.475)
		(end 239.59 171.475)
		(width 0.256)
		(layer "B.Cu")
		(net 1)
	)
	(segment
		(start 137.5 152.885)
		(end 136.69 152.885)
		(width 0.256)
		(layer "B.Cu")
		(net 1)
	)
	(segment
		(start 189.3 153.95)
		(end 189.3 154.3)
		(width 0.256)
		(layer "B.Cu")
		(net 1)
	)
	(segment
		(start 122.646 104.11)
		(end 123.903 104.11)
		(width 0.4)
		(layer "B.Cu")
		(net 1)
	)
	(segment
		(start 243.5 101.57)
		(end 243.5 100.540001)
		(width 0.201)
		(layer "B.Cu")
		(net 1)
	)
	(segment
		(start 123.906 104.107)
		(end 123.903 104.11)
		(width 0.4)
		(layer "B.Cu")
		(net 1)
	)
	(segment
		(start 192.5 150.5)
		(end 193 151)
		(width 0.256)
		(layer "B.Cu")
		(net 1)
	)
	(segment
		(start 186 163)
		(end 186.5 162.5)
		(width 0.256)
		(layer "B.Cu")
		(net 1)
	)
	(segment
		(start 180.65 195.324501)
		(end 180.65 199.25)
		(width 0.22)
		(layer "B.Cu")
		(net 1)
	)
	(segment
		(start 113.431 167.12)
		(end 113.431 167.848463)
		(width 0.201)
		(layer "B.Cu")
		(net 1)
	)
	(segment
		(start 181.999999 142)
		(end 181.499999 142.5)
		(width 0.256)
		(layer "B.Cu")
		(net 1)
	)
	(segment
		(start 115.897499 118.149)
		(end 116.624499 118.149)
		(width 0.4)
		(layer "B.Cu")
		(net 1)
	)
	(segment
		(start 139.708499 144.383)
		(end 139.774499 144.449)
		(width 0.256)
		(layer "B.Cu")
		(net 1)
	)
	(segment
		(start 203.6 139.5)
		(end 203.6 140.012268)
		(width 0.256)
		(layer "B.Cu")
		(net 1)
	)
	(segment
		(start 186 156.998)
		(end 186.002 156.998)
		(width 0.256)
		(layer "B.Cu")
		(net 1)
	)
	(segment
		(start 122.646 122.124)
		(end 123.903 122.124)
		(width 0.4)
		(layer "B.Cu")
		(net 1)
	)
	(segment
		(start 203.6 140.012268)
		(end 203.601 140.013268)
		(width 0.256)
		(layer "B.Cu")
		(net 1)
	)
	(segment
		(start 136.8925 101.1895)
		(end 136.8895 101.1925)
		(width 0.4)
		(layer "B.Cu")
		(net 1)
	)
	(segment
		(start 123.9 122.8)
		(end 123.9114 122.8114)
		(width 0.4)
		(layer "B.Cu")
		(net 1)
	)
	(segment
		(start 196.999999 149)
		(end 196.499999 149.5)
		(width 0.256)
		(layer "B.Cu")
		(net 1)
	)
	(segment
		(start 123.8985 100.4905)
		(end 123.8871 100.4791)
		(width 0.4)
		(layer "B.Cu")
		(net 1)
	)
	(segment
		(start 114.86 168.82)
		(end 114.86 168.251)
		(width 0.201)
		(layer "B.Cu")
		(net 1)
	)
	(segment
		(start 182 142)
		(end 181.999999 142)
		(width 0.256)
		(layer "B.Cu")
		(net 1)
	)
	(segment
		(start 195 156)
		(end 194.999999 156)
		(width 0.256)
		(layer "B.Cu")
		(net 1)
	)
	(segment
		(start 177.5 150.5)
		(end 178 150)
		(width 0.256)
		(layer "B.Cu")
		(net 1)
	)
	(segment
		(start 125.16 101.159)
		(end 123.903 101.159)
		(width 0.4)
		(layer "B.Cu")
		(net 1)
	)
	(segment
		(start 169.898001 101.183)
		(end 169.898 100.510001)
		(width 0.4)
		(layer "B.Cu")
		(net 1)
	)
	(segment
		(start 246.925 110.625)
		(end 246.551 110.251)
		(width 0.198)
		(layer "B.Cu")
		(net 1)
	)
	(segment
		(start 194 155.999999)
		(end 194.499999 155.5)
		(width 0.201)
		(layer "B.Cu")
		(net 1)
	)
	(segment
		(start 191.498 162.5)
		(end 191 162.998)
		(width 0.256)
		(layer "B.Cu")
		(net 1)
	)
	(segment
		(start 135.6505 104.1255)
		(end 136.9075 104.1255)
		(width 0.4)
		(layer "B.Cu")
		(net 1)
	)
	(segment
		(start 135.6355 101.1895)
		(end 136.8925 101.1895)
		(width 0.4)
		(layer "B.Cu")
		(net 1)
	)
	(segment
		(start 246.551 110.251)
		(end 246.551 109.446)
		(width 0.198)
		(layer "B.Cu")
		(net 1)
	)
	(segment
		(start 123.903 122.124)
		(end 123.9 122.127)
		(width 0.4)
		(layer "B.Cu")
		(net 1)
	)
	(segment
		(start 124.68 164.05)
		(end 125.35 164.05)
		(width 0.1)
		(layer "B.Cu")
		(net 1)
	)
	(segment
		(start 116.225 117.45)
		(end 115.897499 117.777501)
		(width 0.4)
		(layer "B.Cu")
		(net 1)
	)
	(segment
		(start 243.53 101.6)
		(end 243.5 101.57)
		(width 0.201)
		(layer "B.Cu")
		(net 1)
	)
	(segment
		(start 166.6 150.424)
		(end 166.584 150.44)
		(width 0.4)
		(layer "B.Cu")
		(net 1)
	)
	(segment
		(start 204.0955 139.0045)
		(end 203.6 139.5)
		(width 0.256)
		(layer "B.Cu")
		(net 1)
	)
	(segment
		(start 185.500001 155.5)
		(end 185.000001 156)
		(width 0.256)
		(layer "B.Cu")
		(net 1)
	)
	(segment
		(start 112.67 163.32)
		(end 112.33 163.66)
		(width 0.201)
		(layer "B.Cu")
		(net 1)
	)
	(segment
		(start 131.211328 137.0395)
		(end 131.215828 137.035)
		(width 0.256)
		(layer "B.Cu")
		(net 1)
	)
	(segment
		(start 187.5 150.55)
		(end 188.5 151.55)
		(width 0.4)
		(layer "B.Cu")
		(net 1)
	)
	(segment
		(start 206.6 138.3)
		(end 206.773206 138.3)
		(width 0.256)
		(layer "B.Cu")
		(net 1)
	)
	(segment
		(start 136.888 101.194)
		(end 136.888 100.521)
		(width 0.4)
		(layer "B.Cu")
		(net 1)
	)
	(segment
		(start 123.893 126.499)
		(end 123.89 126.502)
		(width 0.4)
		(layer "B.Cu")
		(net 1)
	)
	(segment
		(start 185.125 194.849501)
		(end 184.65 195.324501)
		(width 0.22)
		(layer "B.Cu")
		(net 1)
	)
	(segment
		(start 201.5 144.5)
		(end 201 144)
		(width 0.256)
		(layer "B.Cu")
		(net 1)
	)
	(segment
		(start 213.05 153.7)
		(end 212.394 154.356)
		(width 0.177)
		(layer "B.Cu")
		(net 1)
	)
	(segment
		(start 259.774499 155.699)
		(end 259.724499 155.649)
		(width 0.256)
		(layer "B.Cu")
		(net 1)
	)
	(segment
		(start 260.358499 155.699)
		(end 259.774499 155.699)
		(width 0.256)
		(layer "B.Cu")
		(net 1)
	)
	(segment
		(start 253.57 122.23)
		(end 253.57 122.225)
		(width 0.198)
		(layer "B.Cu")
		(net 1)
	)
	(segment
		(start 190.002 148.998)
		(end 190.5 148.5)
		(width 0.256)
		(layer "B.Cu")
		(net 1)
	)
	(segment
		(start 123.897 119.179)
		(end 123.9 119.176)
		(width 0.4)
		(layer "B.Cu")
		(net 1)
	)
	(segment
		(start 147.214499 164.999)
		(end 146.598499 164.999)
		(width 0.15)
		(layer "B.Cu")
		(net 1)
	)
	(segment
		(start 221.635 176.534)
		(end 221.635 176.26)
		(width 0.15)
		(layer "B.Cu")
		(net 1)
	)
	(segment
		(start 256.338998 140.25)
		(end 256.323998 140.265)
		(width 0.182)
		(layer "B.Cu")
		(net 1)
	)
	(segment
		(start 200.998 155)
		(end 201 155)
		(width 0.256)
		(layer "B.Cu")
		(net 1)
	)
	(segment
		(start 115.705 105.5)
		(end 116.435 105.5)
		(width 0.15)
		(layer "B.Cu")
		(net 1)
	)
	(segment
		(start 139.708499 146.33)
		(end 139.708499 146.6)
		(width 0.256)
		(layer "B.Cu")
		(net 1)
	)
	(segment
		(start 164.6 155)
		(end 164.046 155)
		(width 0.4)
		(layer "B.Cu")
		(net 1)
	)
	(segment
		(start 185.5 150.5)
		(end 185.500001 150.5)
		(width 0.256)
		(layer "B.Cu")
		(net 1)
	)
	(segment
		(start 169.907 101.174001)
		(end 169.904 101.177)
		(width 0.4)
		(layer "B.Cu")
		(net 1)
	)
	(segment
		(start 138.1495 101.1895)
		(end 136.8925 101.1895)
		(width 0.4)
		(layer "B.Cu")
		(net 1)
	)
	(segment
		(start 193.5 156.5)
		(end 194 156)
		(width 0.256)
		(layer "B.Cu")
		(net 1)
	)
	(segment
		(start 253.57 122.225)
		(end 253.57 121.496)
		(width 0.198)
		(layer "B.Cu")
		(net 1)
	)
	(segment
		(start 124.68 162.5)
		(end 125.35 162.5)
		(width 0.1)
		(layer "B.Cu")
		(net 1)
	)
	(segment
		(start 190 159)
		(end 189.5 158.5)
		(width 0.256)
		(layer "B.Cu")
		(net 1)
	)
	(segment
		(start 136.891 101.191)
		(end 136.888 101.194)
		(width 0.4)
		(layer "B.Cu")
		(net 1)
	)
	(segment
		(start 191.65 195.300001)
		(end 191.65 199.25)
		(width 0.22)
		(layer "B.Cu")
		(net 1)
	)
	(segment
		(start 123.9 104.113)
		(end 123.903 104.11)
		(width 0.4)
		(layer "B.Cu")
		(net 1)
	)
	(segment
		(start 193.5 154.5)
		(end 193 154)
		(width 0.256)
		(layer "B.Cu")
		(net 1)
	)
	(segment
		(start 178.5 143.5)
		(end 179 143)
		(width 0.256)
		(layer "B.Cu")
		(net 1)
	)
	(segment
		(start 184 149)
		(end 184.5 149.5)
		(width 0.256)
		(layer "B.Cu")
		(net 1)
	)
	(segment
		(start 190.5 160.5)
		(end 191 160)
		(width 0.256)
		(layer "B.Cu")
		(net 1)
	)
	(segment
		(start 189.3 154.3)
		(end 189.5 154.5)
		(width 0.256)
		(layer "B.Cu")
		(net 1)
	)
	(segment
		(start 184.5 146.5)
		(end 184.5 146.500001)
		(width 0.256)
		(layer "B.Cu")
		(net 1)
	)
	(segment
		(start 174.9 158.5)
		(end 174.6 158.8)
		(width 0.4)
		(layer "B.Cu")
		(net 1)
	)
	(segment
		(start 253.839499 177.624)
		(end 253.839499 176.812)
		(width 0.256)
		(layer "B.Cu")
		(net 1)
	)
	(segment
		(start 254.674499 150.509)
		(end 254.674499 151.099)
		(width 0.256)
		(layer "B.Cu")
		(net 1)
	)
	(segment
		(start 140.14 146.33)
		(end 139.708499 146.33)
		(width 0.256)
		(layer "B.Cu")
		(net 1)
	)
	(segment
		(start 186.5 158.5)
		(end 187 159)
		(width 0.256)
		(layer "B.Cu")
		(net 1)
	)
	(segment
		(start 206.34 151.15)
		(end 206.64 151.45)
		(width 0.114)
		(layer "B.Cu")
		(net 1)
	)
	(segment
		(start 249.895 121.496)
		(end 249.725 121.326)
		(width 0.198)
		(layer "B.Cu")
		(net 1)
	)
	(segment
		(start 115.705 116.3)
		(end 116.435 116.3)
		(width 0.15)
		(layer "B.Cu")
		(net 1)
	)
	(segment
		(start 105.95 166.27)
		(end 105.17 166.27)
		(width 0.4)
		(layer "B.Cu")
		(net 1)
	)
	(segment
		(start 173.65 195.300001)
		(end 173.65 199.25)
		(width 0.22)
		(layer "B.Cu")
		(net 1)
	)
	(segment
		(start 187 146.000001)
		(end 187.500001 145.5)
		(width 0.256)
		(layer "B.Cu")
		(net 1)
	)
	(segment
		(start 181.5 153.5)
		(end 181.5 153.475)
		(width 0.4)
		(layer "B.Cu")
		(net 1)
	)
	(segment
		(start 119.91 126.282383)
		(end 119.91 127.01692)
		(width 0.4)
		(layer "B.Cu")
		(net 1)
	)
	(segment
		(start 260.534499 176.599)
		(end 260.549499 176.584)
		(width 0.256)
		(layer "B.Cu")
		(net 1)
	)
	(segment
		(start 249.895 122.915)
		(end 249.89 122.92)
		(width 0.198)
		(layer "B.Cu")
		(net 1)
	)
	(segment
		(start 136.897 101.185)
		(end 136.894 101.188)
		(width 0.4)
		(layer "B.Cu")
		(net 1)
	)
	(segment
		(start 206.841 136.0045)
		(end 206.841 137.0045)
		(width 0.256)
		(layer "B.Cu")
		(net 1)
	)
	(segment
		(start 180 149.999)
		(end 180.001 149.999)
		(width 0.256)
		(layer "B.Cu")
		(net 1)
	)
	(segment
		(start 198 145)
		(end 198.5 145.5)
		(width 0.256)
		(layer "B.Cu")
		(net 1)
	)
	(segment
		(start 195 149)
		(end 194.5 148.5)
		(width 0.256)
		(layer "B.Cu")
		(net 1)
	)
	(segment
		(start 122.646 119.173)
		(end 123.903 119.173)
		(width 0.4)
		(layer "B.Cu")
		(net 1)
	)
	(segment
		(start 119.075 158.3)
		(end 119.625 157.75)
		(width 0.182)
		(layer "B.Cu")
		(net 1)
	)
	(segment
		(start 193.000001 151)
		(end 193.500001 151.5)
		(width 0.256)
		(layer "B.Cu")
		(net 1)
	)
	(segment
		(start 195 163)
		(end 195.5 162.5)
		(width 0.256)
		(layer "B.Cu")
		(net 1)
	)
	(segment
		(start 148.65 199.25)
		(end 148.65 196.3)
		(width 0.4)
		(layer "B.Cu")
		(net 1)
	)
	(segment
		(start 139.487656 139.267165)
		(end 140.202656 139.267165)
		(width 0.2)
		(layer "B.Cu")
		(net 1)
	)
	(segment
		(start 249.89 122.92)
		(end 250.37 123.4)
		(width 0.198)
		(layer "B.Cu")
		(net 1)
	)
	(segment
		(start 249.895 122.225)
		(end 249.895 122.915)
		(width 0.198)
		(layer "B.Cu")
		(net 1)
	)
	(segment
		(start 247.365 110.625)
		(end 246.925 110.625)
		(width 0.198)
		(layer "B.Cu")
		(net 1)
	)
	(segment
		(start 125.16 104.11)
		(end 123.903 104.11)
		(width 0.4)
		(layer "B.Cu")
		(net 1)
	)
	(segment
		(start 185.5 148.5)
		(end 186 149)
		(width 0.256)
		(layer "B.Cu")
		(net 1)
	)
	(segment
		(start 148.074499 160.917)
		(end 149.084499 160.917)
		(width 0.15)
		(layer "B.Cu")
		(net 1)
	)
	(segment
		(start 193 159)
		(end 192.5 158.5)
		(width 0.256)
		(layer "B.Cu")
		(net 1)
	)
	(segment
		(start 192 154)
		(end 192.5 153.5)
		(width 0.256)
		(layer "B.Cu")
		(net 1)
	)
	(segment
		(start 169.898 100.510001)
		(end 169.8866 100.498601)
		(width 0.4)
		(layer "B.Cu")
		(net 1)
	)
	(segment
		(start 185.5 153.5)
		(end 185.5 152.85)
		(width 0.4)
		(layer "B.Cu")
		(net 1)
	)
	(segment
		(start 243.03 121.78)
		(end 242.12 121.78)
		(width 0.4)
		(layer "B.Cu")
		(net 1)
	)
	(segment
		(start 132.274499 145.969992)
		(end 132.303507 145.969992)
		(width 0.4)
		(layer "B.Cu")
		(net 1)
	)
	(segment
		(start 183.65 195.324501)
		(end 183.65 199.25)
		(width 0.22)
		(layer "B.Cu")
		(net 1)
	)
	(segment
		(start 254.804499 139.38)
		(end 255.689499 140.265)
		(width 0.256)
		(layer "B.Cu")
		(net 1)
	)
	(segment
		(start 188.5 153.05)
		(end 188.5 153.15)
		(width 0.256)
		(layer "B.Cu")
		(net 1)
	)
	(segment
		(start 191.500001 149.5)
		(end 191.500001 149.499999)
		(width 0.256)
		(layer "B.Cu")
		(net 1)
	)
	(segment
		(start 136.458499 137.999)
		(end 136.724499 138.265)
		(width 0.2)
		(layer "B.Cu")
		(net 1)
	)
	(segment
		(start 204.5 155.5)
		(end 202.5 155.5)
		(width 0.4)
		(layer "B.Cu")
		(net 1)
	)
	(segment
		(start 193 148)
		(end 192.5 148.5)
		(width 0.256)
		(layer "B.Cu")
		(net 1)
	)
	(segment
		(start 193 151)
		(end 193.000001 151)
		(width 0.256)
		(layer "B.Cu")
		(net 1)
	)
	(segment
		(start 175.5 144.5)
		(end 176 145)
		(width 0.256)
		(layer "B.Cu")
		(net 1)
	)
	(segment
		(start 206.66 140.6045)
		(end 206.66 138.8945)
		(width 0.256)
		(layer "B.Cu")
		(net 1)
	)
	(segment
		(start 237.276998 176.747501)
		(end 237.554497 177.025)
		(width 0.256)
		(layer "B.Cu")
		(net 1)
	)
	(segment
		(start 186.5 154.499999)
		(end 187 153.999999)
		(width 0.256)
		(layer "B.Cu")
		(net 1)
	)
	(segment
		(start 131.77 140.874821)
		(end 132.052656 140.592165)
		(width 0.256)
		(layer "B.Cu")
		(net 1)
	)
	(segment
		(start 123.903 104.11)
		(end 123.9 104.113)
		(width 0.4)
		(layer "B.Cu")
		(net 1)
	)
	(segment
		(start 123.887 129.456)
		(end 123.884 129.459)
		(width 0.4)
		(layer "B.Cu")
		(net 1)
	)
	(segment
		(start 191.5 154.5)
		(end 192 154)
		(width 0.256)
		(layer "B.Cu")
		(net 1)
	)
	(segment
		(start 259.825499 173.174)
		(end 259.751499 173.1)
		(width 0.256)
		(layer "B.Cu")
		(net 1)
	)
	(segment
		(start 184.5 149.5)
		(end 185 150)
		(width 0.256)
		(layer "B.Cu")
		(net 1)
	)
	(segment
		(start 180.001 149.999)
		(end 180.5 149.5)
		(width 0.256)
		(layer "B.Cu")
		(net 1)
	)
	(segment
		(start 192.998 160)
		(end 192.998 159.002)
		(width 0.256)
		(layer "B.Cu")
		(net 1)
	)
	(segment
		(start 136.891 101.191)
		(end 136.894 101.188)
		(width 0.4)
		(layer "B.Cu")
		(net 1)
	)
	(segment
		(start 123.903 119.173)
		(end 123.9 119.176)
		(width 0.4)
		(layer "B.Cu")
		(net 1)
	)
	(segment
		(start 102.35 152.77)
		(end 104.634 152.77)
		(width 0.4)
		(layer "B.Cu")
		(net 1)
	)
	(segment
		(start 187.000002 153.999999)
		(end 187.500001 153.5)
		(width 0.256)
		(layer "B.Cu")
		(net 1)
	)
	(segment
		(start 206.841 136.0045)
		(end 206.841 135.215503)
		(width 0.256)
		(layer "B.Cu")
		(net 1)
	)
	(segment
		(start 148.725 193.325)
		(end 148.725 193.841)
		(width 0.201)
		(layer "B.Cu")
		(net 1)
	)
	(segment
		(start 239.1 120.94)
		(end 239.675 120.94)
		(width 0.4)
		(layer "B.Cu")
		(net 1)
	)
	(segment
		(start 115.897499 117.777501)
		(end 115.897499 118.149)
		(width 0.4)
		(layer "B.Cu")
		(net 1)
	)
	(segment
		(start 188.5 155.55)
		(end 188.55 155.55)
		(width 0.4)
		(layer "B.Cu")
		(net 1)
	)
	(segment
		(start 136.69 152.885)
		(end 136.675 152.9)
		(width 0.256)
		(layer "B.Cu")
		(net 1)
	)
	(segment
		(start 175.125 194.849501)
		(end 174.65 195.324501)
		(width 0.22)
		(layer "B.Cu")
		(net 1)
	)
	(segment
		(start 139.708499 144.515)
		(end 139.774499 144.449)
		(width 0.256)
		(layer "B.Cu")
		(net 1)
	)
	(segment
		(start 133.912171 137.999)
		(end 134.161328 138.248157)
		(width 0.256)
		(layer "B.Cu")
		(net 1)
	)
	(segment
		(start 123.909 104.104)
		(end 123.909 104.777)
		(width 0.4)
		(layer "B.Cu")
		(net 1)
	)
	(segment
		(start 201.5 149.5)
		(end 201.7 149.5)
		(width 0.4)
		(layer "B.Cu")
		(net 1)
	)
	(segment
		(start 133.433171 145.969992)
		(end 133.433171 145.890328)
		(width 0.4)
		(layer "B.Cu")
		(net 1)
	)
	(segment
		(start 125.389 127.978)
		(end 128.389 127.978)
		(width 0.256)
		(layer "B.Cu")
		(net 1)
	)
	(segment
		(start 131.233171 145.969992)
		(end 132.274499 145.969992)
		(width 0.4)
		(layer "B.Cu")
		(net 1)
	)
	(segment
		(start 105.17 154.969)
		(end 105.949 154.969)
		(width 0.4)
		(layer "B.Cu")
		(net 1)
	)
	(segment
		(start 206.64 151.45)
		(end 207.94 151.45)
		(width 0.4)
		(layer "B.Cu")
		(net 1)
	)
	(segment
		(start 192.5 148.5)
		(end 192 149)
		(width 0.256)
		(layer "B.Cu")
		(net 1)
	)
	(segment
		(start 239.59 177.025)
		(end 239.64 176.975)
		(width 0.256)
		(layer "B.Cu")
		(net 1)
	)
	(segment
		(start 194.5 143.5)
		(end 194.499 143.5)
		(width 0.256)
		(layer "B.Cu")
		(net 1)
	)
	(segment
		(start 135.048171 143.249)
		(end 135.383171 142.914)
		(width 0.256)
		(layer "B.Cu")
		(net 1)
	)
	(segment
		(start 165.125 194.824501)
		(end 164.65 195.299501)
		(width 0.22)
		(layer "B.Cu")
		(net 1)
	)
	(segment
		(start 188.95 146)
		(end 188.5 146.45)
		(width 0.256)
		(layer "B.Cu")
		(net 1)
	)
	(segment
		(start 130.211328 137.598157)
		(end 130.211328 137.028672)
		(width 0.256)
		(layer "B.Cu")
		(net 1)
	)
	(segment
		(start 120.125 158.15)
		(end 119.625 157.65)
		(width 0.182)
		(layer "B.Cu")
		(net 1)
	)
	(segment
		(start 193 159)
		(end 193.5 158.5)
		(width 0.256)
		(layer "B.Cu")
		(net 1)
	)
	(segment
		(start 194 155.000001)
		(end 194.499999 155.5)
		(width 0.256)
		(layer "B.Cu")
		(net 1)
	)
	(segment
		(start 191.500001 162.5)
		(end 191.498 162.5)
		(width 0.256)
		(layer "B.Cu")
		(net 1)
	)
	(segment
		(start 135.433171 145.969992)
		(end 135.433171 145.890328)
		(width 0.4)
		(layer "B.Cu")
		(net 1)
	)
	(segment
		(start 256.323998 140.265)
		(end 255.689499 140.265)
		(width 0.182)
		(layer "B.Cu")
		(net 1)
	)
	(segment
		(start 187 156)
		(end 187.5 155.5)
		(width 0.256)
		(layer "B.Cu")
		(net 1)
	)
	(segment
		(start 111.53 163.66)
		(end 112.33 163.66)
		(width 0.201)
		(layer "B.Cu")
		(net 1)
	)
	(segment
		(start 189.5 149.498)
		(end 190 148.998)
		(width 0.256)
		(layer "B.Cu")
		(net 1)
	)
	(segment
		(start 185.500001 150.5)
		(end 186.002 151.001999)
		(width 0.256)
		(layer "B.Cu")
		(net 1)
	)
	(segment
		(start 260.4735 159.124)
		(end 260.5055 159.156)
		(width 0.256)
		(layer "B.Cu")
		(net 1)
	)
	(segment
		(start 184.5 146.5)
		(end 185 146)
		(width 0.256)
		(layer "B.Cu")
		(net 1)
	)
	(segment
		(start 254.699499 168.552)
		(end 254.651499 168.6)
		(width 0.256)
		(layer "B.Cu")
		(net 1)
	)
	(segment
		(start 191.500001 149.499999)
		(end 192 149)
		(width 0.256)
		(layer "B.Cu")
		(net 1)
	)
	(segment
		(start 187.5 150.5)
		(end 187.5 150.500001)
		(width 0.256)
		(layer "B.Cu")
		(net 1)
	)
	(segment
		(start 136.024499 137.999)
		(end 136.458499 137.999)
		(width 0.2)
		(layer "B.Cu")
		(net 1)
	)
	(segment
		(start 167.125 194.849501)
		(end 166.65 195.324501)
		(width 0.22)
		(layer "B.Cu")
		(net 1)
	)
	(segment
		(start 198 159)
		(end 198 158.999)
		(width 0.256)
		(layer "B.Cu")
		(net 1)
	)
	(segment
		(start 149.084499 166.329984)
		(end 149.105843 166.351328)
		(width 0.15)
		(layer "B.Cu")
		(net 1)
	)
	(segment
		(start 122.636 126.499)
		(end 123.893 126.499)
		(width 0.4)
		(layer "B.Cu")
		(net 1)
	)
	(segment
		(start 134.433171 145.890328)
		(end 134.924499 145.399)
		(width 0.4)
		(layer "B.Cu")
		(net 1)
	)
	(segment
		(start 186 155)
		(end 186.5 154.5)
		(width 0.256)
		(layer "B.Cu")
		(net 1)
	)
	(segment
		(start 254.699499 167.959)
		(end 254.699499 168.552)
		(width 0.256)
		(layer "B.Cu")
		(net 1)
	)
	(segment
		(start 191.1995 194.849501)
		(end 191.65 195.300001)
		(width 0.22)
		(layer "B.Cu")
		(net 1)
	)
	(segment
		(start 174.8 107.755)
		(end 174.795 107.75)
		(width 0.4)
		(layer "B.Cu")
		(net 1)
	)
	(segment
		(start 185.825 152.175)
		(end 186.5 151.5)
		(width 0.4)
		(layer "B.Cu")
		(net 1)
	)
	(segment
		(start 164.65 195.349501)
		(end 164.125 194.824501)
		(width 0.22)
		(layer "B.Cu")
		(net 1)
	)
	(segment
		(start 189.5 154.5)
		(end 190 154)
		(width 0.256)
		(layer "B.Cu")
		(net 1)
	)
	(segment
		(start 212.395 151.875)
		(end 212.475 151.875)
		(width 0.177)
		(layer "B.Cu")
		(net 1)
	)
	(segment
		(start 188.5 153.05)
		(end 188.5 151.55)
		(width 0.4)
		(layer "B.Cu")
		(net 1)
	)
	(segment
		(start 136.888 100.521)
		(end 136.8766 100.5096)
		(width 0.4)
		(layer "B.Cu")
		(net 1)
	)
	(segment
		(start 123.903 122.124)
		(end 123.906 122.121)
		(width 0.4)
		(layer "B.Cu")
		(net 1)
	)
	(segment
		(start 162.125 194.849501)
		(end 161.65 195.324501)
		(width 0.22)
		(layer "B.Cu")
		(net 1)
	)
	(segment
		(start 185.500001 155.5)
		(end 186 155.000001)
		(width 0.256)
		(layer "B.Cu")
		(net 1)
	)
	(segment
		(start 188 148.5)
		(end 188.5 149)
		(width 0.4)
		(layer "B.Cu")
		(net 1)
	)
	(segment
		(start 192 144)
		(end 192 144.000001)
		(width 0.256)
		(layer "B.Cu")
		(net 1)
	)
	(segment
		(start 102.43 168.39)
		(end 102.35 168.47)
		(width 0.4)
		(layer "B.Cu")
		(net 1)
	)
	(segment
		(start 119.625 157.75)
		(end 119.625 157.65)
		(width 0.182)
		(layer "B.Cu")
		(net 1)
	)
	(segment
		(start 136.954163 145.449)
		(end 137.274499 145.449)
		(width 0.4)
		(layer "B.Cu")
		(net 1)
	)
	(segment
		(start 130.211328 137.028672)
		(end 130.215 137.025)
		(width 0.256)
		(layer "B.Cu")
		(net 1)
	)
	(segment
		(start 184.5 154.5)
		(end 184.5 154.500001)
		(width 0.256)
		(layer "B.Cu")
		(net 1)
	)
	(segment
		(start 187.5 148.5)
		(end 188 148.5)
		(width 0.4)
		(layer "B.Cu")
		(net 1)
	)
	(segment
		(start 181 150)
		(end 180.5 149.5)
		(width 0.4)
		(layer "B.Cu")
		(net 1)
	)
	(segment
		(start 127.661328 139.882157)
		(end 127.661328 139.582157)
		(width 0.2)
		(layer "B.Cu")
		(net 1)
	)
	(segment
		(start 131.77 141.056)
		(end 131.77 140.874821)
		(width 0.256)
		(layer "B.Cu")
		(net 1)
	)
	(segment
		(start 191 156)
		(end 191.5 156.5)
		(width 0.256)
		(layer "B.Cu")
		(net 1)
	)
	(segment
		(start 207.29 155.14)
		(end 207.29 154.67)
		(width 0.4)
		(layer "B.Cu")
		(net 1)
	)
	(segment
		(start 123.9 104.113)
		(end 123.897 104.116)
		(width 0.4)
		(layer "B.Cu")
		(net 1)
	)
	(segment
		(start 138.1645 104.1255)
		(end 136.9075 104.1255)
		(width 0.4)
		(layer "B.Cu")
		(net 1)
	)
	(segment
		(start 192 150.002)
		(end 192.002 150.002)
		(width 0.256)
		(layer "B.Cu")
		(net 1)
	)
	(segment
		(start 253.839499 160.174)
		(end 253.839499 159.364)
		(width 0.256)
		(layer "B.Cu")
		(net 1)
	)
	(segment
		(start 196 148.999)
		(end 196 149.000001)
		(width 0.198)
		(layer "B.Cu")
		(net 1)
	)
	(segment
		(start 169.865 158.45)
		(end 170.4 158.45)
		(width 0.256)
		(layer "B.Cu")
		(net 1)
	)
	(segment
		(start 123.906 104.107)
		(end 123.909 104.104)
		(width 0.4)
		(layer "B.Cu")
		(net 1)
	)
	(segment
		(start 136.897 101.185)
		(end 136.9 101.182)
		(width 0.4)
		(layer "B.Cu")
		(net 1)
	)
	(segment
		(start 142.75 152.885)
		(end 137.5 152.885)
		(width 0.256)
		(layer "B.Cu")
		(net 1)
	)
	(segment
		(start 184.5 154.5)
		(end 184.5 154.499999)
		(width 0.256)
		(layer "B.Cu")
		(net 1)
	)
	(segment
		(start 190.5 150.5)
		(end 190 150)
		(width 0.256)
		(layer "B.Cu")
		(net 1)
	)
	(segment
		(start 212.025 155.625)
		(end 212.025 154.875)
		(width 0.177)
		(layer "B.Cu")
		(net 1)
	)
	(segment
		(start 148.725 193.841)
		(end 148.759 193.875)
		(width 0.201)
		(layer "B.Cu")
		(net 1)
	)
	(segment
		(start 115.897499 119.134)
		(end 115.882499 119.149)
		(width 0.4)
		(layer "B.Cu")
		(net 1)
	)
	(segment
		(start 239.59 171.475)
		(end 239.64 171.425)
		(width 0.256)
		(layer "B.Cu")
		(net 1)
	)
	(segment
		(start 197.5 153.501)
		(end 197.999 154)
		(width 0.256)
		(layer "B.Cu")
		(net 1)
	)
	(segment
		(start 187 159)
		(end 187.5 158.5)
		(width 0.256)
		(layer "B.Cu")
		(net 1)
	)
	(segment
		(start 180.999 149)
		(end 180.999 149.001)
		(width 0.198)
		(layer "B.Cu")
		(net 1)
	)
	(segment
		(start 125.144 129.456)
		(end 123.887 129.456)
		(width 0.4)
		(layer "B.Cu")
		(net 1)
	)
	(segment
		(start 206.75 138.8045)
		(end 205.7 138.8045)
		(width 0.256)
		(layer "B.Cu")
		(net 1)
	)
	(segment
		(start 185.5005 160.4995)
		(end 185.5005 160.5005)
		(width 0.256)
		(layer "B.Cu")
		(net 1)
	)
	(segment
		(start 192 150.002)
		(end 192 149.999999)
		(width 0.256)
		(layer "B.Cu")
		(net 1)
	)
	(segment
		(start 135.57266 137.947161)
		(end 135.97266 137.947161)
		(width 0.2)
		(layer "B.Cu")
		(net 1)
	)
	(segment
		(start 195 163.000001)
		(end 195 163)
		(width 0.256)
		(layer "B.Cu")
		(net 1)
	)
	(segment
		(start 260.524499 155.865)
		(end 260.358499 155.699)
		(width 0.256)
		(layer "B.Cu")
		(net 1)
	)
	(segment
		(start 139.708499 146.6)
		(end 139.708499 145.6)
		(width 0.256)
		(layer "B.Cu")
		(net 1)
	)
	(segment
		(start 123.893 126.499)
		(end 123.896 126.496)
		(width 0.4)
		(layer "B.Cu")
		(net 1)
	)
	(segment
		(start 221.485 176.11)
		(end 221.8 176.425)
		(width 0.1)
		(layer "In2.Cu")
		(net 1)
	)
	(segment
		(start 184.1 157.630331)
		(end 184.1 153.369669)
		(width 0.1)
		(layer "In2.Cu")
		(net 1)
	)
	(segment
		(start 186.782842 157.9)
		(end 184.369669 157.9)
		(width 0.1)
		(layer "In2.Cu")
		(net 1)
	)
	(segment
		(start 221.8 177.292158)
		(end 221.617158 177.475)
		(width 0.1)
		(layer "In2.Cu")
		(net 1)
	)
	(segment
		(start 221.617158 177.475)
		(end 210.375 177.475)
		(width 0.1)
		(layer "In2.Cu")
		(net 1)
	)
	(segment
		(start 205.7 182.15)
		(end 192.5 182.15)
		(width 0.1)
		(layer "In2.Cu")
		(net 1)
	)
	(segment
		(start 210.375 177.475)
		(end 205.7 182.15)
		(width 0.1)
		(layer "In2.Cu")
		(net 1)
	)
	(segment
		(start 184.819669 152.65)
		(end 185.55 152.65)
		(width 0.1)
		(layer "In2.Cu")
		(net 1)
	)
	(segment
		(start 185.55 152.65)
		(end 186.099999 152.100001)
		(width 0.1)
		(layer "In2.Cu")
		(net 1)
	)
	(segment
		(start 187.1 158.217158)
		(end 186.782842 157.9)
		(width 0.1)
		(layer "In2.Cu")
		(net 1)
	)
	(segment
		(start 187.1 176.75)
		(end 187.1 158.217158)
		(width 0.1)
		(layer "In2.Cu")
		(net 1)
	)
	(segment
		(start 186.099999 151.625)
		(end 186.224999 151.5)
		(width 0.1)
		(layer "In2.Cu")
		(net 1)
	)
	(segment
		(start 184.1 153.369669)
		(end 184.819669 152.65)
		(width 0.1)
		(layer "In2.Cu")
		(net 1)
	)
	(segment
		(start 186.099999 152.100001)
		(end 186.099999 151.625)
		(width 0.1)
		(layer "In2.Cu")
		(net 1)
	)
	(segment
		(start 221.8 176.425)
		(end 221.8 177.292158)
		(width 0.1)
		(layer "In2.Cu")
		(net 1)
	)
	(segment
		(start 184.369669 157.9)
		(end 184.1 157.630331)
		(width 0.1)
		(layer "In2.Cu")
		(net 1)
	)
	(segment
		(start 186.224999 151.5)
		(end 186.5 151.5)
		(width 0.1)
		(layer "In2.Cu")
		(net 1)
	)
	(segment
		(start 192.5 182.15)
		(end 187.1 176.75)
		(width 0.1)
		(layer "In2.Cu")
		(net 1)
	)
	(segment
		(start 106.163999 146.001999)
		(end 105.077498 146.001999)
		(width 0.256)
		(layer "F.Cu")
		(net 2)
	)
	(segment
		(start 105.077498 146.001999)
		(end 104.324499 145.249)
		(width 0.256)
		(layer "F.Cu")
		(net 2)
	)
	(segment
		(start 107.508499 141.365)
		(end 108.224499 140.649)
		(width 0.4)
		(layer "F.Cu")
		(net 2)
	)
	(segment
		(start 108.524499 141.049)
		(end 109.924499 141.049)
		(width 0.182)
		(layer "F.Cu")
		(net 2)
	)
	(segment
		(start 106.655 141.365)
		(end 107.508499 141.365)
		(width 0.4)
		(layer "F.Cu")
		(net 2)
	)
	(segment
		(start 104.324499 142.049)
		(end 104.846498 141.527001)
		(width 0.256)
		(layer "F.Cu")
		(net 2)
	)
	(segment
		(start 109.274499 138.598)
		(end 109.273499 138.599)
		(width 0.15)
		(layer "F.Cu")
		(net 2)
	)
	(segment
		(start 110.772499 138.599)
		(end 110.773499 138.598)
		(width 0.4)
		(layer "F.Cu")
		(net 2)
	)
	(segment
		(start 107.373 146.163)
		(end 108.139 146.929)
		(width 0.256)
		(layer "F.Cu")
		(net 2)
	)
	(segment
		(start 109.274499 137.449)
		(end 109.274499 138.598)
		(width 0.15)
		(layer "F.Cu")
		(net 2)
	)
	(segment
		(start 108.139 146.929)
		(end 108.139 146.96)
		(width 0.256)
		(layer "F.Cu")
		(net 2)
	)
	(segment
		(start 104.846498 141.527001)
		(end 106.162999 141.527001)
		(width 0.256)
		(layer "F.Cu")
		(net 2)
	)
	(segment
		(start 108.224499 140.649)
		(end 108.424499 140.449)
		(width 0.4)
		(layer "F.Cu")
		(net 2)
	)
	(segment
		(start 108.224499 140.749)
		(end 108.524499 141.049)
		(width 0.182)
		(layer "F.Cu")
		(net 2)
	)
	(segment
		(start 104.324499 145.249)
		(end 104.324499 142.049)
		(width 0.256)
		(layer "F.Cu")
		(net 2)
	)
	(segment
		(start 106.325 146.163)
		(end 107.373 146.163)
		(width 0.256)
		(layer "F.Cu")
		(net 2)
	)
	(segment
		(start 109.074499 138.599)
		(end 109.273499 138.599)
		(width 0.4)
		(layer "F.Cu")
		(net 2)
	)
	(segment
		(start 110.475499 140.498)
		(end 109.924499 141.049)
		(width 0.182)
		(layer "F.Cu")
		(net 2)
	)
	(segment
		(start 106.325 146.163)
		(end 106.163999 146.001999)
		(width 0.256)
		(layer "F.Cu")
		(net 2)
	)
	(segment
		(start 109.273499 138.599)
		(end 110.772499 138.599)
		(width 0.4)
		(layer "F.Cu")
		(net 2)
	)
	(segment
		(start 108.424499 140.449)
		(end 108.424499 139.249)
		(width 0.4)
		(layer "F.Cu")
		(net 2)
	)
	(segment
		(start 108.224499 140.649)
		(end 108.224499 140.749)
		(width 0.182)
		(layer "F.Cu")
		(net 2)
	)
	(segment
		(start 110.773499 140.498)
		(end 110.475499 140.498)
		(width 0.182)
		(layer "F.Cu")
		(net 2)
	)
	(segment
		(start 108.424499 139.249)
		(end 109.074499 138.599)
		(width 0.4)
		(layer "F.Cu")
		(net 2)
	)
	(segment
		(start 106.162999 141.527001)
		(end 106.325 141.365)
		(width 0.256)
		(layer "F.Cu")
		(net 2)
	)
	(segment
		(start 136.107 164)
		(end 134.8135 164)
		(width 0.256)
		(layer "F.Cu")
		(net 3)
	)
	(segment
		(start 136.523 163.584)
		(end 136.107 164)
		(width 0.256)
		(layer "F.Cu")
		(net 3)
	)
	(segment
		(start 133.816 164)
		(end 133.815 164.001)
		(width 0.256)
		(layer "F.Cu")
		(net 3)
	)
	(segment
		(start 134.8135 164)
		(end 133.816 164)
		(width 0.256)
		(layer "F.Cu")
		(net 3)
	)
	(segment
		(start 137.746 163.584)
		(end 136.523 163.584)
		(width 0.256)
		(layer "F.Cu")
		(net 3)
	)
	(segment
		(start 132.53 164.001)
		(end 132.435 164.096)
		(width 0.256)
		(layer "F.Cu")
		(net 3)
	)
	(segment
		(start 133.815 164.001)
		(end 132.53 164.001)
		(width 0.256)
		(layer "F.Cu")
		(net 3)
	)
	(segment
		(start 137.7465 160.585)
		(end 136.550515 160.585)
		(width 0.15)
		(layer "F.Cu")
		(net 4)
	)
	(segment
		(start 137.180485 156.484)
		(end 135.983 156.484)
		(width 0.15)
		(layer "F.Cu")
		(net 4)
	)
	(segment
		(start 135.973 160.007485)
		(end 135.973 156.474)
		(width 0.15)
		(layer "F.Cu")
		(net 4)
	)
	(segment
		(start 136.550515 160.585)
		(end 135.973 160.007485)
		(width 0.15)
		(layer "F.Cu")
		(net 4)
	)
	(segment
		(start 134.8135 160.468)
		(end 134.893499 160.468)
		(width 0.256)
		(layer "F.Cu")
		(net 5)
	)
	(segment
		(start 136.010499 161.585)
		(end 137.7465 161.585)
		(width 0.256)
		(layer "F.Cu")
		(net 5)
	)
	(segment
		(start 132.532 160.469)
		(end 133.815 160.469)
		(width 0.256)
		(layer "F.Cu")
		(net 5)
	)
	(segment
		(start 133.816 160.468)
		(end 133.815 160.469)
		(width 0.256)
		(layer "F.Cu")
		(net 5)
	)
	(segment
		(start 134.8135 160.468)
		(end 133.816 160.468)
		(width 0.256)
		(layer "F.Cu")
		(net 5)
	)
	(segment
		(start 134.893499 160.468)
		(end 136.010499 161.585)
		(width 0.256)
		(layer "F.Cu")
		(net 5)
	)
	(segment
		(start 132.435 160.372)
		(end 132.532 160.469)
		(width 0.256)
		(layer "F.Cu")
		(net 5)
	)
	(segment
		(start 141.024499 168.565)
		(end 141.024499 167.949)
		(width 0.15)
		(layer "F.Cu")
		(net 6)
	)
	(segment
		(start 113.474499 138.598)
		(end 114.772499 138.598)
		(width 0.4)
		(layer "F.Cu")
		(net 6)
	)
	(segment
		(start 148.364499 160.81)
		(end 148.115499 160.81)
		(width 0.114)
		(layer "F.Cu")
		(net 6)
	)
	(segment
		(start 140.321298 180.852201)
		(end 139.968097 180.499)
		(width 0.201)
		(layer "F.Cu")
		(net 6)
	)
	(segment
		(start 147.174499 162.199)
		(end 148.090515 162.199)
		(width 0.256)
		(layer "F.Cu")
		(net 6)
	)
	(segment
		(start 147.083499 159.05)
		(end 147.054499 159.079)
		(width 0.15)
		(layer "F.Cu")
		(net 6)
	)
	(segment
		(start 114.772499 138.598)
		(end 114.773499 138.599)
		(width 0.4)
		(layer "F.Cu")
		(net 6)
	)
	(segment
		(start 147.773499 159.758)
		(end 147.504499 159.758)
		(width 0.114)
		(layer "F.Cu")
		(net 6)
	)
	(segment
		(start 147.773499 163.458)
		(end 147.504499 163.458)
		(width 0.114)
		(layer "F.Cu")
		(net 6)
	)
	(segment
		(start 148.090515 162.199)
		(end 148.107843 162.216328)
		(width 0.256)
		(layer "F.Cu")
		(net 6)
	)
	(segment
		(start 142.971843 156.475328)
		(end 142.971843 156.496344)
		(width 0.256)
		(layer "F.Cu")
		(net 6)
	)
	(segment
		(start 137.823499 178.248)
		(end 137.823499 179.148)
		(width 0.201)
		(layer "F.Cu")
		(net 6)
	)
	(segment
		(start 132.435 166.535)
		(end 132.425 166.545)
		(width 0.256)
		(layer "F.Cu")
		(net 6)
	)
	(segment
		(start 141.434 158.897)
		(end 141.434 158.208501)
		(width 0.256)
		(layer "F.Cu")
		(net 6)
	)
	(segment
		(start 115.474499 138.525501)
		(end 116.2 137.8)
		(width 0.4)
		(layer "F.Cu")
		(net 6)
	)
	(segment
		(start 150.325499 169.601)
		(end 150.959499 169.601)
		(width 0.15)
		(layer "F.Cu")
		(net 6)
	)
	(segment
		(start 140.396171 156.486)
		(end 140.396843 156.485328)
		(width 0.256)
		(layer "F.Cu")
		(net 6)
	)
	(segment
		(start 115.474499 138.699)
		(end 115.474499 138.525501)
		(width 0.4)
		(layer "F.Cu")
		(net 6)
	)
	(segment
		(start 132.425 166.545)
		(end 133.743499 166.545)
		(width 0.256)
		(layer "F.Cu")
		(net 6)
	)
	(segment
		(start 147.934499 164.329)
		(end 147.934499 163.619)
		(width 0.114)
		(layer "F.Cu")
		(net 6)
	)
	(segment
		(start 140.396843 157.171344)
		(end 140.396843 156.485328)
		(width 0.256)
		(layer "F.Cu")
		(net 6)
	)
	(segment
		(start 135.440499 177.965)
		(end 135.424499 177.949)
		(width 0.201)
		(layer "F.Cu")
		(net 6)
	)
	(segment
		(start 115.374499 138.599)
		(end 114.773499 138.599)
		(width 0.4)
		(layer "F.Cu")
		(net 6)
	)
	(segment
		(start 147.054499 159.499)
		(end 147.313499 159.758)
		(width 0.15)
		(layer "F.Cu")
		(net 6)
	)
	(segment
		(start 142.971843 156.496344)
		(end 144.433 157.957501)
		(width 0.256)
		(layer "F.Cu")
		(net 6)
	)
	(segment
		(start 132.435 165.875)
		(end 132.435 166.535)
		(width 0.256)
		(layer "F.Cu")
		(net 6)
	)
	(segment
		(start 116.2 137.8)
		(end 117.977 137.8)
		(width 0.4)
		(layer "F.Cu")
		(net 6)
	)
	(segment
		(start 141.434 158.208501)
		(end 140.396843 157.171344)
		(width 0.256)
		(layer "F.Cu")
		(net 6)
	)
	(segment
		(start 148.115499 160.81)
		(end 147.934499 160.629)
		(width 0.114)
		(layer "F.Cu")
		(net 6)
	)
	(segment
		(start 145.621 162.585)
		(end 146.788499 162.585)
		(width 0.256)
		(layer "F.Cu")
		(net 6)
	)
	(segment
		(start 150.959499 169.601)
		(end 150.975499 169.617)
		(width 0.15)
		(layer "F.Cu")
		(net 6)
	)
	(segment
		(start 144.433 157.957501)
		(end 144.433 158.897)
		(width 0.256)
		(layer "F.Cu")
		(net 6)
	)
	(segment
		(start 149.275499 169.884)
		(end 150.008499 169.884)
		(width 0.15)
		(layer "F.Cu")
		(net 6)
	)
	(segment
		(start 148.5 161.65)
		(end 148.106843 162.043157)
		(width 0.256)
		(layer "F.Cu")
		(net 6)
	)
	(segment
		(start 117.977 137.8)
		(end 118.78 138.603)
		(width 0.4)
		(layer "F.Cu")
		(net 6)
	)
	(segment
		(start 148.115499 164.51)
		(end 147.934499 164.329)
		(width 0.114)
		(layer "F.Cu")
		(net 6)
	)
	(segment
		(start 139.724499 156.486)
		(end 140.396171 156.486)
		(width 0.256)
		(layer "F.Cu")
		(net 6)
	)
	(segment
		(start 137.540499 177.965)
		(end 137.823499 178.248)
		(width 0.201)
		(layer "F.Cu")
		(net 6)
	)
	(segment
		(start 148.364499 164.51)
		(end 148.115499 164.51)
		(width 0.114)
		(layer "F.Cu")
		(net 6)
	)
	(segment
		(start 148.106843 162.043157)
		(end 148.106843 162.216328)
		(width 0.256)
		(layer "F.Cu")
		(net 6)
	)
	(segment
		(start 115.624499 138.849)
		(end 115.624499 139.249)
		(width 0.4)
		(layer "F.Cu")
		(net 6)
	)
	(segment
		(start 147.054499 159.079)
		(end 147.054499 159.499)
		(width 0.15)
		(layer "F.Cu")
		(net 6)
	)
	(segment
		(start 115.474499 138.699)
		(end 115.624499 138.849)
		(width 0.4)
		(layer "F.Cu")
		(net 6)
	)
	(segment
		(start 147.934499 159.919)
		(end 147.773499 159.758)
		(width 0.114)
		(layer "F.Cu")
		(net 6)
	)
	(segment
		(start 147.65 159.05)
		(end 147.083499 159.05)
		(width 0.15)
		(layer "F.Cu")
		(net 6)
	)
	(segment
		(start 136.124499 177.965)
		(end 135.440499 177.965)
		(width 0.201)
		(layer "F.Cu")
		(net 6)
	)
	(segment
		(start 146.788499 162.585)
		(end 147.174499 162.199)
		(width 0.256)
		(layer "F.Cu")
		(net 6)
	)
	(segment
		(start 150.008499 169.884)
		(end 150.375499 169.517)
		(width 0.15)
		(layer "F.Cu")
		(net 6)
	)
	(segment
		(start 133.363328 158.573672)
		(end 132.424157 158.573672)
		(width 0.256)
		(layer "F.Cu")
		(net 6)
	)
	(segment
		(start 142.424499 157.199)
		(end 142.424499 157.022672)
		(width 0.256)
		(layer "F.Cu")
		(net 6)
	)
	(segment
		(start 147.934499 160.629)
		(end 147.934499 159.919)
		(width 0.114)
		(layer "F.Cu")
		(net 6)
	)
	(segment
		(start 136.124499 177.965)
		(end 137.540499 177.965)
		(width 0.201)
		(layer "F.Cu")
		(net 6)
	)
	(segment
		(start 138.524499 169.899)
		(end 139.308499 169.899)
		(width 0.256)
		(layer "F.Cu")
		(net 6)
	)
	(segment
		(start 133.743499 166.545)
		(end 133.839499 166.449)
		(width 0.256)
		(layer "F.Cu")
		(net 6)
	)
	(segment
		(start 147.934499 163.619)
		(end 147.773499 163.458)
		(width 0.114)
		(layer "F.Cu")
		(net 6)
	)
	(segment
		(start 139.574499 168.099)
		(end 138.934 167.458501)
		(width 0.15)
		(layer "F.Cu")
		(net 6)
	)
	(segment
		(start 139.968097 180.499)
		(end 139.571499 180.499)
		(width 0.201)
		(layer "F.Cu")
		(net 6)
	)
	(segment
		(start 115.474499 138.699)
		(end 115.374499 138.599)
		(width 0.4)
		(layer "F.Cu")
		(net 6)
	)
	(segment
		(start 141.024499 167.949)
		(end 140.724499 167.649)
		(width 0.15)
		(layer "F.Cu")
		(net 6)
	)
	(segment
		(start 141.024499 168.565)
		(end 140.558499 168.099)
		(width 0.15)
		(layer "F.Cu")
		(net 6)
	)
	(segment
		(start 140.824499 178.934)
		(end 140.824499 179.549)
		(width 0.201)
		(layer "F.Cu")
		(net 6)
	)
	(segment
		(start 140.558499 168.099)
		(end 139.574499 168.099)
		(width 0.15)
		(layer "F.Cu")
		(net 6)
	)
	(segment
		(start 138.934 167.458501)
		(end 138.934 166.772)
		(width 0.15)
		(layer "F.Cu")
		(net 6)
	)
	(segment
		(start 142.424499 157.022672)
		(end 142.971843 156.475328)
		(width 0.256)
		(layer "F.Cu")
		(net 6)
	)
	(segment
		(start 147.313499 159.758)
		(end 147.504499 159.758)
		(width 0.15)
		(layer "F.Cu")
		(net 6)
	)
	(segment
		(start 139.308499 169.899)
		(end 139.624499 169.583)
		(width 0.256)
		(layer "F.Cu")
		(net 6)
	)
	(segment
		(start 147.504499 163.458)
		(end 146.479 163.458)
		(width 0.15)
		(layer "F.Cu")
		(net 6)
	)
	(segment
		(start 139.624499 169.4355)
		(end 140.258499 169.4355)
		(width 0.15)
		(layer "F.Cu")
		(net 6)
	)
	(segment
		(start 146.479 163.458)
		(end 146.45 163.429)
		(width 0.15)
		(layer "F.Cu")
		(net 6)
	)
	(via
		(at 115.624499 139.249)
		(size 0.45)
		(drill 0.1)
		(layers "F.Cu" "B.Cu")
		(remove_unused_layers yes)
		(keep_end_layers yes)
		(zone_layer_connections)
		(net 6)
	)
	(via
		(at 139.724499 156.486)
		(size 0.45)
		(drill 0.1)
		(layers "F.Cu" "B.Cu")
		(remove_unused_layers yes)
		(keep_end_layers yes)
		(zone_layer_connections "In6.Cu")
		(net 6)
	)
	(via
		(at 150.975499 169.617)
		(size 0.45)
		(drill 0.1)
		(layers "F.Cu" "B.Cu")
		(remove_unused_layers yes)
		(keep_end_layers yes)
		(zone_layer_connections "In6.Cu")
		(net 6)
	)
	(via
		(at 133.363328 158.573672)
		(size 0.45)
		(drill 0.1)
		(layers "F.Cu" "B.Cu")
		(remove_unused_layers yes)
		(keep_end_layers yes)
		(zone_layer_connections "In6.Cu")
		(net 6)
	)
	(via
		(at 147.65 159.05)
		(size 0.45)
		(drill 0.1)
		(layers "F.Cu" "B.Cu")
		(remove_unused_layers yes)
		(keep_end_layers yes)
		(zone_layer_connections "In6.Cu")
		(net 6)
	)
	(via
		(at 140.258499 169.4355)
		(size 0.45)
		(drill 0.1)
		(layers "F.Cu" "B.Cu")
		(remove_unused_layers yes)
		(keep_end_layers yes)
		(zone_layer_connections "In6.Cu")
		(net 6)
	)
	(via
		(at 134.75 167.85)
		(size 0.45)
		(drill 0.1)
		(layers "F.Cu" "B.Cu")
		(remove_unused_layers yes)
		(keep_end_layers yes)
		(zone_layer_connections "In6.Cu")
		(net 6)
	)
	(via
		(at 142.424499 157.199)
		(size 0.45)
		(drill 0.1)
		(layers "F.Cu" "B.Cu")
		(remove_unused_layers yes)
		(keep_end_layers yes)
		(zone_layer_connections "In6.Cu")
		(net 6)
	)
	(via
		(at 115.474499 138.699)
		(size 0.45)
		(drill 0.1)
		(layers "F.Cu" "B.Cu")
		(remove_unused_layers yes)
		(keep_end_layers yes)
		(zone_layer_connections)
		(net 6)
	)
	(via
		(at 146.45 163.429)
		(size 0.45)
		(drill 0.1)
		(layers "F.Cu" "B.Cu")
		(remove_unused_layers yes)
		(keep_end_layers yes)
		(zone_layer_connections "In6.Cu")
		(net 6)
	)
	(via
		(at 135.424499 177.949)
		(size 0.45)
		(drill 0.1)
		(layers "F.Cu" "B.Cu")
		(remove_unused_layers yes)
		(keep_end_layers yes)
		(zone_layer_connections)
		(net 6)
	)
	(via
		(at 132.425 166.545)
		(size 0.45)
		(drill 0.1)
		(layers "F.Cu" "B.Cu")
		(remove_unused_layers yes)
		(keep_end_layers yes)
		(zone_layer_connections "In6.Cu")
		(net 6)
	)
	(via
		(at 148.5 161.65)
		(size 0.45)
		(drill 0.1)
		(layers "F.Cu" "B.Cu")
		(remove_unused_layers yes)
		(keep_end_layers yes)
		(zone_layer_connections "In6.Cu")
		(net 6)
	)
	(via
		(at 140.724499 167.649)
		(size 0.45)
		(drill 0.1)
		(layers "F.Cu" "B.Cu")
		(remove_unused_layers yes)
		(keep_end_layers yes)
		(zone_layer_connections "In6.Cu")
		(net 6)
	)
	(via
		(at 140.321298 180.852201)
		(size 0.45)
		(drill 0.1)
		(layers "F.Cu" "B.Cu")
		(remove_unused_layers yes)
		(keep_end_layers yes)
		(zone_layer_connections)
		(net 6)
	)
	(via
		(at 140.824499 179.549)
		(size 0.45)
		(drill 0.1)
		(layers "F.Cu" "B.Cu")
		(remove_unused_layers yes)
		(keep_end_layers yes)
		(zone_layer_connections)
		(net 6)
	)
	(segment
		(start 140.318097 180.849)
		(end 139.124499 180.849)
		(width 0.4)
		(layer "B.Cu")
		(net 6)
	)
	(segment
		(start 135.424499 177.949)
		(end 134.724499 177.249)
		(width 0.4)
		(layer "B.Cu")
		(net 6)
	)
	(segment
		(start 139.124499 180.849)
		(end 140.324499 180.849)
		(width 0.4)
		(layer "B.Cu")
		(net 6)
	)
	(segment
		(start 140.321298 180.852201)
		(end 140.318097 180.849)
		(width 0.4)
		(layer "B.Cu")
		(net 6)
	)
	(segment
		(start 134.349499 168.224)
		(end 134.724499 167.849)
		(width 0.4)
		(layer "B.Cu")
		(net 6)
	)
	(segment
		(start 147.65 159.05)
		(end 147.924499 159.324499)
		(width 0.15)
		(layer "B.Cu")
		(net 6)
	)
	(segment
		(start 115.624499 139.249)
		(end 115.624499 138.849)
		(width 0.4)
		(layer "B.Cu")
		(net 6)
	)
	(segment
		(start 115.9 140.5)
		(end 115.624499 140.5)
		(width 0.198)
		(layer "B.Cu")
		(net 6)
	)
	(segment
		(start 115.9 140.5)
		(end 115.824499 140.5)
		(width 0.198)
		(layer "B.Cu")
		(net 6)
	)
	(segment
		(start 115.824499 140.5)
		(end 115.624499 140.3)
		(width 0.198)
		(layer "B.Cu")
		(net 6)
	)
	(segment
		(start 115.624499 140.5)
		(end 115.624499 140.7)
		(width 0.4)
		(layer "B.Cu")
		(net 6)
	)
	(segment
		(start 115.624499 141.394499)
		(end 119.07 144.84)
		(width 0.4)
		(layer "B.Cu")
		(net 6)
	)
	(segment
		(start 147.924499 159.324499)
		(end 147.924499 159.799)
		(width 0.15)
		(layer "B.Cu")
		(net 6)
	)
	(segment
		(start 140.324499 180.849)
		(end 140.824499 180.349)
		(width 0.4)
		(layer "B.Cu")
		(net 6)
	)
	(segment
		(start 123.33 144.84)
		(end 126.2 147.71)
		(width 0.4)
		(layer "B.Cu")
		(net 6)
	)
	(segment
		(start 147.924499 159.799)
		(end 148.074499 159.949)
		(width 0.15)
		(layer "B.Cu")
		(net 6)
	)
	(segment
		(start 134.724499 177.249)
		(end 134.724499 170.849)
		(width 0.4)
		(layer "B.Cu")
		(net 6)
	)
	(segment
		(start 115.624499 138.849)
		(end 115.474499 138.699)
		(width 0.4)
		(layer "B.Cu")
		(net 6)
	)
	(segment
		(start 146.464499 164.165)
		(end 146.464499 163.443499)
		(width 0.15)
		(layer "B.Cu")
		(net 6)
	)
	(segment
		(start 115.624499 139.249)
		(end 115.624499 140.3)
		(width 0.4)
		(layer "B.Cu")
		(net 6)
	)
	(segment
		(start 134.724499 170.849)
		(end 134.349499 170.474)
		(width 0.4)
		(layer "B.Cu")
		(net 6)
	)
	(segment
		(start 116.64 140.5)
		(end 115.9 140.5)
		(width 0.198)
		(layer "B.Cu")
		(net 6)
	)
	(segment
		(start 115.824499 140.5)
		(end 115.624499 140.7)
		(width 0.198)
		(layer "B.Cu")
		(net 6)
	)
	(segment
		(start 126.2 151.410344)
		(end 133.363328 158.573672)
		(width 0.4)
		(layer "B.Cu")
		(net 6)
	)
	(segment
		(start 115.624499 140.7)
		(end 115.624499 141.394499)
		(width 0.4)
		(layer "B.Cu")
		(net 6)
	)
	(segment
		(start 119.07 144.84)
		(end 123.33 144.84)
		(width 0.4)
		(layer "B.Cu")
		(net 6)
	)
	(segment
		(start 134.349499 170.474)
		(end 134.349499 168.224)
		(width 0.4)
		(layer "B.Cu")
		(net 6)
	)
	(segment
		(start 126.2 147.71)
		(end 126.2 151.410344)
		(width 0.4)
		(layer "B.Cu")
		(net 6)
	)
	(segment
		(start 140.824499 180.349)
		(end 140.824499 179.549)
		(width 0.4)
		(layer "B.Cu")
		(net 6)
	)
	(segment
		(start 146.464499 163.443499)
		(end 146.45 163.429)
		(width 0.15)
		(layer "B.Cu")
		(net 6)
	)
	(segment
		(start 138.324499 180.849)
		(end 135.424499 177.949)
		(width 0.4)
		(layer "B.Cu")
		(net 6)
	)
	(segment
		(start 115.624499 140.3)
		(end 115.624499 140.5)
		(width 0.4)
		(layer "B.Cu")
		(net 6)
	)
	(segment
		(start 139.124499 180.849)
		(end 138.324499 180.849)
		(width 0.4)
		(layer "B.Cu")
		(net 6)
	)
	(segment
		(start 132.648 154.139)
		(end 134.138 154.139)
		(width 0.15)
		(layer "F.Cu")
		(net 7)
	)
	(segment
		(start 135.023 157.214)
		(end 135.023 155.124)
		(width 0.15)
		(layer "F.Cu")
		(net 7)
	)
	(segment
		(start 135.023 155.124)
		(end 134.173 154.274)
		(width 0.15)
		(layer "F.Cu")
		(net 7)
	)
	(segment
		(start 135.593 160.252485)
		(end 135.593 157.784)
		(width 0.15)
		(layer "F.Cu")
		(net 7)
	)
	(segment
		(start 137.7465 161.085)
		(end 136.425515 161.085)
		(width 0.15)
		(layer "F.Cu")
		(net 7)
	)
	(segment
		(start 136.425515 161.085)
		(end 135.593 160.252485)
		(width 0.15)
		(layer "F.Cu")
		(net 7)
	)
	(segment
		(start 135.593 157.784)
		(end 135.023 157.214)
		(width 0.15)
		(layer "F.Cu")
		(net 7)
	)
	(segment
		(start 116.736 175.962)
		(end 116.981 175.717)
		(width 0.201)
		(layer "F.Cu")
		(net 8)
	)
	(segment
		(start 109.375 175.2685)
		(end 112.616 175.2685)
		(width 0.256)
		(layer "F.Cu")
		(net 8)
	)
	(segment
		(start 113.921999 175.275)
		(end 113.917499 175.2705)
		(width 0.201)
		(layer "F.Cu")
		(net 8)
	)
	(segment
		(start 116.981 175.369)
		(end 118.231 175.369)
		(width 0.256)
		(layer "F.Cu")
		(net 8)
	)
	(segment
		(start 113.145499 175.2705)
		(end 113.917499 175.2705)
		(width 0.256)
		(layer "F.Cu")
		(net 8)
	)
	(segment
		(start 116.736 176.367)
		(end 116.736 175.962)
		(width 0.201)
		(layer "F.Cu")
		(net 8)
	)
	(segment
		(start 112.618 175.2705)
		(end 112.616 175.2685)
		(width 0.201)
		(layer "F.Cu")
		(net 8)
	)
	(segment
		(start 113.145499 175.2705)
		(end 112.618 175.2705)
		(width 0.201)
		(layer "F.Cu")
		(net 8)
	)
	(segment
		(start 116.981 175.717)
		(end 116.981 175.369)
		(width 0.201)
		(layer "F.Cu")
		(net 8)
	)
	(segment
		(start 116.981 175.369)
		(end 115.781 175.369)
		(width 0.256)
		(layer "F.Cu")
		(net 8)
	)
	(segment
		(start 115.687 175.275)
		(end 113.921999 175.275)
		(width 0.201)
		(layer "F.Cu")
		(net 8)
	)
	(segment
		(start 116.736 177.3375)
		(end 116.736 176.367)
		(width 0.201)
		(layer "F.Cu")
		(net 8)
	)
	(segment
		(start 115.781 175.369)
		(end 115.687 175.275)
		(width 0.201)
		(layer "F.Cu")
		(net 8)
	)
	(segment
		(start 258.79 174.3895)
		(end 259.6525 174.3895)
		(width 0.182)
		(layer "F.Cu")
		(net 9)
	)
	(via
		(at 259.6525 174.3895)
		(size 0.45)
		(drill 0.1)
		(layers "F.Cu" "B.Cu")
		(remove_unused_layers yes)
		(keep_end_layers yes)
		(zone_layer_connections)
		(net 9)
	)
	(segment
		(start 259.668 174.374)
		(end 259.6525 174.3895)
		(width 0.256)
		(layer "B.Cu")
		(net 9)
	)
	(segment
		(start 260.574499 174.283)
		(end 260.483499 174.374)
		(width 0.256)
		(layer "B.Cu")
		(net 9)
	)
	(segment
		(start 260.483499 174.374)
		(end 259.668 174.374)
		(width 0.256)
		(layer "B.Cu")
		(net 9)
	)
	(segment
		(start 145.65 199.25)
		(end 145.65 195.9)
		(width 0.4)
		(layer "F.Cu")
		(net 10)
	)
	(segment
		(start 146.65 199.25)
		(end 146.65 195.9)
		(width 0.4)
		(layer "F.Cu")
		(net 10)
	)
	(segment
		(start 148.5 193.775)
		(end 148.51 193.785)
		(width 0.4)
		(layer "F.Cu")
		(net 10)
	)
	(segment
		(start 147.65 199.25)
		(end 147.65 195.9)
		(width 0.4)
		(layer "F.Cu")
		(net 10)
	)
	(segment
		(start 146.61 193.635)
		(end 146.75 193.775)
		(width 0.4)
		(layer "F.Cu")
		(net 10)
	)
	(segment
		(start 146.75 193.775)
		(end 148.5 193.775)
		(width 0.4)
		(layer "F.Cu")
		(net 10)
	)
	(via
		(at 147.974499 194.599)
		(size 0.45)
		(drill 0.1)
		(layers "F.Cu" "B.Cu")
		(remove_unused_layers yes)
		(keep_end_layers yes)
		(zone_layer_connections)
		(net 10)
	)
	(via
		(at 147.524499 194.849)
		(size 0.45)
		(drill 0.1)
		(layers "F.Cu" "B.Cu")
		(remove_unused_layers yes)
		(keep_end_layers yes)
		(zone_layer_connections)
		(net 10)
	)
	(via
		(at 146.324499 194.849)
		(size 0.45)
		(drill 0.1)
		(layers "F.Cu" "B.Cu")
		(remove_unused_layers yes)
		(keep_end_layers yes)
		(zone_layer_connections)
		(net 10)
	)
	(via
		(at 146.974499 194.699)
		(size 0.45)
		(drill 0.1)
		(layers "F.Cu" "B.Cu")
		(remove_unused_layers yes)
		(keep_end_layers yes)
		(zone_layer_connections)
		(net 10)
	)
	(segment
		(start 147.575 193.175)
		(end 147.791 193.391)
		(width 0.201)
		(layer "B.Cu")
		(net 10)
	)
	(segment
		(start 147.791 193.391)
		(end 147.791 193.875)
		(width 0.201)
		(layer "B.Cu")
		(net 10)
	)
	(segment
		(start 147.575 192.625)
		(end 147.575 193.175)
		(width 0.201)
		(layer "B.Cu")
		(net 10)
	)
	(segment
		(start 147.65 199.25)
		(end 147.65 196.25)
		(width 0.4)
		(layer "B.Cu")
		(net 10)
	)
	(segment
		(start 147.65 196.25)
		(end 146.7 196.25)
		(width 0.4)
		(layer "B.Cu")
		(net 10)
	)
	(segment
		(start 146.7 196.25)
		(end 146.65 196.3)
		(width 0.4)
		(layer "B.Cu")
		(net 10)
	)
	(segment
		(start 146.65 196.3)
		(end 146.65 199.25)
		(width 0.4)
		(layer "B.Cu")
		(net 10)
	)
	(segment
		(start 159.962 196.468796)
		(end 159.962 194.28415)
		(width 0.22)
		(layer "B.Cu")
		(net 11)
	)
	(segment
		(start 159.962 196.468796)
		(end 159.962 197.1395)
		(width 0.22)
		(layer "B.Cu")
		(net 11)
	)
	(segment
		(start 159.962 197.1395)
		(end 159.652 197.4495)
		(width 0.22)
		(layer "B.Cu")
		(net 11)
	)
	(segment
		(start 159.652 197.4495)
		(end 159.652 199.2495)
		(width 0.22)
		(layer "B.Cu")
		(net 11)
	)
	(segment
		(start 159.793249 193.87675)
		(end 159.624499 193.708)
		(width 0.22)
		(layer "B.Cu")
		(net 11)
	)
	(arc
		(start 159.962 194.28415)
		(mid 159.918143 194.063666)
		(end 159.793249 193.87675)
		(width 0.22)
		(layer "B.Cu")
		(net 11)
	)
	(segment
		(start 197.5 159.5)
		(end 197.0005 159.0005)
		(width 0.256)
		(layer "F.Cu")
		(net 12)
	)
	(via
		(at 197.5 159.5)
		(size 0.45)
		(drill 0.1)
		(layers "F.Cu" "B.Cu")
		(remove_unused_layers yes)
		(keep_end_layers yes)
		(zone_layer_connections)
		(net 12)
	)
	(segment
		(start 188.009181 164.163375)
		(end 188.009181 163.763561)
		(width 0.22)
		(layer "B.Cu")
		(net 12)
	)
	(segment
		(start 188.635 168.95023)
		(end 188.635 165.360809)
		(width 0.22)
		(layer "B.Cu")
		(net 12)
	)
	(segment
		(start 196.9 160.667157)
		(end 196.9 160.241421)
		(width 0.1)
		(layer "B.Cu")
		(net 12)
	)
	(segment
		(start 188.488553 165.007255)
		(end 188.266927 164.785629)
		(width 0.22)
		(layer "B.Cu")
		(net 12)
	)
	(segment
		(start 188.009181 163.763561)
		(end 188.07071 163.702032)
		(width 0.1)
		(layer "B.Cu")
		(net 12)
	)
	(segment
		(start 160.162667 191.718631)
		(end 166.431319 185.449979)
		(width 0.22)
		(layer "B.Cu")
		(net 12)
	)
	(segment
		(start 175.489191 184.167107)
		(end 187.170534 172.485764)
		(width 0.22)
		(layer "B.Cu")
		(net 12)
	)
	(segment
		(start 188.1 163.631321)
		(end 188.1 161.682842)
		(width 0.1)
		(layer "B.Cu")
		(net 12)
	)
	(segment
		(start 197.241421 159.9)
		(end 197.358459 159.9)
		(width 0.1)
		(layer "B.Cu")
		(net 12)
	)
	(segment
		(start 196.737868 160.87071)
		(end 196.870711 160.737867)
		(width 0.1)
		(layer "B.Cu")
		(net 12)
	)
	(segment
		(start 197.5 159.714816)
		(end 197.5 159.5)
		(width 0.1)
		(layer "B.Cu")
		(net 12)
	)
	(segment
		(start 188.187868 161.47071)
		(end 188.67071 160.987868)
		(width 0.1)
		(layer "B.Cu")
		(net 12)
	)
	(segment
		(start 159.963499 192.326157)
		(end 159.963499 192.199464)
		(width 0.22)
		(layer "B.Cu")
		(net 12)
	)
	(segment
		(start 168.82134 184.46)
		(end 174.782084 184.46)
		(width 0.22)
		(layer "B.Cu")
		(net 12)
	)
	(segment
		(start 159.624499 192.748)
		(end 159.904921 192.467578)
		(width 0.22)
		(layer "B.Cu")
		(net 12)
	)
	(segment
		(start 197.429289 159.870711)
		(end 197.439767 159.860233)
		(width 0.1)
		(layer "B.Cu")
		(net 12)
	)
	(segment
		(start 188.882842 160.9)
		(end 196.667157 160.9)
		(width 0.1)
		(layer "B.Cu")
		(net 12)
	)
	(segment
		(start 196.958578 160.1)
		(end 197.099999 159.958579)
		(width 0.1)
		(layer "B.Cu")
		(net 12)
	)
	(arc
		(start 188.187868 161.47071)
		(mid 188.122836 161.568037)
		(end 188.1 161.682842)
		(width 0.1)
		(layer "B.Cu")
		(net 12)
	)
	(arc
		(start 196.667157 160.9)
		(mid 196.705426 160.892388)
		(end 196.737868 160.87071)
		(width 0.1)
		(layer "B.Cu")
		(net 12)
	)
	(arc
		(start 187.170534 172.485764)
		(mid 188.254398 170.863647)
		(end 188.635 168.95023)
		(width 0.22)
		(layer "B.Cu")
		(net 12)
	)
	(arc
		(start 159.963499 192.199464)
		(mid 160.015261 191.939239)
		(end 160.162667 191.718631)
		(width 0.22)
		(layer "B.Cu")
		(net 12)
	)
	(arc
		(start 188.635 165.360809)
		(mid 188.59694 165.169467)
		(end 188.488553 165.007255)
		(width 0.22)
		(layer "B.Cu")
		(net 12)
	)
	(arc
		(start 168.82134 184.46)
		(mid 167.52787 184.717287)
		(end 166.431319 185.449979)
		(width 0.22)
		(layer "B.Cu")
		(net 12)
	)
	(arc
		(start 159.904921 192.467578)
		(mid 159.948275 192.402693)
		(end 159.963499 192.326157)
		(width 0.22)
		(layer "B.Cu")
		(net 12)
	)
	(arc
		(start 188.67071 160.987868)
		(mid 188.768037 160.922836)
		(end 188.882842 160.9)
		(width 0.1)
		(layer "B.Cu")
		(net 12)
	)
	(arc
		(start 188.266927 164.785629)
		(mid 188.076167 164.500136)
		(end 188.009181 164.163375)
		(width 0.22)
		(layer "B.Cu")
		(net 12)
	)
	(arc
		(start 175.489191 184.167107)
		(mid 175.164768 184.38388)
		(end 174.782084 184.46)
		(width 0.22)
		(layer "B.Cu")
		(net 12)
	)
	(arc
		(start 188.07071 163.702032)
		(mid 188.092388 163.66959)
		(end 188.1 163.631321)
		(width 0.1)
		(layer "B.Cu")
		(net 12)
	)
	(arc
		(start 197.358459 159.9)
		(mid 197.396831 159.892369)
		(end 197.429289 159.870711)
		(width 0.1)
		(layer "B.Cu")
		(net 12)
	)
	(arc
		(start 196.870711 160.737867)
		(mid 196.892388 160.705425)
		(end 196.9 160.667157)
		(width 0.1)
		(layer "B.Cu")
		(net 12)
	)
	(arc
		(start 196.9 160.241421)
		(mid 196.915224 160.164885)
		(end 196.958578 160.1)
		(width 0.1)
		(layer "B.Cu")
		(net 12)
	)
	(arc
		(start 197.099999 159.958579)
		(mid 197.164884 159.915224)
		(end 197.241421 159.9)
		(width 0.1)
		(layer "B.Cu")
		(net 12)
	)
	(arc
		(start 197.439767 159.860233)
		(mid 197.484346 159.793515)
		(end 197.5 159.714816)
		(width 0.1)
		(layer "B.Cu")
		(net 12)
	)
	(segment
		(start 160.508249 193.874249)
		(end 160.674499 193.708)
		(width 0.22)
		(layer "B.Cu")
		(net 13)
	)
	(segment
		(start 160.342 196.472796)
		(end 160.342 197.1395)
		(width 0.22)
		(layer "B.Cu")
		(net 13)
	)
	(segment
		(start 160.652 197.4495)
		(end 160.652 199.2495)
		(width 0.22)
		(layer "B.Cu")
		(net 13)
	)
	(segment
		(start 160.342 196.472796)
		(end 160.342 194.275611)
		(width 0.22)
		(layer "B.Cu")
		(net 13)
	)
	(segment
		(start 160.342 197.1395)
		(end 160.652 197.4495)
		(width 0.22)
		(layer "B.Cu")
		(net 13)
	)
	(arc
		(start 160.342 194.275611)
		(mid 160.385206 194.058395)
		(end 160.508249 193.874249)
		(width 0.22)
		(layer "B.Cu")
		(net 13)
	)
	(segment
		(start 197.5 160.5)
		(end 197.0005 160.0005)
		(width 0.256)
		(layer "F.Cu")
		(net 14)
	)
	(via
		(at 197.5 160.5)
		(size 0.45)
		(drill 0.1)
		(layers "F.Cu" "B.Cu")
		(remove_unused_layers yes)
		(keep_end_layers yes)
		(zone_layer_connections)
		(net 14)
	)
	(segment
		(start 197.5 160.222799)
		(end 197.5 160.5)
		(width 0.1)
		(layer "B.Cu")
		(net 14)
	)
	(segment
		(start 189.015 168.950233)
		(end 189.015 165.360806)
		(width 0.22)
		(layer "B.Cu")
		(net 14)
	)
	(segment
		(start 188.389181 164.163372)
		(end 188.389181 163.763561)
		(width 0.22)
		(layer "B.Cu")
		(net 14)
	)
	(segment
		(start 190.303298 161.1)
		(end 190.37 161.1)
		(width 0.1)
		(layer "B.Cu")
		(net 14)
	)
	(segment
		(start 190.161649 161.24165)
		(end 190.161649 161.241649)
		(width 0.1)
		(layer "B.Cu")
		(net 14)
	)
	(segment
		(start 168.821343 184.84)
		(end 174.782087 184.84)
		(width 0.22)
		(layer "B.Cu")
		(net 14)
	)
	(segment
		(start 175.757895 184.435807)
		(end 187.439235 172.754467)
		(width 0.22)
		(layer "B.Cu")
		(net 14)
	)
	(segment
		(start 197.429289 160.129289)
		(end 197.483879 160.183879)
		(width 0.1)
		(layer "B.Cu")
		(net 14)
	)
	(segment
		(start 160.343499 192.326157)
		(end 160.343499 192.199467)
		(width 0.22)
		(layer "B.Cu")
		(net 14)
	)
	(segment
		(start 188.389181 163.763561)
		(end 188.32929 163.70367)
		(width 0.1)
		(layer "B.Cu")
		(net 14)
	)
	(segment
		(start 188.3 163.632959)
		(end 188.3 161.682843)
		(width 0.1)
		(layer "B.Cu")
		(net 14)
	)
	(segment
		(start 197.1 160.667158)
		(end 197.1 160.282843)
		(width 0.1)
		(layer "B.Cu")
		(net 14)
	)
	(segment
		(start 196.87929 161.012132)
		(end 197.012132 160.87929)
		(width 0.1)
		(layer "B.Cu")
		(net 14)
	)
	(segment
		(start 197.129289 160.212133)
		(end 197.212132 160.12929)
		(width 0.1)
		(layer "B.Cu")
		(net 14)
	)
	(segment
		(start 188.757254 164.738552)
		(end 188.535627 164.516925)
		(width 0.22)
		(layer "B.Cu")
		(net 14)
	)
	(segment
		(start 188.32929 161.612132)
		(end 188.812133 161.129289)
		(width 0.1)
		(layer "B.Cu")
		(net 14)
	)
	(segment
		(start 189.811649 161.241649)
		(end 189.811649 161.24165)
		(width 0.1)
		(layer "B.Cu")
		(net 14)
	)
	(segment
		(start 160.431367 191.987335)
		(end 166.700023 185.718679)
		(width 0.22)
		(layer "B.Cu")
		(net 14)
	)
	(segment
		(start 160.674499 192.74)
		(end 160.402077 192.467578)
		(width 0.22)
		(layer "B.Cu")
		(net 14)
	)
	(segment
		(start 197.282843 160.1)
		(end 197.358579 160.1)
		(width 0.1)
		(layer "B.Cu")
		(net 14)
	)
	(segment
		(start 189.953298 161.383299)
		(end 190.02 161.383299)
		(width 0.1)
		(layer "B.Cu")
		(net 14)
	)
	(segment
		(start 190.37 161.1)
		(end 196.667158 161.1)
		(width 0.1)
		(layer "B.Cu")
		(net 14)
	)
	(segment
		(start 188.882843 161.1)
		(end 189.67 161.1)
		(width 0.1)
		(layer "B.Cu")
		(net 14)
	)
	(arc
		(start 166.700023 185.718679)
		(mid 167.673293 185.068361)
		(end 168.821343 184.84)
		(width 0.22)
		(layer "B.Cu")
		(net 14)
	)
	(arc
		(start 197.358579 160.1)
		(mid 197.396847 160.107612)
		(end 197.429289 160.129289)
		(width 0.1)
		(layer "B.Cu")
		(net 14)
	)
	(arc
		(start 197.012132 160.87929)
		(mid 197.077164 160.781963)
		(end 197.1 160.667158)
		(width 0.1)
		(layer "B.Cu")
		(net 14)
	)
	(arc
		(start 188.812133 161.129289)
		(mid 188.844575 161.107612)
		(end 188.882843 161.1)
		(width 0.1)
		(layer "B.Cu")
		(net 14)
	)
	(arc
		(start 160.343499 192.326157)
		(mid 160.358723 192.402693)
		(end 160.402077 192.467578)
		(width 0.22)
		(layer "B.Cu")
		(net 14)
	)
	(arc
		(start 187.439235 172.754467)
		(mid 188.605472 171.00907)
		(end 189.015 168.950233)
		(width 0.22)
		(layer "B.Cu")
		(net 14)
	)
	(arc
		(start 197.1 160.282843)
		(mid 197.107612 160.244575)
		(end 197.129289 160.212133)
		(width 0.1)
		(layer "B.Cu")
		(net 14)
	)
	(arc
		(start 196.667158 161.1)
		(mid 196.781963 161.077164)
		(end 196.87929 161.012132)
		(width 0.1)
		(layer "B.Cu")
		(net 14)
	)
	(arc
		(start 188.389181 164.163372)
		(mid 188.427241 164.354713)
		(end 188.535627 164.516925)
		(width 0.22)
		(layer "B.Cu")
		(net 14)
	)
	(arc
		(start 188.757254 164.738552)
		(mid 188.948014 165.024045)
		(end 189.015 165.360806)
		(width 0.22)
		(layer "B.Cu")
		(net 14)
	)
	(arc
		(start 197.483879 160.183879)
		(mid 197.49581 160.201736)
		(end 197.5 160.222799)
		(width 0.1)
		(layer "B.Cu")
		(net 14)
	)
	(arc
		(start 197.212132 160.12929)
		(mid 197.244574 160.107612)
		(end 197.282843 160.1)
		(width 0.1)
		(layer "B.Cu")
		(net 14)
	)
	(arc
		(start 190.02 161.383299)
		(mid 190.120161 161.341811)
		(end 190.161649 161.24165)
		(width 0.1)
		(layer "B.Cu")
		(net 14)
	)
	(arc
		(start 175.757895 184.435807)
		(mid 175.310191 184.734954)
		(end 174.782087 184.84)
		(width 0.22)
		(layer "B.Cu")
		(net 14)
	)
	(arc
		(start 188.32929 163.70367)
		(mid 188.307612 163.671228)
		(end 188.3 163.632959)
		(width 0.1)
		(layer "B.Cu")
		(net 14)
	)
	(arc
		(start 188.3 161.682843)
		(mid 188.307612 161.644574)
		(end 188.32929 161.612132)
		(width 0.1)
		(layer "B.Cu")
		(net 14)
	)
	(arc
		(start 189.67 161.1)
		(mid 189.770161 161.141488)
		(end 189.811649 161.241649)
		(width 0.1)
		(layer "B.Cu")
		(net 14)
	)
	(arc
		(start 160.343499 192.199467)
		(mid 160.366335 192.084662)
		(end 160.431367 191.987335)
		(width 0.22)
		(layer "B.Cu")
		(net 14)
	)
	(arc
		(start 189.811649 161.24165)
		(mid 189.853137 161.341811)
		(end 189.953298 161.383299)
		(width 0.1)
		(layer "B.Cu")
		(net 14)
	)
	(arc
		(start 190.161649 161.241649)
		(mid 190.203137 161.141488)
		(end 190.303298 161.1)
		(width 0.1)
		(layer "B.Cu")
		(net 14)
	)
	(segment
		(start 175.791249 193.87725)
		(end 175.622499 193.7085)
		(width 0.22)
		(layer "B.Cu")
		(net 15)
	)
	(segment
		(start 175.96 196.469296)
		(end 175.96 194.28465)
		(width 0.22)
		(layer "B.Cu")
		(net 15)
	)
	(segment
		(start 175.65 197.45)
		(end 175.65 199.25)
		(width 0.22)
		(layer "B.Cu")
		(net 15)
	)
	(segment
		(start 175.96 196.469296)
		(end 175.96 197.14)
		(width 0.22)
		(layer "B.Cu")
		(net 15)
	)
	(segment
		(start 175.96 197.14)
		(end 175.65 197.45)
		(width 0.22)
		(layer "B.Cu")
		(net 15)
	)
	(arc
		(start 175.791249 193.87725)
		(mid 175.916143 194.064166)
		(end 175.96 194.28465)
		(width 0.22)
		(layer "B.Cu")
		(net 15)
	)
	(segment
		(start 196.0005 161.0005)
		(end 196.5 161.5)
		(width 0.256)
		(layer "F.Cu")
		(net 16)
	)
	(via
		(at 196.5 161.5)
		(size 0.45)
		(drill 0.1)
		(layers "F.Cu" "B.Cu")
		(remove_unused_layers yes)
		(keep_end_layers yes)
		(zone_layer_connections)
		(net 16)
	)
	(segment
		(start 196.099999 161.958579)
		(end 195.958578 162.1)
		(width 0.1)
		(layer "B.Cu")
		(net 16)
	)
	(segment
		(start 196.47071 161.82929)
		(end 196.429289 161.870711)
		(width 0.1)
		(layer "B.Cu")
		(net 16)
	)
	(segment
		(start 196.358579 161.9)
		(end 196.241421 161.9)
		(width 0.1)
		(layer "B.Cu")
		(net 16)
	)
	(segment
		(start 195.9 162.241421)
		(end 195.9 163.717158)
		(width 0.1)
		(layer "B.Cu")
		(net 16)
	)
	(segment
		(start 196.31 164.6)
		(end 196.370711 164.539289)
		(width 0.1)
		(layer "B.Cu")
		(net 16)
	)
	(segment
		(start 196.37071 164.312132)
		(end 195.987868 163.92929)
		(width 0.1)
		(layer "B.Cu")
		(net 16)
	)
	(segment
		(start 196.31 164.6)
		(end 196.31 173.35023)
		(width 0.22)
		(layer "B.Cu")
		(net 16)
	)
	(segment
		(start 196.5 161.5)
		(end 196.5 161.758579)
		(width 0.1)
		(layer "B.Cu")
		(net 16)
	)
	(segment
		(start 194.845534 176.885764)
		(end 183.139191 188.592107)
		(width 0.22)
		(layer "B.Cu")
		(net 16)
	)
	(segment
		(start 182.432084 188.885)
		(end 181.742913 188.885)
		(width 0.22)
		(layer "B.Cu")
		(net 16)
	)
	(segment
		(start 178.182084 191.46)
		(end 176.802963 191.46)
		(width 0.22)
		(layer "B.Cu")
		(net 16)
	)
	(segment
		(start 180.767105 189.289193)
		(end 178.889191 191.167107)
		(width 0.22)
		(layer "B.Cu")
		(net 16)
	)
	(segment
		(start 175.96 192.302963)
		(end 175.96 192.372658)
		(width 0.22)
		(layer "B.Cu")
		(net 16)
	)
	(segment
		(start 196.4 164.382843)
		(end 196.4 164.468579)
		(width 0.1)
		(layer "B.Cu")
		(net 16)
	)
	(segment
		(start 175.901421 192.51408)
		(end 175.65 192.765501)
		(width 0.22)
		(layer "B.Cu")
		(net 16)
	)
	(segment
		(start 176.32213 191.659168)
		(end 176.159167 191.822131)
		(width 0.22)
		(layer "B.Cu")
		(net 16)
	)
	(arc
		(start 175.96 192.372658)
		(mid 175.944776 192.449195)
		(end 175.901421 192.51408)
		(width 0.22)
		(layer "B.Cu")
		(net 16)
	)
	(arc
		(start 194.845534 176.885764)
		(mid 195.929398 175.263647)
		(end 196.31 173.35023)
		(width 0.22)
		(layer "B.Cu")
		(net 16)
	)
	(arc
		(start 175.96 192.302963)
		(mid 176.011762 192.042739)
		(end 176.159167 191.822131)
		(width 0.22)
		(layer "B.Cu")
		(net 16)
	)
	(arc
		(start 195.987868 163.92929)
		(mid 195.922836 163.831963)
		(end 195.9 163.717158)
		(width 0.1)
		(layer "B.Cu")
		(net 16)
	)
	(arc
		(start 196.5 161.758579)
		(mid 196.492388 161.796848)
		(end 196.47071 161.82929)
		(width 0.1)
		(layer "B.Cu")
		(net 16)
	)
	(arc
		(start 196.358579 161.9)
		(mid 196.396847 161.892388)
		(end 196.429289 161.870711)
		(width 0.1)
		(layer "B.Cu")
		(net 16)
	)
	(arc
		(start 196.370711 164.539289)
		(mid 196.392388 164.506847)
		(end 196.4 164.468579)
		(width 0.1)
		(layer "B.Cu")
		(net 16)
	)
	(arc
		(start 176.802963 191.46)
		(mid 176.542738 191.511762)
		(end 176.32213 191.659168)
		(width 0.22)
		(layer "B.Cu")
		(net 16)
	)
	(arc
		(start 196.37071 164.312132)
		(mid 196.392388 164.344574)
		(end 196.4 164.382843)
		(width 0.1)
		(layer "B.Cu")
		(net 16)
	)
	(arc
		(start 178.182084 191.46)
		(mid 178.564767 191.38388)
		(end 178.889191 191.167107)
		(width 0.22)
		(layer "B.Cu")
		(net 16)
	)
	(arc
		(start 183.139191 188.592107)
		(mid 182.814768 188.80888)
		(end 182.432084 188.885)
		(width 0.22)
		(layer "B.Cu")
		(net 16)
	)
	(arc
		(start 181.742913 188.885)
		(mid 181.21481 188.990046)
		(end 180.767105 189.289193)
		(width 0.22)
		(layer "B.Cu")
		(net 16)
	)
	(arc
		(start 196.241421 161.9)
		(mid 196.164884 161.915224)
		(end 196.099999 161.958579)
		(width 0.1)
		(layer "B.Cu")
		(net 16)
	)
	(arc
		(start 195.958578 162.1)
		(mid 195.915224 162.164885)
		(end 195.9 162.241421)
		(width 0.1)
		(layer "B.Cu")
		(net 16)
	)
	(segment
		(start 171.96 196.469296)
		(end 171.96 194.28465)
		(width 0.22)
		(layer "B.Cu")
		(net 17)
	)
	(segment
		(start 171.65 197.45)
		(end 171.65 199.25)
		(width 0.22)
		(layer "B.Cu")
		(net 17)
	)
	(segment
		(start 171.96 197.14)
		(end 171.65 197.45)
		(width 0.22)
		(layer "B.Cu")
		(net 17)
	)
	(segment
		(start 171.791249 193.87725)
		(end 171.622499 193.7085)
		(width 0.22)
		(layer "B.Cu")
		(net 17)
	)
	(segment
		(start 171.96 196.469296)
		(end 171.96 197.14)
		(width 0.22)
		(layer "B.Cu")
		(net 17)
	)
	(arc
		(start 171.96 194.28465)
		(mid 171.916143 194.064166)
		(end 171.791249 193.87725)
		(width 0.22)
		(layer "B.Cu")
		(net 17)
	)
	(segment
		(start 194.0005 161.0005)
		(end 194.5 161.5)
		(width 0.256)
		(layer "F.Cu")
		(net 18)
	)
	(via
		(at 194.5 161.5)
		(size 0.45)
		(drill 0.1)
		(layers "F.Cu" "B.Cu")
		(remove_unused_layers yes)
		(keep_end_layers yes)
		(zone_layer_connections)
		(net 18)
	)
	(segment
		(start 171.65 192.815501)
		(end 171.901422 192.564079)
		(width 0.22)
		(layer "B.Cu")
		(net 18)
	)
	(segment
		(start 193.9 162.241421)
		(end 193.9 163.717158)
		(width 0.1)
		(layer "B.Cu")
		(net 18)
	)
	(segment
		(start 194.4 164.382843)
		(end 194.4 164.468579)
		(width 0.1)
		(layer "B.Cu")
		(net 18)
	)
	(segment
		(start 182.164191 186.642107)
		(end 192.845534 175.960764)
		(width 0.22)
		(layer "B.Cu")
		(net 18)
	)
	(segment
		(start 171.96 192.422658)
		(end 171.96 192.052963)
		(width 0.22)
		(layer "B.Cu")
		(net 18)
	)
	(segment
		(start 194.5 161.5)
		(end 194.5 161.758579)
		(width 0.1)
		(layer "B.Cu")
		(net 18)
	)
	(segment
		(start 194.099999 161.958579)
		(end 193.958578 162.1)
		(width 0.1)
		(layer "B.Cu")
		(net 18)
	)
	(segment
		(start 175.42134 189.71)
		(end 177.232084 189.71)
		(width 0.22)
		(layer "B.Cu")
		(net 18)
	)
	(segment
		(start 194.47071 161.82929)
		(end 194.429289 161.870711)
		(width 0.1)
		(layer "B.Cu")
		(net 18)
	)
	(segment
		(start 194.31 164.6)
		(end 194.370711 164.539289)
		(width 0.1)
		(layer "B.Cu")
		(net 18)
	)
	(segment
		(start 177.939191 189.417107)
		(end 180.017106 187.339192)
		(width 0.22)
		(layer "B.Cu")
		(net 18)
	)
	(segment
		(start 172.159168 191.57213)
		(end 173.031319 190.699979)
		(width 0.22)
		(layer "B.Cu")
		(net 18)
	)
	(segment
		(start 194.31 172.42523)
		(end 194.31 164.6)
		(width 0.22)
		(layer "B.Cu")
		(net 18)
	)
	(segment
		(start 194.358579 161.9)
		(end 194.241421 161.9)
		(width 0.1)
		(layer "B.Cu")
		(net 18)
	)
	(segment
		(start 194.37071 164.312132)
		(end 193.987868 163.92929)
		(width 0.1)
		(layer "B.Cu")
		(net 18)
	)
	(segment
		(start 180.992913 186.935)
		(end 181.457084 186.935)
		(width 0.22)
		(layer "B.Cu")
		(net 18)
	)
	(arc
		(start 194.358579 161.9)
		(mid 194.396847 161.892388)
		(end 194.429289 161.870711)
		(width 0.1)
		(layer "B.Cu")
		(net 18)
	)
	(arc
		(start 194.5 161.758579)
		(mid 194.492388 161.796848)
		(end 194.47071 161.82929)
		(width 0.1)
		(layer "B.Cu")
		(net 18)
	)
	(arc
		(start 194.4 164.468579)
		(mid 194.392388 164.506847)
		(end 194.370711 164.539289)
		(width 0.1)
		(layer "B.Cu")
		(net 18)
	)
	(arc
		(start 177.232084 189.71)
		(mid 177.614767 189.63388)
		(end 177.939191 189.417107)
		(width 0.22)
		(layer "B.Cu")
		(net 18)
	)
	(arc
		(start 193.958578 162.1)
		(mid 193.915224 162.164885)
		(end 193.9 162.241421)
		(width 0.1)
		(layer "B.Cu")
		(net 18)
	)
	(arc
		(start 194.4 164.382843)
		(mid 194.392388 164.344574)
		(end 194.37071 164.312132)
		(width 0.1)
		(layer "B.Cu")
		(net 18)
	)
	(arc
		(start 194.241421 161.9)
		(mid 194.164884 161.915224)
		(end 194.099999 161.958579)
		(width 0.1)
		(layer "B.Cu")
		(net 18)
	)
	(arc
		(start 171.901422 192.564079)
		(mid 171.944776 192.499194)
		(end 171.96 192.422658)
		(width 0.22)
		(layer "B.Cu")
		(net 18)
	)
	(arc
		(start 175.42134 189.71)
		(mid 174.12787 189.967287)
		(end 173.031319 190.699979)
		(width 0.22)
		(layer "B.Cu")
		(net 18)
	)
	(arc
		(start 194.31 172.42523)
		(mid 193.929398 174.338647)
		(end 192.845534 175.960764)
		(width 0.22)
		(layer "B.Cu")
		(net 18)
	)
	(arc
		(start 180.017106 187.339192)
		(mid 180.46481 187.040046)
		(end 180.992913 186.935)
		(width 0.22)
		(layer "B.Cu")
		(net 18)
	)
	(arc
		(start 181.457084 186.935)
		(mid 181.839767 186.85888)
		(end 182.164191 186.642107)
		(width 0.22)
		(layer "B.Cu")
		(net 18)
	)
	(arc
		(start 172.159168 191.57213)
		(mid 172.011762 191.792738)
		(end 171.96 192.052963)
		(width 0.22)
		(layer "B.Cu")
		(net 18)
	)
	(arc
		(start 193.987868 163.92929)
		(mid 193.922836 163.831963)
		(end 193.9 163.717158)
		(width 0.1)
		(layer "B.Cu")
		(net 18)
	)
	(segment
		(start 167.96 196.469296)
		(end 167.96 194.28465)
		(width 0.22)
		(layer "B.Cu")
		(net 19)
	)
	(segment
		(start 167.96 197.14)
		(end 167.65 197.45)
		(width 0.22)
		(layer "B.Cu")
		(net 19)
	)
	(segment
		(start 167.791249 193.87725)
		(end 167.622499 193.7085)
		(width 0.22)
		(layer "B.Cu")
		(net 19)
	)
	(segment
		(start 167.96 196.469296)
		(end 167.96 197.14)
		(width 0.22)
		(layer "B.Cu")
		(net 19)
	)
	(segment
		(start 167.65 197.45)
		(end 167.65 199.25)
		(width 0.22)
		(layer "B.Cu")
		(net 19)
	)
	(arc
		(start 167.791249 193.87725)
		(mid 167.916143 194.064166)
		(end 167.96 194.28465)
		(width 0.22)
		(layer "B.Cu")
		(net 19)
	)
	(segment
		(start 192.5 161.5)
		(end 192.0005 161.0005)
		(width 0.256)
		(layer "F.Cu")
		(net 20)
	)
	(via
		(at 192.5 161.5)
		(size 0.45)
		(drill 0.1)
		(layers "F.Cu" "B.Cu")
		(remove_unused_layers yes)
		(keep_end_layers yes)
		(zone_layer_connections)
		(net 20)
	)
	(segment
		(start 167.96 192.422658)
		(end 167.96 191.627304)
		(width 0.22)
		(layer "B.Cu")
		(net 20)
	)
	(segment
		(start 192.4 164.382843)
		(end 192.4 164.468579)
		(width 0.1)
		(layer "B.Cu")
		(net 20)
	)
	(segment
		(start 176.914191 187.667107)
		(end 179.142106 185.439192)
		(width 0.22)
		(layer "B.Cu")
		(net 20)
	)
	(segment
		(start 180.117913 185.035)
		(end 180.432084 185.035)
		(width 0.22)
		(layer "B.Cu")
		(net 20)
	)
	(segment
		(start 168.159168 191.146471)
		(end 170.35566 188.949979)
		(width 0.22)
		(layer "B.Cu")
		(net 20)
	)
	(segment
		(start 172.745681 187.96)
		(end 176.207084 187.96)
		(width 0.22)
		(layer "B.Cu")
		(net 20)
	)
	(segment
		(start 192.31 171.50023)
		(end 192.31 164.6)
		(width 0.22)
		(layer "B.Cu")
		(net 20)
	)
	(segment
		(start 192.099999 161.958579)
		(end 191.958578 162.1)
		(width 0.1)
		(layer "B.Cu")
		(net 20)
	)
	(segment
		(start 192.5 161.5)
		(end 192.5 161.69999)
		(width 0.1)
		(layer "B.Cu")
		(net 20)
	)
	(segment
		(start 191.9 162.241421)
		(end 191.9 163.717158)
		(width 0.1)
		(layer "B.Cu")
		(net 20)
	)
	(segment
		(start 167.65 192.815501)
		(end 167.901422 192.564079)
		(width 0.22)
		(layer "B.Cu")
		(net 20)
	)
	(segment
		(start 192.31 164.6)
		(end 192.370711 164.539289)
		(width 0.1)
		(layer "B.Cu")
		(net 20)
	)
	(segment
		(start 192.37071 164.312132)
		(end 191.987868 163.92929)
		(width 0.1)
		(layer "B.Cu")
		(net 20)
	)
	(segment
		(start 192.358579 161.9)
		(end 192.241421 161.9)
		(width 0.1)
		(layer "B.Cu")
		(net 20)
	)
	(segment
		(start 181.139191 184.742107)
		(end 190.845534 175.035764)
		(width 0.22)
		(layer "B.Cu")
		(net 20)
	)
	(arc
		(start 167.901422 192.564079)
		(mid 167.944776 192.499194)
		(end 167.96 192.422658)
		(width 0.22)
		(layer "B.Cu")
		(net 20)
	)
	(arc
		(start 179.142106 185.439192)
		(mid 179.58981 185.140046)
		(end 180.117913 185.035)
		(width 0.22)
		(layer "B.Cu")
		(net 20)
	)
	(arc
		(start 190.845534 175.035764)
		(mid 191.929398 173.413647)
		(end 192.31 171.50023)
		(width 0.22)
		(layer "B.Cu")
		(net 20)
	)
	(arc
		(start 180.432084 185.035)
		(mid 180.814767 184.95888)
		(end 181.139191 184.742107)
		(width 0.22)
		(layer "B.Cu")
		(net 20)
	)
	(arc
		(start 191.987868 163.92929)
		(mid 191.922836 163.831963)
		(end 191.9 163.717158)
		(width 0.1)
		(layer "B.Cu")
		(net 20)
	)
	(arc
		(start 192.358579 161.9)
		(mid 192.396847 161.892388)
		(end 192.429289 161.870711)
		(width 0.1)
		(layer "B.Cu")
		(net 20)
	)
	(arc
		(start 176.914191 187.667107)
		(mid 176.589768 187.88388)
		(end 176.207084 187.96)
		(width 0.22)
		(layer "B.Cu")
		(net 20)
	)
	(arc
		(start 192.4 164.382843)
		(mid 192.392388 164.344574)
		(end 192.37071 164.312132)
		(width 0.1)
		(layer "B.Cu")
		(net 20)
	)
	(arc
		(start 192.4 164.468579)
		(mid 192.392388 164.506847)
		(end 192.370711 164.539289)
		(width 0.1)
		(layer "B.Cu")
		(net 20)
	)
	(arc
		(start 170.35566 188.949979)
		(mid 171.452211 188.217287)
		(end 172.745681 187.96)
		(width 0.22)
		(layer "B.Cu")
		(net 20)
	)
	(arc
		(start 191.958578 162.1)
		(mid 191.915224 162.164885)
		(end 191.9 162.241421)
		(width 0.1)
		(layer "B.Cu")
		(net 20)
	)
	(arc
		(start 168.159168 191.146471)
		(mid 168.011762 191.367079)
		(end 167.96 191.627304)
		(width 0.22)
		(layer "B.Cu")
		(net 20)
	)
	(arc
		(start 192.5 161.69999)
		(mid 192.481621 161.792387)
		(end 192.429289 161.870711)
		(width 0.1)
		(layer "B.Cu")
		(net 20)
	)
	(arc
		(start 192.241421 161.9)
		(mid 192.164884 161.915224)
		(end 192.099999 161.958579)
		(width 0.1)
		(layer "B.Cu")
		(net 20)
	)
	(segment
		(start 162.96 196.469296)
		(end 162.96 194.28465)
		(width 0.22)
		(layer "B.Cu")
		(net 21)
	)
	(segment
		(start 162.791249 193.87725)
		(end 162.622499 193.7085)
		(width 0.22)
		(layer "B.Cu")
		(net 21)
	)
	(segment
		(start 162.65 197.45)
		(end 162.65 199.25)
		(width 0.22)
		(layer "B.Cu")
		(net 21)
	)
	(segment
		(start 162.96 196.469296)
		(end 162.96 197.14)
		(width 0.22)
		(layer "B.Cu")
		(net 21)
	)
	(segment
		(start 162.96 197.14)
		(end 162.65 197.45)
		(width 0.22)
		(layer "B.Cu")
		(net 21)
	)
	(arc
		(start 162.96 194.28465)
		(mid 162.916143 194.064166)
		(end 162.791249 193.87725)
		(width 0.22)
		(layer "B.Cu")
		(net 21)
	)
	(segment
		(start 190.5 161.5)
		(end 190.0005 161.0005)
		(width 0.256)
		(layer "F.Cu")
		(net 22)
	)
	(via
		(at 190.5 161.5)
		(size 0.45)
		(drill 0.1)
		(layers "F.Cu" "B.Cu")
		(remove_unused_layers yes)
		(keep_end_layers yes)
		(zone_layer_connections)
		(net 22)
	)
	(segment
		(start 190.4 164.382843)
		(end 190.4 164.468579)
		(width 0.1)
		(layer "B.Cu")
		(net 22)
	)
	(segment
		(start 190.31 164.6)
		(end 190.370711 164.539289)
		(width 0.1)
		(layer "B.Cu")
		(net 22)
	)
	(segment
		(start 170.1182 186.31)
		(end 175.432084 186.31)
		(width 0.22)
		(layer "B.Cu")
		(net 22)
	)
	(segment
		(start 179.142913 183.585)
		(end 179.157084 183.585)
		(width 0.22)
		(layer "B.Cu")
		(net 22)
	)
	(segment
		(start 179.864191 183.292107)
		(end 188.845534 174.310764)
		(width 0.22)
		(layer "B.Cu")
		(net 22)
	)
	(segment
		(start 190.099999 161.958579)
		(end 189.958578 162.1)
		(width 0.1)
		(layer "B.Cu")
		(net 22)
	)
	(segment
		(start 162.96 192.422658)
		(end 162.96 192.349823)
		(width 0.22)
		(layer "B.Cu")
		(net 22)
	)
	(segment
		(start 190.31 170.77523)
		(end 190.31 164.6)
		(width 0.22)
		(layer "B.Cu")
		(net 22)
	)
	(segment
		(start 189.9 162.241421)
		(end 189.9 163.717158)
		(width 0.1)
		(layer "B.Cu")
		(net 22)
	)
	(segment
		(start 190.47071 161.82929)
		(end 190.429289 161.870711)
		(width 0.1)
		(layer "B.Cu")
		(net 22)
	)
	(segment
		(start 176.139191 186.017107)
		(end 178.167106 183.989192)
		(width 0.22)
		(layer "B.Cu")
		(net 22)
	)
	(segment
		(start 163.159168 191.86899)
		(end 167.728179 187.299979)
		(width 0.22)
		(layer "B.Cu")
		(net 22)
	)
	(segment
		(start 190.37071 164.312132)
		(end 189.987868 163.92929)
		(width 0.1)
		(layer "B.Cu")
		(net 22)
	)
	(segment
		(start 190.358579 161.9)
		(end 190.241421 161.9)
		(width 0.1)
		(layer "B.Cu")
		(net 22)
	)
	(segment
		(start 162.65 192.815501)
		(end 162.901422 192.564079)
		(width 0.22)
		(layer "B.Cu")
		(net 22)
	)
	(segment
		(start 190.5 161.5)
		(end 190.5 161.758579)
		(width 0.1)
		(layer "B.Cu")
		(net 22)
	)
	(arc
		(start 189.987868 163.92929)
		(mid 189.922836 163.831963)
		(end 189.9 163.717158)
		(width 0.1)
		(layer "B.Cu")
		(net 22)
	)
	(arc
		(start 170.1182 186.31)
		(mid 168.82473 186.567287)
		(end 167.728179 187.299979)
		(width 0.22)
		(layer "B.Cu")
		(net 22)
	)
	(arc
		(start 179.142913 183.585)
		(mid 178.61481 183.690046)
		(end 178.167106 183.989192)
		(width 0.22)
		(layer "B.Cu")
		(net 22)
	)
	(arc
		(start 190.4 164.468579)
		(mid 190.392388 164.506847)
		(end 190.370711 164.539289)
		(width 0.1)
		(layer "B.Cu")
		(net 22)
	)
	(arc
		(start 190.4 164.382843)
		(mid 190.392388 164.344574)
		(end 190.37071 164.312132)
		(width 0.1)
		(layer "B.Cu")
		(net 22)
	)
	(arc
		(start 190.31 170.77523)
		(mid 189.929398 172.688647)
		(end 188.845534 174.310764)
		(width 0.22)
		(layer "B.Cu")
		(net 22)
	)
	(arc
		(start 179.157084 183.585)
		(mid 179.539767 183.50888)
		(end 179.864191 183.292107)
		(width 0.22)
		(layer "B.Cu")
		(net 22)
	)
	(arc
		(start 189.958578 162.1)
		(mid 189.915224 162.164885)
		(end 189.9 162.241421)
		(width 0.1)
		(layer "B.Cu")
		(net 22)
	)
	(arc
		(start 190.5 161.758579)
		(mid 190.492388 161.796848)
		(end 190.47071 161.82929)
		(width 0.1)
		(layer "B.Cu")
		(net 22)
	)
	(arc
		(start 162.96 192.349823)
		(mid 163.011762 192.089598)
		(end 163.159168 191.86899)
		(width 0.22)
		(layer "B.Cu")
		(net 22)
	)
	(arc
		(start 190.358579 161.9)
		(mid 190.396847 161.892388)
		(end 190.429289 161.870711)
		(width 0.1)
		(layer "B.Cu")
		(net 22)
	)
	(arc
		(start 162.96 192.422658)
		(mid 162.944776 192.499194)
		(end 162.901422 192.564079)
		(width 0.22)
		(layer "B.Cu")
		(net 22)
	)
	(arc
		(start 190.241421 161.9)
		(mid 190.164884 161.915224)
		(end 190.099999 161.958579)
		(width 0.1)
		(layer "B.Cu")
		(net 22)
	)
	(arc
		(start 175.432084 186.31)
		(mid 175.814767 186.23388)
		(end 176.139191 186.017107)
		(width 0.22)
		(layer "B.Cu")
		(net 22)
	)
	(segment
		(start 176.65 197.45)
		(end 176.65 199.25)
		(width 0.22)
		(layer "B.Cu")
		(net 23)
	)
	(segment
		(start 176.34 194.276111)
		(end 176.34 196.473296)
		(width 0.22)
		(layer "B.Cu")
		(net 23)
	)
	(segment
		(start 176.506249 193.874749)
		(end 176.672499 193.7085)
		(width 0.22)
		(layer "B.Cu")
		(net 23)
	)
	(segment
		(start 176.34 197.14)
		(end 176.65 197.45)
		(width 0.22)
		(layer "B.Cu")
		(net 23)
	)
	(segment
		(start 176.34 196.473296)
		(end 176.34 197.14)
		(width 0.22)
		(layer "B.Cu")
		(net 23)
	)
	(arc
		(start 176.34 194.276111)
		(mid 176.383206 194.058895)
		(end 176.506249 193.874749)
		(width 0.22)
		(layer "B.Cu")
		(net 23)
	)
	(segment
		(start 196.499999 162.5)
		(end 196.0005 162.000501)
		(width 0.256)
		(layer "F.Cu")
		(net 24)
	)
	(via
		(at 196.499999 162.5)
		(size 0.45)
		(drill 0.1)
		(layers "F.Cu" "B.Cu")
		(remove_unused_layers yes)
		(keep_end_layers yes)
		(zone_layer_connections)
		(net 24)
	)
	(segment
		(start 182.432087 189.265)
		(end 181.742916 189.265)
		(width 0.22)
		(layer "B.Cu")
		(net 24)
	)
	(segment
		(start 196.69 164.6)
		(end 196.69 173.350233)
		(width 0.22)
		(layer "B.Cu")
		(net 24)
	)
	(segment
		(start 176.590834 191.927868)
		(end 176.427868 192.090834)
		(width 0.22)
		(layer "B.Cu")
		(net 24)
	)
	(segment
		(start 196.282843 162.1)
		(end 196.358579 162.1)
		(width 0.1)
		(layer "B.Cu")
		(net 24)
	)
	(segment
		(start 176.398579 192.51408)
		(end 176.65 192.765501)
		(width 0.22)
		(layer "B.Cu")
		(net 24)
	)
	(segment
		(start 181.035809 189.557893)
		(end 179.157894 191.435808)
		(width 0.22)
		(layer "B.Cu")
		(net 24)
	)
	(segment
		(start 196.6 164.468579)
		(end 196.6 164.382842)
		(width 0.1)
		(layer "B.Cu")
		(net 24)
	)
	(segment
		(start 196.25 162.865)
		(end 196.225 162.865)
		(width 0.1)
		(layer "B.Cu")
		(net 24)
	)
	(segment
		(start 196.5 162.241421)
		(end 196.5 162.5)
		(width 0.1)
		(layer "B.Cu")
		(net 24)
	)
	(segment
		(start 195.114234 177.154468)
		(end 183.407894 188.860808)
		(width 0.22)
		(layer "B.Cu")
		(net 24)
	)
	(segment
		(start 196.25 163.115)
		(end 196.225 163.115)
		(width 0.1)
		(layer "B.Cu")
		(net 24)
	)
	(segment
		(start 196.512132 164.17071)
		(end 196.129289 163.787867)
		(width 0.1)
		(layer "B.Cu")
		(net 24)
	)
	(segment
		(start 196.69 164.6)
		(end 196.629289 164.539289)
		(width 0.1)
		(layer "B.Cu")
		(net 24)
	)
	(segment
		(start 196.429289 162.129289)
		(end 196.47071 162.17071)
		(width 0.1)
		(layer "B.Cu")
		(net 24)
	)
	(segment
		(start 196.129289 162.212133)
		(end 196.212132 162.12929)
		(width 0.1)
		(layer "B.Cu")
		(net 24)
	)
	(segment
		(start 178.182087 191.84)
		(end 176.802966 191.84)
		(width 0.22)
		(layer "B.Cu")
		(net 24)
	)
	(segment
		(start 196.1 163.717157)
		(end 196.1 163.24)
		(width 0.1)
		(layer "B.Cu")
		(net 24)
	)
	(segment
		(start 176.34 192.302966)
		(end 176.34 192.372658)
		(width 0.22)
		(layer "B.Cu")
		(net 24)
	)
	(segment
		(start 196.1 162.74)
		(end 196.1 162.282843)
		(width 0.1)
		(layer "B.Cu")
		(net 24)
	)
	(arc
		(start 196.629289 164.539289)
		(mid 196.607612 164.506847)
		(end 196.6 164.468579)
		(width 0.1)
		(layer "B.Cu")
		(net 24)
	)
	(arc
		(start 196.1 162.282843)
		(mid 196.107612 162.244575)
		(end 196.129289 162.212133)
		(width 0.1)
		(layer "B.Cu")
		(net 24)
	)
	(arc
		(start 176.802966 191.84)
		(mid 176.688161 191.862836)
		(end 176.590834 191.927868)
		(width 0.22)
		(layer "B.Cu")
		(net 24)
	)
	(arc
		(start 196.225 162.865)
		(mid 196.136612 162.828388)
		(end 196.1 162.74)
		(width 0.1)
		(layer "B.Cu")
		(net 24)
	)
	(arc
		(start 196.212132 162.12929)
		(mid 196.244574 162.107612)
		(end 196.282843 162.1)
		(width 0.1)
		(layer "B.Cu")
		(net 24)
	)
	(arc
		(start 196.47071 162.17071)
		(mid 196.492388 162.203152)
		(end 196.5 162.241421)
		(width 0.1)
		(layer "B.Cu")
		(net 24)
	)
	(arc
		(start 176.34 192.302966)
		(mid 176.362836 192.188161)
		(end 176.427868 192.090834)
		(width 0.22)
		(layer "B.Cu")
		(net 24)
	)
	(arc
		(start 181.035809 189.557893)
		(mid 181.360232 189.34112)
		(end 181.742916 189.265)
		(width 0.22)
		(layer "B.Cu")
		(net 24)
	)
	(arc
		(start 196.358579 162.1)
		(mid 196.396847 162.107612)
		(end 196.429289 162.129289)
		(width 0.1)
		(layer "B.Cu")
		(net 24)
	)
	(arc
		(start 196.25 163.115)
		(mid 196.338388 163.078388)
		(end 196.375 162.99)
		(width 0.1)
		(layer "B.Cu")
		(net 24)
	)
	(arc
		(start 196.129289 163.787867)
		(mid 196.107612 163.755425)
		(end 196.1 163.717157)
		(width 0.1)
		(layer "B.Cu")
		(net 24)
	)
	(arc
		(start 179.157894 191.435808)
		(mid 178.71019 191.734954)
		(end 178.182087 191.84)
		(width 0.22)
		(layer "B.Cu")
		(net 24)
	)
	(arc
		(start 176.398579 192.51408)
		(mid 176.355224 192.449195)
		(end 176.34 192.372658)
		(width 0.22)
		(layer "B.Cu")
		(net 24)
	)
	(arc
		(start 196.1 163.24)
		(mid 196.136612 163.151612)
		(end 196.225 163.115)
		(width 0.1)
		(layer "B.Cu")
		(net 24)
	)
	(arc
		(start 196.375 162.99)
		(mid 196.338388 162.901612)
		(end 196.25 162.865)
		(width 0.1)
		(layer "B.Cu")
		(net 24)
	)
	(arc
		(start 195.114234 177.154468)
		(mid 196.280472 175.40907)
		(end 196.69 173.350233)
		(width 0.22)
		(layer "B.Cu")
		(net 24)
	)
	(arc
		(start 196.6 164.382842)
		(mid 196.577164 164.268037)
		(end 196.512132 164.17071)
		(width 0.1)
		(layer "B.Cu")
		(net 24)
	)
	(arc
		(start 183.407894 188.860808)
		(mid 182.96019 189.159954)
		(end 182.432087 189.265)
		(width 0.22)
		(layer "B.Cu")
		(net 24)
	)
	(segment
		(start 172.65 197.45)
		(end 172.65 199.25)
		(width 0.22)
		(layer "B.Cu")
		(net 25)
	)
	(segment
		(start 172.34 196.473296)
		(end 172.34 197.14)
		(width 0.22)
		(layer "B.Cu")
		(net 25)
	)
	(segment
		(start 172.34 196.473296)
		(end 172.34 194.276111)
		(width 0.22)
		(layer "B.Cu")
		(net 25)
	)
	(segment
		(start 172.506249 193.874749)
		(end 172.672499 193.7085)
		(width 0.22)
		(layer "B.Cu")
		(net 25)
	)
	(segment
		(start 172.34 197.14)
		(end 172.65 197.45)
		(width 0.22)
		(layer "B.Cu")
		(net 25)
	)
	(arc
		(start 172.34 194.276111)
		(mid 172.383206 194.058895)
		(end 172.506249 193.874749)
		(width 0.22)
		(layer "B.Cu")
		(net 25)
	)
	(segment
		(start 194.5 162.5)
		(end 194.0005 162.0005)
		(width 0.256)
		(layer "F.Cu")
		(net 26)
	)
	(via
		(at 194.5 162.5)
		(size 0.45)
		(drill 0.1)
		(layers "F.Cu" "B.Cu")
		(remove_unused_layers yes)
		(keep_end_layers yes)
		(zone_layer_connections)
		(net 26)
	)
	(segment
		(start 178.207895 189.685807)
		(end 180.285809 187.607893)
		(width 0.22)
		(layer "B.Cu")
		(net 26)
	)
	(segment
		(start 194.129289 163.787867)
		(end 194.512132 164.17071)
		(width 0.1)
		(layer "B.Cu")
		(net 26)
	)
	(segment
		(start 172.427868 191.840834)
		(end 173.300023 190.968679)
		(width 0.22)
		(layer "B.Cu")
		(net 26)
	)
	(segment
		(start 182.432895 186.910807)
		(end 193.114235 176.229467)
		(width 0.22)
		(layer "B.Cu")
		(net 26)
	)
	(segment
		(start 194.6 164.382842)
		(end 194.6 164.468579)
		(width 0.1)
		(layer "B.Cu")
		(net 26)
	)
	(segment
		(start 180.992916 187.315)
		(end 181.457087 187.315)
		(width 0.22)
		(layer "B.Cu")
		(net 26)
	)
	(segment
		(start 172.34 192.457157)
		(end 172.34 192.052966)
		(width 0.22)
		(layer "B.Cu")
		(net 26)
	)
	(segment
		(start 194.358579 162.1)
		(end 194.282843 162.1)
		(width 0.1)
		(layer "B.Cu")
		(net 26)
	)
	(segment
		(start 172.615501 192.815501)
		(end 172.398578 192.598578)
		(width 0.22)
		(layer "B.Cu")
		(net 26)
	)
	(segment
		(start 194.212132 162.12929)
		(end 194.129289 162.212133)
		(width 0.1)
		(layer "B.Cu")
		(net 26)
	)
	(segment
		(start 194.1 163.26)
		(end 194.1 163.440561)
		(width 0.1)
		(layer "B.Cu")
		(net 26)
	)
	(segment
		(start 194.5 162.5)
		(end 194.5 162.241421)
		(width 0.1)
		(layer "B.Cu")
		(net 26)
	)
	(segment
		(start 194.47071 162.17071)
		(end 194.429289 162.129289)
		(width 0.1)
		(layer "B.Cu")
		(net 26)
	)
	(segment
		(start 194.629289 164.539289)
		(end 194.69 164.6)
		(width 0.1)
		(layer "B.Cu")
		(net 26)
	)
	(segment
		(start 172.65 192.815501)
		(end 172.615501 192.815501)
		(width 0.22)
		(layer "B.Cu")
		(net 26)
	)
	(segment
		(start 175.421343 190.09)
		(end 177.232087 190.09)
		(width 0.22)
		(layer "B.Cu")
		(net 26)
	)
	(segment
		(start 194.1 162.282843)
		(end 194.1 162.76)
		(width 0.1)
		(layer "B.Cu")
		(net 26)
	)
	(segment
		(start 194.69 172.425233)
		(end 194.69 164.6)
		(width 0.22)
		(layer "B.Cu")
		(net 26)
	)
	(segment
		(start 194.1 163.440561)
		(end 194.1 163.717157)
		(width 0.1)
		(layer "B.Cu")
		(net 26)
	)
	(arc
		(start 194.1 162.76)
		(mid 194.136612 162.848388)
		(end 194.225 162.885)
		(width 0.1)
		(layer "B.Cu")
		(net 26)
	)
	(arc
		(start 193.114235 176.229467)
		(mid 194.280472 174.48407)
		(end 194.69 172.425233)
		(width 0.22)
		(layer "B.Cu")
		(net 26)
	)
	(arc
		(start 194.129289 162.212133)
		(mid 194.107612 162.244575)
		(end 194.1 162.282843)
		(width 0.1)
		(layer "B.Cu")
		(net 26)
	)
	(arc
		(start 194.35 163.01)
		(mid 194.313388 163.098388)
		(end 194.225 163.135)
		(width 0.1)
		(layer "B.Cu")
		(net 26)
	)
	(arc
		(start 194.512132 164.17071)
		(mid 194.577164 164.268037)
		(end 194.6 164.382842)
		(width 0.1)
		(layer "B.Cu")
		(net 26)
	)
	(arc
		(start 172.427868 191.840834)
		(mid 172.362836 191.938161)
		(end 172.34 192.052966)
		(width 0.22)
		(layer "B.Cu")
		(net 26)
	)
	(arc
		(start 172.398578 192.598578)
		(mid 172.355224 192.533693)
		(end 172.34 192.457157)
		(width 0.22)
		(layer "B.Cu")
		(net 26)
	)
	(arc
		(start 194.429289 162.129289)
		(mid 194.396847 162.107612)
		(end 194.358579 162.1)
		(width 0.1)
		(layer "B.Cu")
		(net 26)
	)
	(arc
		(start 194.282843 162.1)
		(mid 194.244574 162.107612)
		(end 194.212132 162.12929)
		(width 0.1)
		(layer "B.Cu")
		(net 26)
	)
	(arc
		(start 182.432895 186.910807)
		(mid 181.985191 187.209954)
		(end 181.457087 187.315)
		(width 0.22)
		(layer "B.Cu")
		(net 26)
	)
	(arc
		(start 177.232087 190.09)
		(mid 177.76019 189.984954)
		(end 178.207895 189.685807)
		(width 0.22)
		(layer "B.Cu")
		(net 26)
	)
	(arc
		(start 194.6 164.468579)
		(mid 194.607612 164.506847)
		(end 194.629289 164.539289)
		(width 0.1)
		(layer "B.Cu")
		(net 26)
	)
	(arc
		(start 180.992916 187.315)
		(mid 180.610233 187.39112)
		(end 180.285809 187.607893)
		(width 0.22)
		(layer "B.Cu")
		(net 26)
	)
	(arc
		(start 194.225 162.885)
		(mid 194.313388 162.921612)
		(end 194.35 163.01)
		(width 0.1)
		(layer "B.Cu")
		(net 26)
	)
	(arc
		(start 194.5 162.241421)
		(mid 194.492388 162.203152)
		(end 194.47071 162.17071)
		(width 0.1)
		(layer "B.Cu")
		(net 26)
	)
	(arc
		(start 173.300023 190.968679)
		(mid 174.273293 190.318361)
		(end 175.421343 190.09)
		(width 0.22)
		(layer "B.Cu")
		(net 26)
	)
	(arc
		(start 194.1 163.717157)
		(mid 194.107612 163.755425)
		(end 194.129289 163.787867)
		(width 0.1)
		(layer "B.Cu")
		(net 26)
	)
	(arc
		(start 194.225 163.135)
		(mid 194.136612 163.171612)
		(end 194.1 163.26)
		(width 0.1)
		(layer "B.Cu")
		(net 26)
	)
	(segment
		(start 163.65 197.45)
		(end 163.65 199.25)
		(width 0.22)
		(layer "B.Cu")
		(net 27)
	)
	(segment
		(start 163.34 197.14)
		(end 163.65 197.45)
		(width 0.22)
		(layer "B.Cu")
		(net 27)
	)
	(segment
		(start 163.34 196.473296)
		(end 163.34 197.14)
		(width 0.22)
		(layer "B.Cu")
		(net 27)
	)
	(segment
		(start 163.506249 193.874749)
		(end 163.672499 193.7085)
		(width 0.22)
		(layer "B.Cu")
		(net 27)
	)
	(segment
		(start 163.34 196.473296)
		(end 163.34 194.276111)
		(width 0.22)
		(layer "B.Cu")
		(net 27)
	)
	(arc
		(start 163.34 194.276111)
		(mid 163.383206 194.058895)
		(end 163.506249 193.874749)
		(width 0.22)
		(layer "B.Cu")
		(net 27)
	)
	(segment
		(start 190.0005 162.0005)
		(end 190.5 162.5)
		(width 0.256)
		(layer "F.Cu")
		(net 28)
	)
	(via
		(at 190.5 162.5)
		(size 0.45)
		(drill 0.1)
		(layers "F.Cu" "B.Cu")
		(remove_unused_layers yes)
		(keep_end_layers yes)
		(zone_layer_connections)
		(net 28)
	)
	(segment
		(start 190.129591 163.788169)
		(end 190.512132 164.17071)
		(width 0.1)
		(layer "B.Cu")
		(net 28)
	)
	(segment
		(start 163.34 192.422658)
		(end 163.34 192.349826)
		(width 0.22)
		(layer "B.Cu")
		(net 28)
	)
	(segment
		(start 190.241525 162.871224)
		(end 190.241526 162.871224)
		(width 0.1)
		(layer "B.Cu")
		(net 28)
	)
	(segment
		(start 190.47071 162.17071)
		(end 190.429289 162.129289)
		(width 0.1)
		(layer "B.Cu")
		(net 28)
	)
	(segment
		(start 179.142916 183.965)
		(end 179.157087 183.965)
		(width 0.22)
		(layer "B.Cu")
		(net 28)
	)
	(segment
		(start 190.62929 164.53929)
		(end 190.69 164.6)
		(width 0.1)
		(layer "B.Cu")
		(net 28)
	)
	(segment
		(start 190.358579 162.1)
		(end 190.282843 162.1)
		(width 0.1)
		(layer "B.Cu")
		(net 28)
	)
	(segment
		(start 190.100301 163.33)
		(end 190.100301 163.717458)
		(width 0.1)
		(layer "B.Cu")
		(net 28)
	)
	(segment
		(start 176.407895 186.285807)
		(end 178.435809 184.257893)
		(width 0.22)
		(layer "B.Cu")
		(net 28)
	)
	(segment
		(start 170.118203 186.69)
		(end 175.432087 186.69)
		(width 0.22)
		(layer "B.Cu")
		(net 28)
	)
	(segment
		(start 190.241526 163.171224)
		(end 190.241525 163.171224)
		(width 0.1)
		(layer "B.Cu")
		(net 28)
	)
	(segment
		(start 190.69 170.775233)
		(end 190.69 164.6)
		(width 0.22)
		(layer "B.Cu")
		(net 28)
	)
	(segment
		(start 163.65 192.815501)
		(end 163.398578 192.564079)
		(width 0.22)
		(layer "B.Cu")
		(net 28)
	)
	(segment
		(start 190.5 162.5)
		(end 190.5 162.241421)
		(width 0.1)
		(layer "B.Cu")
		(net 28)
	)
	(segment
		(start 190.100301 162.26301)
		(end 190.100301 162.73)
		(width 0.1)
		(layer "B.Cu")
		(net 28)
	)
	(segment
		(start 163.427868 192.137694)
		(end 167.996883 187.568679)
		(width 0.22)
		(layer "B.Cu")
		(net 28)
	)
	(segment
		(start 190.212132 162.12929)
		(end 190.129289 162.212133)
		(width 0.1)
		(layer "B.Cu")
		(net 28)
	)
	(segment
		(start 190.6 164.382842)
		(end 190.6 164.468579)
		(width 0.1)
		(layer "B.Cu")
		(net 28)
	)
	(segment
		(start 190.100301 163.312448)
		(end 190.100301 163.33)
		(width 0.1)
		(layer "B.Cu")
		(net 28)
	)
	(segment
		(start 180.132895 183.560807)
		(end 189.114235 174.579467)
		(width 0.22)
		(layer "B.Cu")
		(net 28)
	)
	(segment
		(start 190.38275 163.012448)
		(end 190.38275 163.03)
		(width 0.1)
		(layer "B.Cu")
		(net 28)
	)
	(arc
		(start 163.34 192.349826)
		(mid 163.362836 192.235021)
		(end 163.427868 192.137694)
		(width 0.22)
		(layer "B.Cu")
		(net 28)
	)
	(arc
		(start 180.132895 183.560807)
		(mid 179.685191 183.859954)
		(end 179.157087 183.965)
		(width 0.22)
		(layer "B.Cu")
		(net 28)
	)
	(arc
		(start 190.6 164.468579)
		(mid 190.607612 164.506848)
		(end 190.62929 164.53929)
		(width 0.1)
		(layer "B.Cu")
		(net 28)
	)
	(arc
		(start 189.114235 174.579467)
		(mid 190.280472 172.83407)
		(end 190.69 170.775233)
		(width 0.22)
		(layer "B.Cu")
		(net 28)
	)
	(arc
		(start 190.100301 163.717458)
		(mid 190.107913 163.755727)
		(end 190.129591 163.788169)
		(width 0.1)
		(layer "B.Cu")
		(net 28)
	)
	(arc
		(start 190.100301 162.73)
		(mid 190.141665 162.82986)
		(end 190.241525 162.871224)
		(width 0.1)
		(layer "B.Cu")
		(net 28)
	)
	(arc
		(start 175.432087 186.69)
		(mid 175.96019 186.584954)
		(end 176.407895 186.285807)
		(width 0.22)
		(layer "B.Cu")
		(net 28)
	)
	(arc
		(start 190.241526 162.871224)
		(mid 190.341386 162.912588)
		(end 190.38275 163.012448)
		(width 0.1)
		(layer "B.Cu")
		(net 28)
	)
	(arc
		(start 179.142916 183.965)
		(mid 178.760233 184.04112)
		(end 178.435809 184.257893)
		(width 0.22)
		(layer "B.Cu")
		(net 28)
	)
	(arc
		(start 190.38275 163.03)
		(mid 190.341386 163.12986)
		(end 190.241526 163.171224)
		(width 0.1)
		(layer "B.Cu")
		(net 28)
	)
	(arc
		(start 190.5 162.241421)
		(mid 190.492388 162.203152)
		(end 190.47071 162.17071)
		(width 0.1)
		(layer "B.Cu")
		(net 28)
	)
	(arc
		(start 190.512132 164.17071)
		(mid 190.577164 164.268037)
		(end 190.6 164.382842)
		(width 0.1)
		(layer "B.Cu")
		(net 28)
	)
	(arc
		(start 163.398578 192.564079)
		(mid 163.355224 192.499194)
		(end 163.34 192.422658)
		(width 0.22)
		(layer "B.Cu")
		(net 28)
	)
	(arc
		(start 190.129289 162.212133)
		(mid 190.111818 162.235706)
		(end 190.100301 162.26301)
		(width 0.1)
		(layer "B.Cu")
		(net 28)
	)
	(arc
		(start 190.429289 162.129289)
		(mid 190.396847 162.107612)
		(end 190.358579 162.1)
		(width 0.1)
		(layer "B.Cu")
		(net 28)
	)
	(arc
		(start 190.282843 162.1)
		(mid 190.244574 162.107612)
		(end 190.212132 162.12929)
		(width 0.1)
		(layer "B.Cu")
		(net 28)
	)
	(arc
		(start 190.241525 163.171224)
		(mid 190.141665 163.212588)
		(end 190.100301 163.312448)
		(width 0.1)
		(layer "B.Cu")
		(net 28)
	)
	(arc
		(start 167.996883 187.568679)
		(mid 168.970153 186.918361)
		(end 170.118203 186.69)
		(width 0.22)
		(layer "B.Cu")
		(net 28)
	)
	(segment
		(start 192.5 162.5)
		(end 192.0005 162.000501)
		(width 0.256)
		(layer "F.Cu")
		(net 29)
	)
	(via
		(at 192.5 162.5)
		(size 0.45)
		(drill 0.1)
		(layers "F.Cu" "B.Cu")
		(remove_unused_layers yes)
		(keep_end_layers yes)
		(zone_layer_connections)
		(net 29)
	)
	(segment
		(start 192.1 163.31)
		(end 192.1 163.717157)
		(width 0.1)
		(layer "B.Cu")
		(net 29)
	)
	(segment
		(start 192.1 163.292748)
		(end 192.1 163.31)
		(width 0.1)
		(layer "B.Cu")
		(net 29)
	)
	(segment
		(start 192.629289 164.539289)
		(end 192.69 164.6)
		(width 0.1)
		(layer "B.Cu")
		(net 29)
	)
	(segment
		(start 192.241374 162.851374)
		(end 192.241375 162.851374)
		(width 0.1)
		(layer "B.Cu")
		(net 29)
	)
	(segment
		(start 181.407895 185.010807)
		(end 191.114235 175.304467)
		(width 0.22)
		(layer "B.Cu")
		(net 29)
	)
	(segment
		(start 192.382749 162.992748)
		(end 192.382749 163.01)
		(width 0.1)
		(layer "B.Cu")
		(net 29)
	)
	(segment
		(start 168.34 192.422658)
		(end 168.34 191.627307)
		(width 0.22)
		(layer "B.Cu")
		(net 29)
	)
	(segment
		(start 177.182895 187.935807)
		(end 179.410809 185.707893)
		(width 0.22)
		(layer "B.Cu")
		(net 29)
	)
	(segment
		(start 192.358579 162.1)
		(end 192.282843 162.1)
		(width 0.1)
		(layer "B.Cu")
		(net 29)
	)
	(segment
		(start 192.1 162.282843)
		(end 192.1 162.71)
		(width 0.1)
		(layer "B.Cu")
		(net 29)
	)
	(segment
		(start 192.6 164.382842)
		(end 192.6 164.468579)
		(width 0.1)
		(layer "B.Cu")
		(net 29)
	)
	(segment
		(start 192.129289 163.787867)
		(end 192.512132 164.17071)
		(width 0.1)
		(layer "B.Cu")
		(net 29)
	)
	(segment
		(start 168.65 192.815501)
		(end 168.398578 192.564079)
		(width 0.22)
		(layer "B.Cu")
		(net 29)
	)
	(segment
		(start 168.427868 191.415175)
		(end 170.624364 189.218679)
		(width 0.22)
		(layer "B.Cu")
		(net 29)
	)
	(segment
		(start 192.69 171.500233)
		(end 192.69 164.6)
		(width 0.22)
		(layer "B.Cu")
		(net 29)
	)
	(segment
		(start 192.241375 163.151374)
		(end 192.241374 163.151374)
		(width 0.1)
		(layer "B.Cu")
		(net 29)
	)
	(segment
		(start 192.5 162.5)
		(end 192.5 162.213944)
		(width 0.1)
		(layer "B.Cu")
		(net 29)
	)
	(segment
		(start 172.745684 188.34)
		(end 176.207087 188.34)
		(width 0.22)
		(layer "B.Cu")
		(net 29)
	)
	(segment
		(start 180.117916 185.415)
		(end 180.432087 185.415)
		(width 0.22)
		(layer "B.Cu")
		(net 29)
	)
	(segment
		(start 192.212132 162.12929)
		(end 192.129289 162.212133)
		(width 0.1)
		(layer "B.Cu")
		(net 29)
	)
	(segment
		(start 192.49014 162.19014)
		(end 192.429289 162.129289)
		(width 0.1)
		(layer "B.Cu")
		(net 29)
	)
	(arc
		(start 192.382749 163.01)
		(mid 192.341342 163.109967)
		(end 192.241375 163.151374)
		(width 0.1)
		(layer "B.Cu")
		(net 29)
	)
	(arc
		(start 192.282843 162.1)
		(mid 192.244574 162.107612)
		(end 192.212132 162.12929)
		(width 0.1)
		(layer "B.Cu")
		(net 29)
	)
	(arc
		(start 177.182895 187.935807)
		(mid 176.735191 188.234954)
		(end 176.207087 188.34)
		(width 0.22)
		(layer "B.Cu")
		(net 29)
	)
	(arc
		(start 192.429289 162.129289)
		(mid 192.396847 162.107612)
		(end 192.358579 162.1)
		(width 0.1)
		(layer "B.Cu")
		(net 29)
	)
	(arc
		(start 192.512132 164.17071)
		(mid 192.577164 164.268037)
		(end 192.6 164.382842)
		(width 0.1)
		(layer "B.Cu")
		(net 29)
	)
	(arc
		(start 192.1 162.71)
		(mid 192.141407 162.809967)
		(end 192.241374 162.851374)
		(width 0.1)
		(layer "B.Cu")
		(net 29)
	)
	(arc
		(start 168.427868 191.415175)
		(mid 168.362836 191.512502)
		(end 168.34 191.627307)
		(width 0.22)
		(layer "B.Cu")
		(net 29)
	)
	(arc
		(start 192.241375 162.851374)
		(mid 192.341342 162.892781)
		(end 192.382749 162.992748)
		(width 0.1)
		(layer "B.Cu")
		(net 29)
	)
	(arc
		(start 192.69 171.500233)
		(mid 192.280472 173.55907)
		(end 191.114235 175.304467)
		(width 0.22)
		(layer "B.Cu")
		(net 29)
	)
	(arc
		(start 192.6 164.468579)
		(mid 192.607612 164.506847)
		(end 192.629289 164.539289)
		(width 0.1)
		(layer "B.Cu")
		(net 29)
	)
	(arc
		(start 170.624364 189.218679)
		(mid 171.597634 188.568361)
		(end 172.745684 188.34)
		(width 0.22)
		(layer "B.Cu")
		(net 29)
	)
	(arc
		(start 192.241374 163.151374)
		(mid 192.141407 163.192781)
		(end 192.1 163.292748)
		(width 0.1)
		(layer "B.Cu")
		(net 29)
	)
	(arc
		(start 192.5 162.213944)
		(mid 192.497437 162.201061)
		(end 192.49014 162.19014)
		(width 0.1)
		(layer "B.Cu")
		(net 29)
	)
	(arc
		(start 181.407895 185.010807)
		(mid 180.960191 185.309954)
		(end 180.432087 185.415)
		(width 0.22)
		(layer "B.Cu")
		(net 29)
	)
	(arc
		(start 168.398578 192.564079)
		(mid 168.355224 192.499194)
		(end 168.34 192.422658)
		(width 0.22)
		(layer "B.Cu")
		(net 29)
	)
	(arc
		(start 192.129289 162.212133)
		(mid 192.107612 162.244575)
		(end 192.1 162.282843)
		(width 0.1)
		(layer "B.Cu")
		(net 29)
	)
	(arc
		(start 179.410809 185.707893)
		(mid 179.735232 185.49112)
		(end 180.117916 185.415)
		(width 0.22)
		(layer "B.Cu")
		(net 29)
	)
	(arc
		(start 192.1 163.717157)
		(mid 192.107612 163.755425)
		(end 192.129289 163.787867)
		(width 0.1)
		(layer "B.Cu")
		(net 29)
	)
	(segment
		(start 168.506249 193.874749)
		(end 168.672499 193.7085)
		(width 0.22)
		(layer "B.Cu")
		(net 30)
	)
	(segment
		(start 168.34 196.473296)
		(end 168.34 197.14)
		(width 0.22)
		(layer "B.Cu")
		(net 30)
	)
	(segment
		(start 168.34 197.14)
		(end 168.65 197.45)
		(width 0.22)
		(layer "B.Cu")
		(net 30)
	)
	(segment
		(start 168.34 196.473296)
		(end 168.34 194.276111)
		(width 0.22)
		(layer "B.Cu")
		(net 30)
	)
	(segment
		(start 168.65 197.45)
		(end 168.65 199.25)
		(width 0.22)
		(layer "B.Cu")
		(net 30)
	)
	(arc
		(start 168.506249 193.874749)
		(mid 168.383206 194.058895)
		(end 168.34 194.276111)
		(width 0.22)
		(layer "B.Cu")
		(net 30)
	)
	(segment
		(start 114.912499 119.149)
		(end 114.912499 118.166)
		(width 0.4)
		(layer "B.Cu")
		(net 31)
	)
	(segment
		(start 111.674499 119.399)
		(end 111.674499 120.999)
		(width 0.4)
		(layer "B.Cu")
		(net 31)
	)
	(segment
		(start 111.674499 120.999)
		(end 110.174499 122.499)
		(width 0.4)
		(layer "B.Cu")
		(net 31)
	)
	(segment
		(start 114.912499 118.166)
		(end 114.929499 118.149)
		(width 0.4)
		(layer "B.Cu")
		(net 31)
	)
	(segment
		(start 110.174499 122.499)
		(end 110.174499 129.449)
		(width 0.4)
		(layer "B.Cu")
		(net 31)
	)
	(segment
		(start 112.264999 118.111487)
		(end 112.264999 118.8085)
		(width 0.4)
		(layer "B.Cu")
		(net 31)
	)
	(segment
		(start 110.174499 129.449)
		(end 111.624499 130.899)
		(width 0.4)
		(layer "B.Cu")
		(net 31)
	)
	(segment
		(start 111.624499 130.899)
		(end 111.624499 132.649)
		(width 0.4)
		(layer "B.Cu")
		(net 31)
	)
	(segment
		(start 112.264999 133.2895)
		(end 112.264999 133.810487)
		(width 0.4)
		(layer "B.Cu")
		(net 31)
	)
	(segment
		(start 112.302512 118.149)
		(end 112.264999 118.111487)
		(width 0.4)
		(layer "B.Cu")
		(net 31)
	)
	(segment
		(start 114.929499 118.149)
		(end 112.302512 118.149)
		(width 0.4)
		(layer "B.Cu")
		(net 31)
	)
	(segment
		(start 112.264999 118.8085)
		(end 111.674499 119.399)
		(width 0.4)
		(layer "B.Cu")
		(net 31)
	)
	(segment
		(start 111.624499 132.649)
		(end 112.264999 133.2895)
		(width 0.4)
		(layer "B.Cu")
		(net 31)
	)
	(segment
		(start 113.399 101.511)
		(end 113.399 100.789)
		(width 0.1)
		(layer "F.Cu")
		(net 32)
	)
	(via
		(at 113.395 100.785)
		(size 0.45)
		(drill 0.1)
		(layers "F.Cu" "B.Cu")
		(remove_unused_layers yes)
		(keep_end_layers yes)
		(zone_layer_connections)
		(net 32)
	)
	(segment
		(start 113.4 101.6)
		(end 113.4 100.79)
		(width 0.1)
		(layer "B.Cu")
		(net 32)
	)
	(segment
		(start 116.981 173.969)
		(end 116.981 173.0505)
		(width 0.256)
		(layer "F.Cu")
		(net 33)
	)
	(segment
		(start 148.106843 166.354179)
		(end 148.106843 165.716328)
		(width 0.256)
		(layer "F.Cu")
		(net 34)
	)
	(segment
		(start 138.396843 156.485328)
		(end 138.288171 156.485328)
		(width 0.256)
		(layer "F.Cu")
		(net 34)
	)
	(segment
		(start 138.288171 156.485328)
		(end 136.474499 158.299)
		(width 0.256)
		(layer "F.Cu")
		(net 34)
	)
	(segment
		(start 139.084328 156.485328)
		(end 138.396843 156.485328)
		(width 0.4)
		(layer "F.Cu")
		(net 34)
	)
	(segment
		(start 145.621 165.084)
		(end 146.534499 165.084)
		(width 0.256)
		(layer "F.Cu")
		(net 34)
	)
	(segment
		(start 144.8 156.482)
		(end 144.058515 156.482)
		(width 0.4)
		(layer "F.Cu")
		(net 34)
	)
	(segment
		(start 144.051843 156.876344)
		(end 144.051843 156.475328)
		(width 0.256)
		(layer "F.Cu")
		(net 34)
	)
	(segment
		(start 137.160499 160.085)
		(end 137.746 160.085)
		(width 0.256)
		(layer "F.Cu")
		(net 34)
	)
	(segment
		(start 144.933 157.757501)
		(end 144.051843 156.876344)
		(width 0.256)
		(layer "F.Cu")
		(net 34)
	)
	(segment
		(start 144.058515 156.482)
		(end 144.051843 156.475328)
		(width 0.4)
		(layer "F.Cu")
		(net 34)
	)
	(segment
		(start 136.474499 159.399)
		(end 137.160499 160.085)
		(width 0.256)
		(layer "F.Cu")
		(net 34)
	)
	(segment
		(start 136.474499 158.299)
		(end 136.474499 159.399)
		(width 0.256)
		(layer "F.Cu")
		(net 34)
	)
	(segment
		(start 147.166827 165.716328)
		(end 148.107843 165.716328)
		(width 0.256)
		(layer "F.Cu")
		(net 34)
	)
	(segment
		(start 144.933 158.897)
		(end 144.933 157.757501)
		(width 0.256)
		(layer "F.Cu")
		(net 34)
	)
	(segment
		(start 146.534499 165.084)
		(end 147.166827 165.716328)
		(width 0.256)
		(layer "F.Cu")
		(net 34)
	)
	(via
		(at 144.8 156.482)
		(size 0.45)
		(drill 0.1)
		(layers "F.Cu" "B.Cu")
		(remove_unused_layers yes)
		(keep_end_layers yes)
		(zone_layer_connections)
		(net 34)
	)
	(via
		(at 139.084328 156.485328)
		(size 0.45)
		(drill 0.1)
		(layers "F.Cu" "B.Cu")
		(remove_unused_layers yes)
		(keep_end_layers yes)
		(zone_layer_connections)
		(net 34)
	)
	(via
		(at 148.106843 166.354179)
		(size 0.45)
		(drill 0.1)
		(layers "F.Cu" "B.Cu")
		(remove_unused_layers yes)
		(keep_end_layers yes)
		(zone_layer_connections)
		(net 34)
	)
	(segment
		(start 147.124499 158.806499)
		(end 147.124499 162.979)
		(width 0.4)
		(layer "B.Cu")
		(net 34)
	)
	(segment
		(start 147.124499 162.979)
		(end 148.106843 163.961344)
		(width 0.4)
		(layer "B.Cu")
		(net 34)
	)
	(segment
		(start 141.451 157.199)
		(end 142.168 156.482)
		(width 0.4)
		(layer "B.Cu")
		(net 34)
	)
	(segment
		(start 144.8 156.482)
		(end 147.124499 158.806499)
		(width 0.4)
		(layer "B.Cu")
		(net 34)
	)
	(segment
		(start 142.168 156.482)
		(end 144.8 156.482)
		(width 0.4)
		(layer "B.Cu")
		(net 34)
	)
	(segment
		(start 139.084328 156.485328)
		(end 139.084328 156.624328)
		(width 0.4)
		(layer "B.Cu")
		(net 34)
	)
	(segment
		(start 139.659 157.199)
		(end 141.451 157.199)
		(width 0.4)
		(layer "B.Cu")
		(net 34)
	)
	(segment
		(start 148.106843 163.961344)
		(end 148.106843 166.354179)
		(width 0.4)
		(layer "B.Cu")
		(net 34)
	)
	(segment
		(start 139.084328 156.624328)
		(end 139.659 157.199)
		(width 0.4)
		(layer "B.Cu")
		(net 34)
	)
	(segment
		(start 250.3125 129.0125)
		(end 250.068901 129.256099)
		(width 0.4)
		(layer "F.Cu")
		(net 35)
	)
	(segment
		(start 251.287998 127.639)
		(end 251.637998 127.989)
		(width 0.4)
		(layer "F.Cu")
		(net 35)
	)
	(segment
		(start 252.149499 130.427499)
		(end 252.688998 129.888)
		(width 0.256)
		(layer "F.Cu")
		(net 35)
	)
	(segment
		(start 250.611 127.689)
		(end 250.3125 127.9875)
		(width 0.4)
		(layer "F.Cu")
		(net 35)
	)
	(segment
		(start 252.688998 129.888)
		(end 252.936998 129.888)
		(width 0.256)
		(layer "F.Cu")
		(net 35)
	)
	(segment
		(start 152.256 189.971)
		(end 152.256 189.831)
		(width 0.4)
		(layer "F.Cu")
		(net 35)
	)
	(segment
		(start 251.287998 127.029)
		(end 251.287998 127.639)
		(width 0.4)
		(layer "F.Cu")
		(net 35)
	)
	(segment
		(start 250.068901 129.256099)
		(end 246.316258 129.256099)
		(width 0.4)
		(layer "F.Cu")
		(net 35)
	)
	(segment
		(start 252.149499 130.449)
		(end 252.149499 130.427499)
		(width 0.256)
		(layer "F.Cu")
		(net 35)
	)
	(segment
		(start 250.3125 127.9875)
		(end 250.3125 129.0125)
		(width 0.4)
		(layer "F.Cu")
		(net 35)
	)
	(segment
		(start 251.637998 127.989)
		(end 252.937998 127.989)
		(width 0.4)
		(layer "F.Cu")
		(net 35)
	)
	(segment
		(start 251.337998 127.689)
		(end 250.611 127.689)
		(width 0.4)
		(layer "F.Cu")
		(net 35)
	)
	(via
		(at 262.55 169.655)
		(size 0.45)
		(drill 0.1)
		(layers "F.Cu" "B.Cu")
		(remove_unused_layers yes)
		(keep_end_layers yes)
		(zone_layer_connections "In9.Cu")
		(net 35)
	)
	(via
		(at 263.55 148.899998)
		(size 0.45)
		(drill 0.1)
		(layers "F.Cu" "B.Cu")
		(remove_unused_layers yes)
		(keep_end_layers yes)
		(zone_layer_connections "In9.Cu")
		(net 35)
	)
	(via
		(at 226.585 189.46)
		(size 0.45)
		(drill 0.1)
		(layers "F.Cu" "B.Cu")
		(remove_unused_layers yes)
		(keep_end_layers yes)
		(zone_layer_connections "In9.Cu")
		(net 35)
	)
	(via
		(at 224.335 189.46)
		(size 0.45)
		(drill 0.1)
		(layers "F.Cu" "B.Cu")
		(remove_unused_layers yes)
		(keep_end_layers yes)
		(zone_layer_connections "In9.Cu")
		(net 35)
	)
	(via
		(at 148.462 188.15)
		(size 0.45)
		(drill 0.1)
		(layers "F.Cu" "B.Cu")
		(remove_unused_layers yes)
		(keep_end_layers yes)
		(zone_layer_connections "In9.Cu")
		(net 35)
	)
	(via
		(at 233.035 188.085)
		(size 0.45)
		(drill 0.1)
		(layers "F.Cu" "B.Cu")
		(remove_unused_layers yes)
		(keep_end_layers yes)
		(zone_layer_connections "In9.Cu")
		(net 35)
	)
	(via
		(at 249.6 118.8)
		(size 0.45)
		(drill 0.1)
		(layers "F.Cu" "B.Cu")
		(net 35)
	)
	(via
		(at 262.55 168.584999)
		(size 0.45)
		(drill 0.1)
		(layers "F.Cu" "B.Cu")
		(remove_unused_layers yes)
		(keep_end_layers yes)
		(zone_layer_connections "In9.Cu")
		(net 35)
	)
	(via
		(at 263.55 167.489999)
		(size 0.45)
		(drill 0.1)
		(layers "F.Cu" "B.Cu")
		(remove_unused_layers yes)
		(keep_end_layers yes)
		(zone_layer_connections "In9.Cu")
		(net 35)
	)
	(via
		(at 233.035 186.985)
		(size 0.45)
		(drill 0.1)
		(layers "F.Cu" "B.Cu")
		(remove_unused_layers yes)
		(keep_end_layers yes)
		(zone_layer_connections "In9.Cu")
		(net 35)
	)
	(via
		(at 223.235 189.06)
		(size 0.45)
		(drill 0.1)
		(layers "F.Cu" "B.Cu")
		(remove_unused_layers yes)
		(keep_end_layers yes)
		(zone_layer_connections "In9.Cu")
		(net 35)
	)
	(via
		(at 263.55 151.039999)
		(size 0.45)
		(drill 0.1)
		(layers "F.Cu" "B.Cu")
		(remove_unused_layers yes)
		(keep_end_layers yes)
		(zone_layer_connections "In9.Cu")
		(net 35)
	)
	(via
		(at 262.516 153.18)
		(size 0.45)
		(drill 0.1)
		(layers "F.Cu" "B.Cu")
		(remove_unused_layers yes)
		(keep_end_layers yes)
		(zone_layer_connections "In9.Cu")
		(net 35)
	)
	(via
		(at 232.185 189.06)
		(size 0.45)
		(drill 0.1)
		(layers "F.Cu" "B.Cu")
		(remove_unused_layers yes)
		(keep_end_layers yes)
		(zone_layer_connections "In9.Cu")
		(net 35)
	)
	(via
		(at 245.825 128.925)
		(size 0.45)
		(drill 0.1)
		(layers "F.Cu" "B.Cu")
		(remove_unused_layers yes)
		(keep_end_layers yes)
		(zone_layer_connections "In9.Cu")
		(net 35)
	)
	(via
		(at 263.55 170.7)
		(size 0.45)
		(drill 0.1)
		(layers "F.Cu" "B.Cu")
		(remove_unused_layers yes)
		(keep_end_layers yes)
		(zone_layer_connections "In9.Cu")
		(net 35)
	)
	(via
		(at 245.825 129.7)
		(size 0.45)
		(drill 0.1)
		(layers "F.Cu" "B.Cu")
		(remove_unused_layers yes)
		(keep_end_layers yes)
		(zone_layer_connections "In9.Cu")
		(net 35)
	)
	(via
		(at 249.33 118.28)
		(size 0.45)
		(drill 0.1)
		(layers "F.Cu" "B.Cu")
		(net 35)
	)
	(via
		(at 233.285 189.46)
		(size 0.45)
		(drill 0.1)
		(layers "F.Cu" "B.Cu")
		(remove_unused_layers yes)
		(keep_end_layers yes)
		(zone_layer_connections "In9.Cu")
		(net 35)
	)
	(via
		(at 248.3 118.83)
		(size 0.45)
		(drill 0.1)
		(layers "F.Cu" "B.Cu")
		(net 35)
	)
	(via
		(at 262.55 166.45)
		(size 0.45)
		(drill 0.1)
		(layers "F.Cu" "B.Cu")
		(remove_unused_layers yes)
		(keep_end_layers yes)
		(zone_layer_connections "In9.Cu")
		(net 35)
	)
	(via
		(at 262.55 167.514999)
		(size 0.45)
		(drill 0.1)
		(layers "F.Cu" "B.Cu")
		(remove_unused_layers yes)
		(keep_end_layers yes)
		(zone_layer_connections "In9.Cu")
		(net 35)
	)
	(via
		(at 250.429476 118.429476)
		(size 0.45)
		(drill 0.1)
		(layers "F.Cu" "B.Cu")
		(net 35)
	)
	(via
		(at 233.035 185.935)
		(size 0.45)
		(drill 0.1)
		(layers "F.Cu" "B.Cu")
		(remove_unused_layers yes)
		(keep_end_layers yes)
		(zone_layer_connections "In9.Cu")
		(net 35)
	)
	(via
		(at 252.149499 130.449)
		(size 0.45)
		(drill 0.1)
		(layers "F.Cu" "B.Cu")
		(remove_unused_layers yes)
		(keep_end_layers yes)
		(zone_layer_connections "In9.Cu")
		(net 35)
	)
	(via
		(at 222.41 188.06)
		(size 0.45)
		(drill 0.1)
		(layers "F.Cu" "B.Cu")
		(remove_unused_layers yes)
		(keep_end_layers yes)
		(zone_layer_connections "In9.Cu")
		(net 35)
	)
	(via
		(at 149.562 187.7)
		(size 0.45)
		(drill 0.1)
		(layers "F.Cu" "B.Cu")
		(remove_unused_layers yes)
		(keep_end_layers yes)
		(zone_layer_connections "In9.Cu")
		(net 35)
	)
	(via
		(at 261.41 153.18)
		(size 0.45)
		(drill 0.1)
		(layers "F.Cu" "B.Cu")
		(remove_unused_layers yes)
		(keep_end_layers yes)
		(zone_layer_connections "In9.Cu")
		(net 35)
	)
	(via
		(at 261.41 170.7)
		(size 0.45)
		(drill 0.1)
		(layers "F.Cu" "B.Cu")
		(remove_unused_layers yes)
		(keep_end_layers yes)
		(zone_layer_connections "In9.Cu")
		(net 35)
	)
	(via
		(at 232.085 188.085)
		(size 0.45)
		(drill 0.1)
		(layers "F.Cu" "B.Cu")
		(remove_unused_layers yes)
		(keep_end_layers yes)
		(zone_layer_connections "In9.Cu")
		(net 35)
	)
	(via
		(at 149.725 184.8)
		(size 0.45)
		(drill 0.1)
		(layers "F.Cu" "B.Cu")
		(remove_unused_layers yes)
		(keep_end_layers yes)
		(zone_layer_connections "In9.Cu")
		(net 35)
	)
	(via
		(at 149.062501 185.576)
		(size 0.45)
		(drill 0.1)
		(layers "F.Cu" "B.Cu")
		(remove_unused_layers yes)
		(keep_end_layers yes)
		(zone_layer_connections "In9.Cu")
		(net 35)
	)
	(via
		(at 225.485 189.06)
		(size 0.45)
		(drill 0.1)
		(layers "F.Cu" "B.Cu")
		(remove_unused_layers yes)
		(keep_end_layers yes)
		(zone_layer_connections "In9.Cu")
		(net 35)
	)
	(via
		(at 251.287998 127.029)
		(size 0.45)
		(drill 0.1)
		(layers "F.Cu" "B.Cu")
		(remove_unused_layers yes)
		(keep_end_layers yes)
		(zone_layer_connections "In9.Cu")
		(net 35)
	)
	(via
		(at 262.525 147.825)
		(size 0.45)
		(drill 0.1)
		(layers "F.Cu" "B.Cu")
		(remove_unused_layers yes)
		(keep_end_layers yes)
		(zone_layer_connections "In9.Cu")
		(net 35)
	)
	(via
		(at 261.41 149.969999)
		(size 0.45)
		(drill 0.1)
		(layers "F.Cu" "B.Cu")
		(remove_unused_layers yes)
		(keep_end_layers yes)
		(zone_layer_connections "In9.Cu")
		(net 35)
	)
	(via
		(at 248.76 118.27)
		(size 0.45)
		(drill 0.1)
		(layers "F.Cu" "B.Cu")
		(net 35)
	)
	(via
		(at 263.55 166.419998)
		(size 0.45)
		(drill 0.1)
		(layers "F.Cu" "B.Cu")
		(remove_unused_layers yes)
		(keep_end_layers yes)
		(zone_layer_connections "In9.Cu")
		(net 35)
	)
	(via
		(at 232.085 186.985)
		(size 0.45)
		(drill 0.1)
		(layers "F.Cu" "B.Cu")
		(remove_unused_layers yes)
		(keep_end_layers yes)
		(zone_layer_connections "In9.Cu")
		(net 35)
	)
	(via
		(at 263.55 149.969999)
		(size 0.45)
		(drill 0.1)
		(layers "F.Cu" "B.Cu")
		(remove_unused_layers yes)
		(keep_end_layers yes)
		(zone_layer_connections "In9.Cu")
		(net 35)
	)
	(via
		(at 222.41 185.95)
		(size 0.45)
		(drill 0.1)
		(layers "F.Cu" "B.Cu")
		(remove_unused_layers yes)
		(keep_end_layers yes)
		(zone_layer_connections "In9.Cu")
		(net 35)
	)
	(via
		(at 261.41 148.899998)
		(size 0.45)
		(drill 0.1)
		(layers "F.Cu" "B.Cu")
		(remove_unused_layers yes)
		(keep_end_layers yes)
		(zone_layer_connections "In9.Cu")
		(net 35)
	)
	(via
		(at 221.46 185.95)
		(size 0.45)
		(drill 0.1)
		(layers "F.Cu" "B.Cu")
		(remove_unused_layers yes)
		(keep_end_layers yes)
		(zone_layer_connections "In9.Cu")
		(net 35)
	)
	(via
		(at 244.225 129.25)
		(size 0.45)
		(drill 0.1)
		(layers "F.Cu" "B.Cu")
		(remove_unused_layers yes)
		(keep_end_layers yes)
		(zone_layer_connections "In9.Cu")
		(net 35)
	)
	(via
		(at 246.316258 129.256099)
		(size 0.45)
		(drill 0.1)
		(layers "F.Cu" "B.Cu")
		(remove_unused_layers yes)
		(keep_end_layers yes)
		(zone_layer_connections "In9.Cu")
		(net 35)
	)
	(via
		(at 244.825 129.7)
		(size 0.45)
		(drill 0.1)
		(layers "F.Cu" "B.Cu")
		(remove_unused_layers yes)
		(keep_end_layers yes)
		(zone_layer_connections "In9.Cu")
		(net 35)
	)
	(via
		(at 231.06 189.46)
		(size 0.45)
		(drill 0.1)
		(layers "F.Cu" "B.Cu")
		(remove_unused_layers yes)
		(keep_end_layers yes)
		(zone_layer_connections "In9.Cu")
		(net 35)
	)
	(via
		(at 261.41 168.559999)
		(size 0.45)
		(drill 0.1)
		(layers "F.Cu" "B.Cu")
		(remove_unused_layers yes)
		(keep_end_layers yes)
		(zone_layer_connections "In9.Cu")
		(net 35)
	)
	(via
		(at 222.11 189.46)
		(size 0.45)
		(drill 0.1)
		(layers "F.Cu" "B.Cu")
		(remove_unused_layers yes)
		(keep_end_layers yes)
		(zone_layer_connections "In9.Cu")
		(net 35)
	)
	(via
		(at 249.91 118.28)
		(size 0.45)
		(drill 0.1)
		(layers "F.Cu" "B.Cu")
		(net 35)
	)
	(via
		(at 245.325 129.3)
		(size 0.45)
		(drill 0.1)
		(layers "F.Cu" "B.Cu")
		(remove_unused_layers yes)
		(keep_end_layers yes)
		(zone_layer_connections "In9.Cu")
		(net 35)
	)
	(via
		(at 147.1 186.1)
		(size 0.45)
		(drill 0.1)
		(layers "F.Cu" "B.Cu")
		(remove_unused_layers yes)
		(keep_end_layers yes)
		(zone_layer_connections "In9.Cu")
		(net 35)
	)
	(via
		(at 227.71 189.06)
		(size 0.45)
		(drill 0.1)
		(layers "F.Cu" "B.Cu")
		(remove_unused_layers yes)
		(keep_end_layers yes)
		(zone_layer_connections "In9.Cu")
		(net 35)
	)
	(via
		(at 263.55 152.11)
		(size 0.45)
		(drill 0.1)
		(layers "F.Cu" "B.Cu")
		(remove_unused_layers yes)
		(keep_end_layers yes)
		(zone_layer_connections "In9.Cu")
		(net 35)
	)
	(via
		(at 249.3 119.4)
		(size 0.45)
		(drill 0.1)
		(layers "F.Cu" "B.Cu")
		(net 35)
	)
	(via
		(at 261.41 151.039999)
		(size 0.45)
		(drill 0.1)
		(layers "F.Cu" "B.Cu")
		(remove_unused_layers yes)
		(keep_end_layers yes)
		(zone_layer_connections "In9.Cu")
		(net 35)
	)
	(via
		(at 229.96 189.06)
		(size 0.45)
		(drill 0.1)
		(layers "F.Cu" "B.Cu")
		(remove_unused_layers yes)
		(keep_end_layers yes)
		(zone_layer_connections "In9.Cu")
		(net 35)
	)
	(via
		(at 232.085 185.935)
		(size 0.45)
		(drill 0.1)
		(layers "F.Cu" "B.Cu")
		(remove_unused_layers yes)
		(keep_end_layers yes)
		(zone_layer_connections "In9.Cu")
		(net 35)
	)
	(via
		(at 246.85 129.75)
		(size 0.45)
		(drill 0.1)
		(layers "F.Cu" "B.Cu")
		(remove_unused_layers yes)
		(keep_end_layers yes)
		(zone_layer_connections "In9.Cu")
		(net 35)
	)
	(via
		(at 262.55 170.725)
		(size 0.45)
		(drill 0.1)
		(layers "F.Cu" "B.Cu")
		(remove_unused_layers yes)
		(keep_end_layers yes)
		(zone_layer_connections "In9.Cu")
		(net 35)
	)
	(via
		(at 244.825 128.925)
		(size 0.45)
		(drill 0.1)
		(layers "F.Cu" "B.Cu")
		(remove_unused_layers yes)
		(keep_end_layers yes)
		(zone_layer_connections "In9.Cu")
		(net 35)
	)
	(via
		(at 228.81 189.46)
		(size 0.45)
		(drill 0.1)
		(layers "F.Cu" "B.Cu")
		(remove_unused_layers yes)
		(keep_end_layers yes)
		(zone_layer_connections "In9.Cu")
		(net 35)
	)
	(via
		(at 261.41 147.829997)
		(size 0.45)
		(drill 0.1)
		(layers "F.Cu" "B.Cu")
		(remove_unused_layers yes)
		(keep_end_layers yes)
		(zone_layer_connections "In9.Cu")
		(net 35)
	)
	(via
		(at 248.99 118.83)
		(size 0.45)
		(drill 0.1)
		(layers "F.Cu" "B.Cu")
		(net 35)
	)
	(via
		(at 261.41 152.11)
		(size 0.45)
		(drill 0.1)
		(layers "F.Cu" "B.Cu")
		(remove_unused_layers yes)
		(keep_end_layers yes)
		(zone_layer_connections "In9.Cu")
		(net 35)
	)
	(via
		(at 250.35 117.9)
		(size 0.45)
		(drill 0.1)
		(layers "F.Cu" "B.Cu")
		(net 35)
	)
	(via
		(at 263.55 168.559999)
		(size 0.45)
		(drill 0.1)
		(layers "F.Cu" "B.Cu")
		(remove_unused_layers yes)
		(keep_end_layers yes)
		(zone_layer_connections "In9.Cu")
		(net 35)
	)
	(via
		(at 221.46 188.06)
		(size 0.45)
		(drill 0.1)
		(layers "F.Cu" "B.Cu")
		(remove_unused_layers yes)
		(keep_end_layers yes)
		(zone_layer_connections "In9.Cu")
		(net 35)
	)
	(via
		(at 148.062501 186.376)
		(size 0.45)
		(drill 0.1)
		(layers "F.Cu" "B.Cu")
		(remove_unused_layers yes)
		(keep_end_layers yes)
		(zone_layer_connections "In9.Cu")
		(net 35)
	)
	(via
		(at 263.55 153.18)
		(size 0.45)
		(drill 0.1)
		(layers "F.Cu" "B.Cu")
		(remove_unused_layers yes)
		(keep_end_layers yes)
		(zone_layer_connections "In9.Cu")
		(net 35)
	)
	(via
		(at 147.95 185.35)
		(size 0.45)
		(drill 0.1)
		(layers "F.Cu" "B.Cu")
		(remove_unused_layers yes)
		(keep_end_layers yes)
		(zone_layer_connections "In9.Cu")
		(net 35)
	)
	(via
		(at 219.885 189.46)
		(size 0.45)
		(drill 0.1)
		(layers "F.Cu" "B.Cu")
		(remove_unused_layers yes)
		(keep_end_layers yes)
		(zone_layer_connections "In9.Cu")
		(net 35)
	)
	(via
		(at 262.525 148.899998)
		(size 0.45)
		(drill 0.1)
		(layers "F.Cu" "B.Cu")
		(remove_unused_layers yes)
		(keep_end_layers yes)
		(zone_layer_connections "In9.Cu")
		(net 35)
	)
	(via
		(at 263.55 169.63)
		(size 0.45)
		(drill 0.1)
		(layers "F.Cu" "B.Cu")
		(remove_unused_layers yes)
		(keep_end_layers yes)
		(zone_layer_connections "In9.Cu")
		(net 35)
	)
	(via
		(at 222.41 186.96)
		(size 0.45)
		(drill 0.1)
		(layers "F.Cu" "B.Cu")
		(remove_unused_layers yes)
		(keep_end_layers yes)
		(zone_layer_connections "In9.Cu")
		(net 35)
	)
	(via
		(at 261.41 166.419998)
		(size 0.45)
		(drill 0.1)
		(layers "F.Cu" "B.Cu")
		(remove_unused_layers yes)
		(keep_end_layers yes)
		(zone_layer_connections "In9.Cu")
		(net 35)
	)
	(via
		(at 261.41 167.489999)
		(size 0.45)
		(drill 0.1)
		(layers "F.Cu" "B.Cu")
		(remove_unused_layers yes)
		(keep_end_layers yes)
		(zone_layer_connections "In9.Cu")
		(net 35)
	)
	(via
		(at 221.01 189.06)
		(size 0.45)
		(drill 0.1)
		(layers "F.Cu" "B.Cu")
		(remove_unused_layers yes)
		(keep_end_layers yes)
		(zone_layer_connections "In9.Cu")
		(net 35)
	)
	(via
		(at 221.46 186.96)
		(size 0.45)
		(drill 0.1)
		(layers "F.Cu" "B.Cu")
		(remove_unused_layers yes)
		(keep_end_layers yes)
		(zone_layer_connections "In9.Cu")
		(net 35)
	)
	(via
		(at 150.112 188.3)
		(size 0.45)
		(drill 0.1)
		(layers "F.Cu" "B.Cu")
		(remove_unused_layers yes)
		(keep_end_layers yes)
		(zone_layer_connections "In9.Cu")
		(net 35)
	)
	(via
		(at 263.55 147.829997)
		(size 0.45)
		(drill 0.1)
		(layers "F.Cu" "B.Cu")
		(remove_unused_layers yes)
		(keep_end_layers yes)
		(zone_layer_connections "In9.Cu")
		(net 35)
	)
	(via
		(at 262.516 149.969999)
		(size 0.45)
		(drill 0.1)
		(layers "F.Cu" "B.Cu")
		(remove_unused_layers yes)
		(keep_end_layers yes)
		(zone_layer_connections "In9.Cu")
		(net 35)
	)
	(via
		(at 147.112 188.2)
		(size 0.45)
		(drill 0.1)
		(layers "F.Cu" "B.Cu")
		(remove_unused_layers yes)
		(keep_end_layers yes)
		(zone_layer_connections "In9.Cu")
		(net 35)
	)
	(via
		(at 262.525 151.039999)
		(size 0.45)
		(drill 0.1)
		(layers "F.Cu" "B.Cu")
		(remove_unused_layers yes)
		(keep_end_layers yes)
		(zone_layer_connections "In9.Cu")
		(net 35)
	)
	(via
		(at 261.41 169.63)
		(size 0.45)
		(drill 0.1)
		(layers "F.Cu" "B.Cu")
		(remove_unused_layers yes)
		(keep_end_layers yes)
		(zone_layer_connections "In9.Cu")
		(net 35)
	)
	(via
		(at 262.516 152.1)
		(size 0.45)
		(drill 0.1)
		(layers "F.Cu" "B.Cu")
		(remove_unused_layers yes)
		(keep_end_layers yes)
		(zone_layer_connections "In9.Cu")
		(net 35)
	)
	(via
		(at 150.262501 187.176)
		(size 0.45)
		(drill 0.1)
		(layers "F.Cu" "B.Cu")
		(remove_unused_layers yes)
		(keep_end_layers yes)
		(zone_layer_connections "In9.Cu")
		(net 35)
	)
	(via
		(at 246.880316 128.880721)
		(size 0.45)
		(drill 0.1)
		(layers "F.Cu" "B.Cu")
		(remove_unused_layers yes)
		(keep_end_layers yes)
		(zone_layer_connections "In9.Cu")
		(net 35)
	)
	(segment
		(start 252.149499 127.890501)
		(end 251.287998 127.029)
		(width 0.256)
		(layer "B.Cu")
		(net 35)
	)
	(segment
		(start 249.7 117.26)
		(end 249.55 117.11)
		(width 0.198)
		(layer "B.Cu")
		(net 35)
	)
	(segment
		(start 245.34 117.11)
		(end 246.8 117.11)
		(width 0.182)
		(layer "B.Cu")
		(net 35)
	)
	(segment
		(start 252.149499 130.449)
		(end 252.149499 127.890501)
		(width 0.256)
		(layer "B.Cu")
		(net 35)
	)
	(segment
		(start 249.55 117.11)
		(end 249.55 117.92)
		(width 0.198)
		(layer "B.Cu")
		(net 35)
	)
	(segment
		(start 248.73 118.24)
		(end 248.76 118.27)
		(width 0.182)
		(layer "B.Cu")
		(net 35)
	)
	(segment
		(start 246.8 117.11)
		(end 247.93 118.24)
		(width 0.182)
		(layer "B.Cu")
		(net 35)
	)
	(segment
		(start 249.55 117.92)
		(end 249.91 118.28)
		(width 0.198)
		(layer "B.Cu")
		(net 35)
	)
	(segment
		(start 247.93 118.24)
		(end 248.73 118.24)
		(width 0.182)
		(layer "B.Cu")
		(net 35)
	)
	(segment
		(start 259.6055 156.9335)
		(end 258.7555 156.9335)
		(width 0.182)
		(layer "F.Cu")
		(net 36)
	)
	(segment
		(start 259.693 157.021)
		(end 259.6055 156.9335)
		(width 0.182)
		(layer "F.Cu")
		(net 36)
	)
	(via
		(at 259.693 157.021)
		(size 0.45)
		(drill 0.1)
		(layers "F.Cu" "B.Cu")
		(remove_unused_layers yes)
		(keep_end_layers yes)
		(zone_layer_connections)
		(net 36)
	)
	(segment
		(start 259.74 156.974)
		(end 259.693 157.021)
		(width 0.256)
		(layer "B.Cu")
		(net 36)
	)
	(segment
		(start 260.383499 156.974)
		(end 259.74 156.974)
		(width 0.256)
		(layer "B.Cu")
		(net 36)
	)
	(segment
		(start 260.524499 156.833)
		(end 260.383499 156.974)
		(width 0.256)
		(layer "B.Cu")
		(net 36)
	)
	(segment
		(start 247.003 177.55)
		(end 247.823499 177.55)
		(width 0.1)
		(layer "F.Cu")
		(net 37)
	)
	(segment
		(start 248.82 174.722)
		(end 248.82 177.322)
		(width 0.4)
		(layer "F.Cu")
		(net 37)
	)
	(segment
		(start 247.823499 177.55)
		(end 247.824499 177.549)
		(width 0.1)
		(layer "F.Cu")
		(net 37)
	)
	(segment
		(start 248.87 174.672)
		(end 248.82 174.722)
		(width 0.4)
		(layer "F.Cu")
		(net 37)
	)
	(segment
		(start 249.873 178.375)
		(end 252.7695 178.375)
		(width 0.4)
		(layer "F.Cu")
		(net 37)
	)
	(segment
		(start 252.7695 178.375)
		(end 253.535 177.6095)
		(width 0.4)
		(layer "F.Cu")
		(net 37)
	)
	(segment
		(start 248.82 177.322)
		(end 249.873 178.375)
		(width 0.4)
		(layer "F.Cu")
		(net 37)
	)
	(segment
		(start 145.124499 172.049)
		(end 145.124499 172.764)
		(width 0.15)
		(layer "F.Cu")
		(net 38)
	)
	(segment
		(start 255.353499 131.738)
		(end 255.324499 131.767)
		(width 0.182)
		(layer "F.Cu")
		(net 38)
	)
	(segment
		(start 242.389499 164.88)
		(end 242.399499 164.89)
		(width 0.256)
		(layer "F.Cu")
		(net 38)
	)
	(segment
		(start 242.389499 174.75)
		(end 242.399499 174.76)
		(width 0.256)
		(layer "F.Cu")
		(net 38)
	)
	(segment
		(start 241.600499 185.757)
		(end 241.774499 185.583)
		(width 0.256)
		(layer "F.Cu")
		(net 38)
	)
	(segment
		(start 149.275499 170.378)
		(end 150.070499 170.378)
		(width 0.15)
		(layer "F.Cu")
		(net 38)
	)
	(segment
		(start 241.764499 174.75)
		(end 241.774499 174.74)
		(width 0.256)
		(layer "F.Cu")
		(net 38)
	)
	(segment
		(start 150.424499 172.764)
		(end 151.009499 172.764)
		(width 0.15)
		(layer "F.Cu")
		(net 38)
	)
	(segment
		(start 150.375499 170.683)
		(end 151.009499 170.683)
		(width 0.15)
		(layer "F.Cu")
		(net 38)
	)
	(segment
		(start 241.774499 181.833)
		(end 242.408499 181.833)
		(width 0.256)
		(layer "F.Cu")
		(net 38)
	)
	(segment
		(start 242.408499 181.833)
		(end 242.424499 181.849)
		(width 0.256)
		(layer "F.Cu")
		(net 38)
	)
	(segment
		(start 240.700499 169.2)
		(end 241.764499 169.2)
		(width 0.256)
		(layer "F.Cu")
		(net 38)
	)
	(segment
		(start 241.544499 155.5585)
		(end 241.774499 155.7885)
		(width 0.256)
		(layer "F.Cu")
		(net 38)
	)
	(segment
		(start 241.773998 156.267)
		(end 241.773998 155.789001)
		(width 0.4)
		(layer "F.Cu")
		(net 38)
	)
	(segment
		(start 145.374499 171.799)
		(end 145.124499 172.049)
		(width 0.15)
		(layer "F.Cu")
		(net 38)
	)
	(segment
		(start 255.424499 134.674)
		(end 255.424499 135.052)
		(width 0.256)
		(layer "F.Cu")
		(net 38)
	)
	(segment
		(start 241.600499 182.007)
		(end 241.774499 181.833)
		(width 0.256)
		(layer "F.Cu")
		(net 38)
	)
	(segment
		(start 241.774499 174.75)
		(end 242.389499 174.75)
		(width 0.256)
		(layer "F.Cu")
		(net 38)
	)
	(segment
		(start 240.651499 185.757)
		(end 241.600499 185.757)
		(width 0.256)
		(layer "F.Cu")
		(net 38)
	)
	(segment
		(start 256.373998 131.738)
		(end 255.353499 131.738)
		(width 0.182)
		(layer "F.Cu")
		(net 38)
	)
	(segment
		(start 151.450499 172.323)
		(end 151.450499 171.124)
		(width 0.15)
		(layer "F.Cu")
		(net 38)
	)
	(segment
		(start 241.764499 169.2)
		(end 241.774499 169.19)
		(width 0.256)
		(layer "F.Cu")
		(net 38)
	)
	(segment
		(start 240.624499 165.349)
		(end 241.305499 165.349)
		(width 0.256)
		(layer "F.Cu")
		(net 38)
	)
	(segment
		(start 151.009499 172.764)
		(end 151.450499 172.323)
		(width 0.15)
		(layer "F.Cu")
		(net 38)
	)
	(segment
		(start 150.070499 170.378)
		(end 150.375499 170.683)
		(width 0.15)
		(layer "F.Cu")
		(net 38)
	)
	(segment
		(start 256.825 128.441)
		(end 256.825 127.866001)
		(width 0.256)
		(layer "F.Cu")
		(net 38)
	)
	(segment
		(start 241.774499 185.583)
		(end 242.408499 185.583)
		(width 0.256)
		(layer "F.Cu")
		(net 38)
	)
	(segment
		(start 255.243499 141.25)
		(end 255.239499 141.254)
		(width 0.198)
		(layer "F.Cu")
		(net 38)
	)
	(segment
		(start 151.009499 170.683)
		(end 151.025499 170.699)
		(width 0.15)
		(layer "F.Cu")
		(net 38)
	)
	(segment
		(start 241.773998 155.789001)
		(end 241.774499 155.7885)
		(width 0.4)
		(layer "F.Cu")
		(net 38)
	)
	(segment
		(start 240.738499 155.5585)
		(end 241.544499 155.5585)
		(width 0.256)
		(layer "F.Cu")
		(net 38)
	)
	(segment
		(start 241.305499 165.349)
		(end 241.774499 164.88)
		(width 0.256)
		(layer "F.Cu")
		(net 38)
	)
	(segment
		(start 241.774499 164.88)
		(end 242.389499 164.88)
		(width 0.256)
		(layer "F.Cu")
		(net 38)
	)
	(segment
		(start 240.651499 182.007)
		(end 241.600499 182.007)
		(width 0.256)
		(layer "F.Cu")
		(net 38)
	)
	(segment
		(start 151.450499 171.124)
		(end 151.025499 170.699)
		(width 0.15)
		(layer "F.Cu")
		(net 38)
	)
	(segment
		(start 240.700499 174.75)
		(end 241.764499 174.75)
		(width 0.256)
		(layer "F.Cu")
		(net 38)
	)
	(segment
		(start 255.449499 134.649)
		(end 255.424499 134.674)
		(width 0.256)
		(layer "F.Cu")
		(net 38)
	)
	(segment
		(start 256.825 127.866001)
		(end 256.817998 127.858999)
		(width 0.256)
		(layer "F.Cu")
		(net 38)
	)
	(segment
		(start 255.424499 135.052)
		(end 255.173999 135.3025)
		(width 0.256)
		(layer "F.Cu")
		(net 38)
	)
	(segment
		(start 241.774499 169.19)
		(end 242.389499 169.19)
		(width 0.256)
		(layer "F.Cu")
		(net 38)
	)
	(segment
		(start 256.824499 134.649)
		(end 255.449499 134.649)
		(width 0.256)
		(layer "F.Cu")
		(net 38)
	)
	(segment
		(start 256.338998 141.25)
		(end 255.243499 141.25)
		(width 0.198)
		(layer "F.Cu")
		(net 38)
	)
	(segment
		(start 242.389499 169.19)
		(end 242.399499 169.2)
		(width 0.256)
		(layer "F.Cu")
		(net 38)
	)
	(segment
		(start 242.408499 185.583)
		(end 242.424499 185.599)
		(width 0.256)
		(layer "F.Cu")
		(net 38)
	)
	(via
		(at 256.373998 131.738)
		(size 0.45)
		(drill 0.1)
		(layers "F.Cu" "B.Cu")
		(remove_unused_layers yes)
		(keep_end_layers yes)
		(zone_layer_connections)
		(net 38)
	)
	(via
		(at 242.399499 169.2)
		(size 0.45)
		(drill 0.1)
		(layers "F.Cu" "B.Cu")
		(remove_unused_layers yes)
		(keep_end_layers yes)
		(zone_layer_connections)
		(net 38)
	)
	(via
		(at 256.817998 127.858999)
		(size 0.45)
		(drill 0.1)
		(layers "F.Cu" "B.Cu")
		(remove_unused_layers yes)
		(keep_end_layers yes)
		(zone_layer_connections)
		(net 38)
	)
	(via
		(at 242.424499 181.849)
		(size 0.45)
		(drill 0.1)
		(layers "F.Cu" "B.Cu")
		(remove_unused_layers yes)
		(keep_end_layers yes)
		(zone_layer_connections)
		(net 38)
	)
	(via
		(at 241.773998 156.267)
		(size 0.45)
		(drill 0.1)
		(layers "F.Cu" "B.Cu")
		(remove_unused_layers yes)
		(keep_end_layers yes)
		(zone_layer_connections)
		(net 38)
	)
	(via
		(at 256.338998 141.25)
		(size 0.45)
		(drill 0.1)
		(layers "F.Cu" "B.Cu")
		(remove_unused_layers yes)
		(keep_end_layers yes)
		(zone_layer_connections)
		(net 38)
	)
	(via
		(at 253.524499 138.645)
		(size 0.45)
		(drill 0.1)
		(layers "F.Cu" "B.Cu")
		(remove_unused_layers yes)
		(keep_end_layers yes)
		(zone_layer_connections)
		(net 38)
	)
	(via
		(at 242.399499 174.76)
		(size 0.45)
		(drill 0.1)
		(layers "F.Cu" "B.Cu")
		(remove_unused_layers yes)
		(keep_end_layers yes)
		(zone_layer_connections)
		(net 38)
	)
	(via
		(at 151.025499 170.699)
		(size 0.45)
		(drill 0.1)
		(layers "F.Cu" "B.Cu")
		(remove_unused_layers yes)
		(keep_end_layers yes)
		(zone_layer_connections)
		(net 38)
	)
	(via
		(at 255.424499 134.674)
		(size 0.45)
		(drill 0.1)
		(layers "F.Cu" "B.Cu")
		(remove_unused_layers yes)
		(keep_end_layers yes)
		(zone_layer_connections)
		(net 38)
	)
	(via
		(at 239.4875 166.26)
		(size 0.45)
		(drill 0.1)
		(layers "F.Cu" "B.Cu")
		(remove_unused_layers yes)
		(keep_end_layers yes)
		(zone_layer_connections)
		(net 38)
	)
	(via
		(at 242.424499 185.599)
		(size 0.45)
		(drill 0.1)
		(layers "F.Cu" "B.Cu")
		(remove_unused_layers yes)
		(keep_end_layers yes)
		(zone_layer_connections)
		(net 38)
	)
	(via
		(at 145.374499 171.799)
		(size 0.45)
		(drill 0.1)
		(layers "F.Cu" "B.Cu")
		(remove_unused_layers yes)
		(keep_end_layers yes)
		(zone_layer_connections)
		(net 38)
	)
	(via
		(at 237.7745 140.0975)
		(size 0.45)
		(drill 0.1)
		(layers "F.Cu" "B.Cu")
		(remove_unused_layers yes)
		(keep_end_layers yes)
		(zone_layer_connections)
		(net 38)
	)
	(via
		(at 242.399499 164.89)
		(size 0.45)
		(drill 0.1)
		(layers "F.Cu" "B.Cu")
		(remove_unused_layers yes)
		(keep_end_layers yes)
		(zone_layer_connections)
		(net 38)
	)
	(segment
		(start 239.4875 166.26)
		(end 241.029499 166.26)
		(width 0.256)
		(layer "B.Cu")
		(net 38)
	)
	(segment
		(start 255.424499 135.449)
		(end 255.424499 134.674)
		(width 0.256)
		(layer "B.Cu")
		(net 38)
	)
	(segment
		(start 239.64 175.975)
		(end 239.64 175.435)
		(width 0.256)
		(layer "B.Cu")
		(net 38)
	)
	(segment
		(start 239.64 175.435)
		(end 240.325 174.75)
		(width 0.256)
		(layer "B.Cu")
		(net 38)
	)
	(segment
		(start 148.374499 171.799)
		(end 145.374499 171.799)
		(width 0.4)
		(layer "B.Cu")
		(net 38)
	)
	(segment
		(start 151.025499 170.699)
		(end 149.474499 170.699)
		(width 0.4)
		(layer "B.Cu")
		(net 38)
	)
	(segment
		(start 240.675 158.085)
		(end 241.35 157.41)
		(width 0.256)
		(layer "B.Cu")
		(net 38)
	)
	(segment
		(start 253.524499 139.3)
		(end 253.524499 141.3)
		(width 0.256)
		(layer "B.Cu")
		(net 38)
	)
	(segment
		(start 240.325 174.75)
		(end 242.399499 174.75)
		(width 0.256)
		(layer "B.Cu")
		(net 38)
	)
	(segment
		(start 256.338998 141.25)
		(end 256.323998 141.235)
		(width 0.182)
		(layer "B.Cu")
		(net 38)
	)
	(segment
		(start 239.64 170.425)
		(end 239.64 169.885)
		(width 0.256)
		(layer "B.Cu")
		(net 38)
	)
	(segment
		(start 255.124499 135.749)
		(end 255.424499 135.449)
		(width 0.256)
		(layer "B.Cu")
		(net 38)
	)
	(segment
		(start 256.364998 131.729)
		(end 255.724499 131.729)
		(width 0.256)
		(layer "B.Cu")
		(net 38)
	)
	(segment
		(start 240.325 169.2)
		(end 242.399499 169.2)
		(width 0.256)
		(layer "B.Cu")
		(net 38)
	)
	(segment
		(start 241.35 157.41)
		(end 241.35 156.690998)
		(width 0.256)
		(layer "B.Cu")
		(net 38)
	)
	(segment
		(start 149.474499 170.699)
		(end 148.374499 171.799)
		(width 0.4)
		(layer "B.Cu")
		(net 38)
	)
	(segment
		(start 239.4625 166.235)
		(end 239.4875 166.26)
		(width 0.182)
		(layer "B.Cu")
		(net 38)
	)
	(segment
		(start 238.289501 140.0975)
		(end 237.7745 140.0975)
		(width 0.4)
		(layer "B.Cu")
		(net 38)
	)
	(segment
		(start 255.399499 134.699)
		(end 255.424499 134.674)
		(width 0.256)
		(layer "B.Cu")
		(net 38)
	)
	(segment
		(start 256.323998 141.235)
		(end 255.689499 141.235)
		(width 0.182)
		(layer "B.Cu")
		(net 38)
	)
	(segment
		(start 239.64 169.885)
		(end 240.325 169.2)
		(width 0.256)
		(layer "B.Cu")
		(net 38)
	)
	(segment
		(start 256.373998 131.738)
		(end 256.364998 131.729)
		(width 0.182)
		(layer "B.Cu")
		(net 38)
	)
	(segment
		(start 238.924499 166.235)
		(end 239.4625 166.235)
		(width 0.182)
		(layer "B.Cu")
		(net 38)
	)
	(segment
		(start 253.524499 139.3)
		(end 253.524499 138.645)
		(width 0.256)
		(layer "B.Cu")
		(net 38)
	)
	(segment
		(start 241.35 156.690998)
		(end 241.773998 156.267)
		(width 0.256)
		(layer "B.Cu")
		(net 38)
	)
	(segment
		(start 241.029499 166.26)
		(end 242.399499 164.89)
		(width 0.256)
		(layer "B.Cu")
		(net 38)
	)
	(segment
		(start 238.289501 140.0975)
		(end 238.289501 141.147502)
		(width 0.4)
		(layer "B.Cu")
		(net 38)
	)
	(segment
		(start 254.658499 134.699)
		(end 255.399499 134.699)
		(width 0.256)
		(layer "B.Cu")
		(net 38)
	)
	(segment
		(start 254.684499 135.749)
		(end 255.124499 135.749)
		(width 0.256)
		(layer "B.Cu")
		(net 38)
	)
	(segment
		(start 238.289501 141.147502)
		(end 238.292999 141.151)
		(width 0.4)
		(layer "B.Cu")
		(net 38)
	)
	(segment
		(start 213.257537 188.15)
		(end 213.367537 188.26)
		(width 0.4)
		(layer "In6.Cu")
		(net 38)
	)
	(segment
		(start 207.113537 188.269)
		(end 211.608537 188.269)
		(width 0.4)
		(layer "In6.Cu")
		(net 38)
	)
	(segment
		(start 242.25 169.349499)
		(end 242.399499 169.2)
		(width 0.4)
		(layer "In6.Cu")
		(net 38)
	)
	(segment
		(start 249.875 146.025)
		(end 249.875 148.7)
		(width 0.4)
		(layer "In6.Cu")
		(net 38)
	)
	(segment
		(start 221.201116 185.325)
		(end 222.668884 185.325)
		(width 0.4)
		(layer "In6.Cu")
		(net 38)
	)
	(segment
		(start 238.525 182.625)
		(end 239.575 182.625)
		(width 0.4)
		(layer "In6.Cu")
		(net 38)
	)
	(segment
		(start 223.31 185.966116)
		(end 223.31 187.71)
		(width 0.4)
		(layer "In6.Cu")
		(net 38)
	)
	(segment
		(start 213.367537 188.26)
		(end 214.902463 188.26)
		(width 0.4)
		(layer "In6.Cu")
		(net 38)
	)
	(segment
		(start 241.773998 156.267)
		(end 241.283 156.267)
		(width 0.4)
		(layer "In6.Cu")
		(net 38)
	)
	(segment
		(start 242.25 171.65)
		(end 242.25 169.725)
		(width 0.4)
		(layer "In6.Cu")
		(net 38)
	)
	(segment
		(start 242.383998 164.874499)
		(end 242.399499 164.89)
		(width 0.4)
		(layer "In6.Cu")
		(net 38)
	)
	(segment
		(start 256.373998 131.738)
		(end 255.95 131.314002)
		(width 0.4)
		(layer "In6.Cu")
		(net 38)
	)
	(segment
		(start 242.85 181.849)
		(end 242.85 182.45)
		(width 0.4)
		(layer "In6.Cu")
		(net 38)
	)
	(segment
		(start 242.85 181.849)
		(end 242.424499 181.849)
		(width 0.4)
		(layer "In6.Cu")
		(net 38)
	)
	(segment
		(start 242.424499 185.599)
		(end 242.398499 185.625)
		(width 0.4)
		(layer "In6.Cu")
		(net 38)
	)
	(segment
		(start 241.874499 174.775)
		(end 241.874499 172.025501)
		(width 0.4)
		(layer "In6.Cu")
		(net 38)
	)
	(segment
		(start 149.324 171.799)
		(end 165.825 188.3)
		(width 0.4)
		(layer "In6.Cu")
		(net 38)
	)
	(segment
		(start 255.424499 134.674)
		(end 254.901 134.674)
		(width 0.4)
		(layer "In6.Cu")
		(net 38)
	)
	(segment
		(start 165.825 188.3)
		(end 207.082537 188.3)
		(width 0.4)
		(layer "In6.Cu")
		(net 38)
	)
	(segment
		(start 151.025499 170.699)
		(end 150.424 170.699)
		(width 0.4)
		(layer "In6.Cu")
		(net 38)
	)
	(segment
		(start 253.96475 136.133748)
		(end 253.959498 136.139)
		(width 0.4)
		(layer "In6.Cu")
		(net 38)
	)
	(segment
		(start 255.95 132.161998)
		(end 255.893499 132.218499)
		(width 0.4)
		(layer "In6.Cu")
		(net 38)
	)
	(segment
		(start 242.449499 185.574)
		(end 242.424499 185.599)
		(width 0.4)
		(layer "In6.Cu")
		(net 38)
	)
	(segment
		(start 254.25 141.65)
		(end 249.875 146.025)
		(width 0.4)
		(layer "In6.Cu")
		(net 38)
	)
	(segment
		(start 255.95 131.314002)
		(end 255.95 132.161998)
		(width 0.4)
		(layer "In6.Cu")
		(net 38)
	)
	(segment
		(start 254.901 134.674)
		(end 254.9 134.675)
		(width 0.4)
		(layer "In6.Cu")
		(net 38)
	)
	(segment
		(start 255.95 128.726997)
		(end 256.817998 127.858999)
		(width 0.4)
		(layer "In6.Cu")
		(net 38)
	)
	(segment
		(start 237.7745 139.365036)
		(end 237.7745 140.0975)
		(width 0.4)
		(layer "In6.Cu")
		(net 38)
	)
	(segment
		(start 242.399499 164.89)
		(end 241.89 164.89)
		(width 0.4)
		(layer "In6.Cu")
		(net 38)
	)
	(segment
		(start 242.25 169.575501)
		(end 241.874499 169.2)
		(width 0.4)
		(layer "In6.Cu")
		(net 38)
	)
	(segment
		(start 253.529499 138.65)
		(end 253.524499 138.645)
		(width 0.4)
		(layer "In6.Cu")
		(net 38)
	)
	(segment
		(start 237.5 185.238001)
		(end 237.8 184.938001)
		(width 0.4)
		(layer "In6.Cu")
		(net 38)
	)
	(segment
		(start 256.338998 141.25)
		(end 255.68975 141.25)
		(width 0.4)
		(layer "In6.Cu")
		(net 38)
	)
	(segment
		(start 241.89 164.89)
		(end 241.874499 164.874499)
		(width 0.4)
		(layer "In6.Cu")
		(net 38)
	)
	(segment
		(start 211.727537 188.15)
		(end 213.257537 188.15)
		(width 0.4)
		(layer "In6.Cu")
		(net 38)
	)
	(segment
		(start 242.25 169.725)
		(end 242.25 169.575501)
		(width 0.4)
		(layer "In6.Cu")
		(net 38)
	)
	(segment
		(start 241.874499 164.874499)
		(end 241.874499 157.674499)
		(width 0.4)
		(layer "In6.Cu")
		(net 38)
	)
	(segment
		(start 223.31 187.71)
		(end 224.035 188.435)
		(width 0.4)
		(layer "In6.Cu")
		(net 38)
	)
	(segment
		(start 241.874499 157.674499)
		(end 241.25 157.05)
		(width 0.4)
		(layer "In6.Cu")
		(net 38)
	)
	(segment
		(start 240.375 183.425)
		(end 240.375 185.15)
		(width 0.4)
		(layer "In6.Cu")
		(net 38)
	)
	(segment
		(start 241.839499 166.26)
		(end 241.874499 166.225)
		(width 0.4)
		(layer "In6.Cu")
		(net 38)
	)
	(segment
		(start 231.898115 185.238001)
		(end 237.5 185.238001)
		(width 0.4)
		(layer "In6.Cu")
		(net 38)
	)
	(segment
		(start 149.324 171.799)
		(end 145.374499 171.799)
		(width 0.4)
		(layer "In6.Cu")
		(net 38)
	)
	(segment
		(start 241.974499 185.625)
		(end 242.449499 185.15)
		(width 0.4)
		(layer "In6.Cu")
		(net 38)
	)
	(segment
		(start 241.875 185.625)
		(end 241.974499 185.625)
		(width 0.4)
		(layer "In6.Cu")
		(net 38)
	)
	(segment
		(start 241.25 151)
		(end 241.25 156.3)
		(width 0.4)
		(layer "In6.Cu")
		(net 38)
	)
	(segment
		(start 241.874499 164.874499)
		(end 242.383998 164.874499)
		(width 0.4)
		(layer "In6.Cu")
		(net 38)
	)
	(segment
		(start 255.4 141.65)
		(end 254.25 141.65)
		(width 0.4)
		(layer "In6.Cu")
		(net 38)
	)
	(segment
		(start 256.373998 131.738)
		(end 255.893499 132.218499)
		(width 0.4)
		(layer "In6.Cu")
		(net 38)
	)
	(segment
		(start 242.85 182.45)
		(end 242.449499 182.850501)
		(width 0.4)
		(layer "In6.Cu")
		(net 38)
	)
	(segment
		(start 254.9 135.198498)
		(end 253.96475 136.133748)
		(width 0.4)
		(layer "In6.Cu")
		(net 38)
	)
	(segment
		(start 224.035 188.435)
		(end 228.701116 188.435)
		(width 0.4)
		(layer "In6.Cu")
		(net 38)
	)
	(segment
		(start 253.96475 139.08525)
		(end 255.68975 140.81025)
		(width 0.4)
		(layer "In6.Cu")
		(net 38)
	)
	(segment
		(start 242.85 176.1)
		(end 242.85 181.849)
		(width 0.4)
		(layer "In6.Cu")
		(net 38)
	)
	(segment
		(start 241.25 157.05)
		(end 241.25 156.3)
		(width 0.4)
		(layer "In6.Cu")
		(net 38)
	)
	(segment
		(start 255.68975 141.36025)
		(end 255.4 141.65)
		(width 0.4)
		(layer "In6.Cu")
		(net 38)
	)
	(segment
		(start 228.701116 188.435)
		(end 231.898115 185.238001)
		(width 0.4)
		(layer "In6.Cu")
		(net 38)
	)
	(segment
		(start 242.399499 169.2)
		(end 241.874499 169.2)
		(width 0.4)
		(layer "In6.Cu")
		(net 38)
	)
	(segment
		(start 241.874499 166.225)
		(end 241.874499 164.874499)
		(width 0.4)
		(layer "In6.Cu")
		(net 38)
	)
	(segment
		(start 216.547537 188.21)
		(end 218.316116 188.21)
		(width 0.4)
		(layer "In6.Cu")
		(net 38)
	)
	(segment
		(start 253.96475 136.133748)
		(end 253.96475 139.08525)
		(width 0.4)
		(layer "In6.Cu")
		(net 38)
	)
	(segment
		(start 241.874499 175.124499)
		(end 242.85 176.1)
		(width 0.4)
		(layer "In6.Cu")
		(net 38)
	)
	(segment
		(start 214.902463 188.26)
		(end 215.077463 188.085)
		(width 0.4)
		(layer "In6.Cu")
		(net 38)
	)
	(segment
		(start 242.25 169.725)
		(end 242.25 169.349499)
		(width 0.4)
		(layer "In6.Cu")
		(net 38)
	)
	(segment
		(start 255.893499 132.218499)
		(end 254.9 133.211998)
		(width 0.4)
		(layer "In6.Cu")
		(net 38)
	)
	(segment
		(start 240.375 185.15)
		(end 240.85 185.625)
		(width 0.4)
		(layer "In6.Cu")
		(net 38)
	)
	(segment
		(start 242.449499 185.15)
		(end 242.449499 185.574)
		(width 0.4)
		(layer "In6.Cu")
		(net 38)
	)
	(segment
		(start 207.082537 188.3)
		(end 207.113537 188.269)
		(width 0.4)
		(layer "In6.Cu")
		(net 38)
	)
	(segment
		(start 237.8 183.35)
		(end 238.525 182.625)
		(width 0.4)
		(layer "In6.Cu")
		(net 38)
	)
	(segment
		(start 240.85 185.625)
		(end 241.875 185.625)
		(width 0.4)
		(layer "In6.Cu")
		(net 38)
	)
	(segment
		(start 241.874499 174.775)
		(end 241.874499 175.124499)
		(width 0.4)
		(layer "In6.Cu")
		(net 38)
	)
	(segment
		(start 253.959498 136.139)
		(end 241.000536 136.139)
		(width 0.4)
		(layer "In6.Cu")
		(net 38)
	)
	(segment
		(start 242.399499 174.76)
		(end 241.889499 174.76)
		(width 0.4)
		(layer "In6.Cu")
		(net 38)
	)
	(segment
		(start 254.9 133.211998)
		(end 254.9 134.675)
		(width 0.4)
		(layer "In6.Cu")
		(net 38)
	)
	(segment
		(start 222.668884 185.325)
		(end 223.31 185.966116)
		(width 0.4)
		(layer "In6.Cu")
		(net 38)
	)
	(segment
		(start 237.8 184.938001)
		(end 237.8 183.35)
		(width 0.4)
		(layer "In6.Cu")
		(net 38)
	)
	(segment
		(start 254.9 134.675)
		(end 254.9 135.198498)
		(width 0.4)
		(layer "In6.Cu")
		(net 38)
	)
	(segment
		(start 215.077463 188.085)
		(end 216.422537 188.085)
		(width 0.4)
		(layer "In6.Cu")
		(net 38)
	)
	(segment
		(start 255.68975 140.81025)
		(end 255.68975 141.36025)
		(width 0.4)
		(layer "In6.Cu")
		(net 38)
	)
	(segment
		(start 253.96475 138.65)
		(end 253.529499 138.65)
		(width 0.4)
		(layer "In6.Cu")
		(net 38)
	)
	(segment
		(start 255.68975 141.25)
		(end 255.68975 140.81025)
		(width 0.4)
		(layer "In6.Cu")
		(net 38)
	)
	(segment
		(start 255.95 131.314002)
		(end 255.95 128.726997)
		(width 0.4)
		(layer "In6.Cu")
		(net 38)
	)
	(segment
		(start 242.449499 182.850501)
		(end 242.449499 185.15)
		(width 0.4)
		(layer "In6.Cu")
		(net 38)
	)
	(segment
		(start 243.05 149.2)
		(end 241.25 151)
		(width 0.4)
		(layer "In6.Cu")
		(net 38)
	)
	(segment
		(start 241.283 156.267)
		(end 241.25 156.3)
		(width 0.4)
		(layer "In6.Cu")
		(net 38)
	)
	(segment
		(start 218.316116 188.21)
		(end 221.201116 185.325)
		(width 0.4)
		(layer "In6.Cu")
		(net 38)
	)
	(segment
		(start 242.398499 185.625)
		(end 241.875 185.625)
		(width 0.4)
		(layer "In6.Cu")
		(net 38)
	)
	(segment
		(start 211.608537 188.269)
		(end 211.727537 188.15)
		(width 0.4)
		(layer "In6.Cu")
		(net 38)
	)
	(segment
		(start 150.424 170.699)
		(end 149.324 171.799)
		(width 0.4)
		(layer "In6.Cu")
		(net 38)
	)
	(segment
		(start 249.375 149.2)
		(end 243.05 149.2)
		(width 0.4)
		(layer "In6.Cu")
		(net 38)
	)
	(segment
		(start 241.000536 136.139)
		(end 237.7745 139.365036)
		(width 0.4)
		(layer "In6.Cu")
		(net 38)
	)
	(segment
		(start 241.874499 172.025501)
		(end 242.25 171.65)
		(width 0.4)
		(layer "In6.Cu")
		(net 38)
	)
	(segment
		(start 249.875 148.7)
		(end 249.375 149.2)
		(width 0.4)
		(layer "In6.Cu")
		(net 38)
	)
	(segment
		(start 239.4875 166.26)
		(end 241.839499 166.26)
		(width 0.4)
		(layer "In6.Cu")
		(net 38)
	)
	(segment
		(start 239.575 182.625)
		(end 240.375 183.425)
		(width 0.4)
		(layer "In6.Cu")
		(net 38)
	)
	(segment
		(start 216.422537 188.085)
		(end 216.547537 188.21)
		(width 0.4)
		(layer "In6.Cu")
		(net 38)
	)
	(segment
		(start 241.874499 169.2)
		(end 241.874499 166.225)
		(width 0.4)
		(layer "In6.Cu")
		(net 38)
	)
	(segment
		(start 241.889499 174.76)
		(end 241.874499 174.775)
		(width 0.4)
		(layer "In6.Cu")
		(net 38)
	)
	(segment
		(start 135.824499 184.798)
		(end 135.824499 183.749)
		(width 0.201)
		(layer "F.Cu")
		(net 39)
	)
	(segment
		(start 194.0005 157.0005)
		(end 194.5 157.5)
		(width 0.256)
		(layer "F.Cu")
		(net 40)
	)
	(via
		(at 194.5 157.5)
		(size 0.45)
		(drill 0.1)
		(layers "F.Cu" "B.Cu")
		(remove_unused_layers yes)
		(keep_end_layers yes)
		(zone_layer_connections)
		(net 40)
	)
	(segment
		(start 194 157)
		(end 194.5 157.5)
		(width 0.201)
		(layer "B.Cu")
		(net 40)
	)
	(segment
		(start 195 157)
		(end 194.5 157.5)
		(width 0.201)
		(layer "B.Cu")
		(net 40)
	)
	(segment
		(start 195.001 157)
		(end 195 157)
		(width 0.201)
		(layer "B.Cu")
		(net 40)
	)
	(segment
		(start 194 156.999)
		(end 194 157)
		(width 0.201)
		(layer "B.Cu")
		(net 40)
	)
	(segment
		(start 137.424499 184.797)
		(end 137.425499 184.798)
		(width 0.201)
		(layer "F.Cu")
		(net 41)
	)
	(segment
		(start 137.424499 183.749)
		(end 137.424499 184.797)
		(width 0.201)
		(layer "F.Cu")
		(net 41)
	)
	(segment
		(start 139.424499 183.764)
		(end 139.424499 184.797)
		(width 0.201)
		(layer "F.Cu")
		(net 42)
	)
	(segment
		(start 139.424499 184.797)
		(end 139.425499 184.798)
		(width 0.201)
		(layer "F.Cu")
		(net 42)
	)
	(segment
		(start 141.024499 184.797)
		(end 141.025499 184.798)
		(width 0.201)
		(layer "F.Cu")
		(net 43)
	)
	(segment
		(start 141.024499 183.749)
		(end 141.024499 184.797)
		(width 0.201)
		(layer "F.Cu")
		(net 43)
	)
	(segment
		(start 147.775499 171.383)
		(end 147.775499 172.234)
		(width 0.15)
		(layer "F.Cu")
		(net 44)
	)
	(segment
		(start 147.775499 172.234)
		(end 148.475499 172.933999)
		(width 0.15)
		(layer "F.Cu")
		(net 44)
	)
	(segment
		(start 248.793 157.221)
		(end 248.793 159.821)
		(width 0.4)
		(layer "F.Cu")
		(net 45)
	)
	(segment
		(start 253.6205 160.2935)
		(end 253.6205 160.171)
		(width 0.4)
		(layer "F.Cu")
		(net 45)
	)
	(segment
		(start 248.793 159.821)
		(end 249.893 160.921)
		(width 0.4)
		(layer "F.Cu")
		(net 45)
	)
	(segment
		(start 252.993 160.921)
		(end 253.6205 160.2935)
		(width 0.4)
		(layer "F.Cu")
		(net 45)
	)
	(segment
		(start 247.003 160.15)
		(end 247.798499 160.15)
		(width 0.1)
		(layer "F.Cu")
		(net 45)
	)
	(segment
		(start 249.893 160.921)
		(end 252.993 160.921)
		(width 0.4)
		(layer "F.Cu")
		(net 45)
	)
	(segment
		(start 247.798499 160.15)
		(end 247.799499 160.149)
		(width 0.1)
		(layer "F.Cu")
		(net 45)
	)
	(segment
		(start 249.793 149.621)
		(end 252.2705 149.621)
		(width 0.4)
		(layer "F.Cu")
		(net 46)
	)
	(segment
		(start 252.2705 149.621)
		(end 253.0205 150.371)
		(width 0.4)
		(layer "F.Cu")
		(net 46)
	)
	(segment
		(start 247.013 150.451)
		(end 247.778999 150.451)
		(width 0.1)
		(layer "F.Cu")
		(net 46)
	)
	(segment
		(start 248.793 150.621)
		(end 249.793 149.621)
		(width 0.4)
		(layer "F.Cu")
		(net 46)
	)
	(segment
		(start 248.793 153.221)
		(end 248.793 150.621)
		(width 0.4)
		(layer "F.Cu")
		(net 46)
	)
	(segment
		(start 247.778999 150.451)
		(end 247.779999 150.45)
		(width 0.1)
		(layer "F.Cu")
		(net 46)
	)
	(segment
		(start 257.573 165.62)
		(end 258.224 165.62)
		(width 0.1)
		(layer "F.Cu")
		(net 47)
	)
	(segment
		(start 258.224 165.62)
		(end 258.225 165.621)
		(width 0.1)
		(layer "F.Cu")
		(net 47)
	)
	(segment
		(start 249.82 167.122)
		(end 252.1975 167.122)
		(width 0.4)
		(layer "F.Cu")
		(net 48)
	)
	(segment
		(start 248.87 170.672)
		(end 248.87 168.072)
		(width 0.4)
		(layer "F.Cu")
		(net 48)
	)
	(segment
		(start 248.87 168.072)
		(end 249.82 167.122)
		(width 0.4)
		(layer "F.Cu")
		(net 48)
	)
	(segment
		(start 252.1975 167.122)
		(end 252.935 167.8595)
		(width 0.4)
		(layer "F.Cu")
		(net 48)
	)
	(segment
		(start 226.56 180.16)
		(end 225.891 180.16)
		(width 0.256)
		(layer "F.Cu")
		(net 49)
	)
	(segment
		(start 226.940001 180.540001)
		(end 226.56 180.16)
		(width 0.256)
		(layer "F.Cu")
		(net 49)
	)
	(segment
		(start 225.891 180.16)
		(end 225.881 180.17)
		(width 0.256)
		(layer "F.Cu")
		(net 49)
	)
	(segment
		(start 227.590001 180.540001)
		(end 226.940001 180.540001)
		(width 0.256)
		(layer "F.Cu")
		(net 49)
	)
	(segment
		(start 225.881 180.17)
		(end 225.881 179.185001)
		(width 0.256)
		(layer "F.Cu")
		(net 49)
	)
	(segment
		(start 246.903 138.101)
		(end 247.904 138.101)
		(width 0.256)
		(layer "F.Cu")
		(net 50)
	)
	(via
		(at 247.904 138.101)
		(size 0.45)
		(drill 0.1)
		(layers "F.Cu" "B.Cu")
		(remove_unused_layers yes)
		(keep_end_layers yes)
		(zone_layer_connections)
		(net 50)
	)
	(via
		(at 252.85 138.6)
		(size 0.45)
		(drill 0.1)
		(layers "F.Cu" "B.Cu")
		(remove_unused_layers yes)
		(keep_end_layers yes)
		(zone_layer_connections)
		(net 50)
	)
	(segment
		(start 253.2 138.25)
		(end 252.85 138.6)
		(width 0.1)
		(layer "B.Cu")
		(net 50)
	)
	(segment
		(start 254.809499 138.25)
		(end 253.2 138.25)
		(width 0.1)
		(layer "B.Cu")
		(net 50)
	)
	(segment
		(start 251.801 138.101)
		(end 247.904 138.101)
		(width 0.1)
		(layer "In4.Cu")
		(net 50)
	)
	(segment
		(start 252.85 138.6)
		(end 252.3 138.6)
		(width 0.1)
		(layer "In4.Cu")
		(net 50)
	)
	(segment
		(start 252.3 138.6)
		(end 251.801 138.101)
		(width 0.1)
		(layer "In4.Cu")
		(net 50)
	)
	(segment
		(start 246.55 106)
		(end 246.55 107.152)
		(width 0.38)
		(layer "F.Cu")
		(net 51)
	)
	(segment
		(start 196.0005 146.9995)
		(end 196.5 146.5)
		(width 0.256)
		(layer "F.Cu")
		(net 51)
	)
	(via
		(at 246.55 107.152)
		(size 0.45)
		(drill 0.1)
		(layers "F.Cu" "B.Cu")
		(remove_unused_layers yes)
		(keep_end_layers yes)
		(zone_layer_connections)
		(net 51)
	)
	(via
		(at 196.5 146.5)
		(size 0.45)
		(drill 0.1)
		(layers "F.Cu" "B.Cu")
		(remove_unused_layers yes)
		(keep_end_layers yes)
		(zone_layer_connections)
		(net 51)
	)
	(segment
		(start 209.738482 139.711521)
		(end 209.73848 139.71152)
		(width 0.148)
		(layer "In2.Cu")
		(net 51)
	)
	(segment
		(start 218.416986 131.752684)
		(end 217.185626 130.521324)
		(width 0.148)
		(layer "In2.Cu")
		(net 51)
	)
	(segment
		(start 211.494624 136.075)
		(end 213.175 136.075)
		(width 0.148)
		(layer "In2.Cu")
		(net 51)
	)
	(segment
		(start 215.235 134.93467)
		(end 214.003648 133.703318)
		(width 0.148)
		(layer "In2.Cu")
		(net 51)
	)
	(segment
		(start 220.53831 130.161691)
		(end 222 128.7)
		(width 0.148)
		(layer "In2.Cu")
		(net 51)
	)
	(segment
		(start 207.900001 141.09038)
		(end 207.405027 140.595406)
		(width 0.148)
		(layer "In2.Cu")
		(net 51)
	)
	(segment
		(start 246.6 111.95)
		(end 246.6 110.9495)
		(width 0.148)
		(layer "In2.Cu")
		(net 51)
	)
	(segment
		(start 216.295662 134.40434)
		(end 216.295664 134.404339)
		(width 0.148)
		(layer "In2.Cu")
		(net 51)
	)
	(segment
		(start 219.624644 129.451855)
		(end 219.779592 129.606803)
		(width 0.148)
		(layer "In2.Cu")
		(net 51)
	)
	(segment
		(start 209.243506 138.297307)
		(end 209.243507 138.297306)
		(width 0.148)
		(layer "In2.Cu")
		(net 51)
	)
	(segment
		(start 214.95 135.75)
		(end 215.235 135.465)
		(width 0.148)
		(layer "In2.Cu")
		(net 51)
	)
	(segment
		(start 215.594634 132.112317)
		(end 216.825995 133.343678)
		(width 0.148)
		(layer "In2.Cu")
		(net 51)
	)
	(segment
		(start 222 128.7)
		(end 224.9 128.7)
		(width 0.148)
		(layer "In2.Cu")
		(net 51)
	)
	(segment
		(start 210.657721 138.33266)
		(end 210.162747 137.837686)
		(width 0.148)
		(layer "In2.Cu")
		(net 51)
	)
	(segment
		(start 219.477648 130.692022)
		(end 218.246281 129.460655)
		(width 0.148)
		(layer "In2.Cu")
		(net 51)
	)
	(segment
		(start 208.819241 140.630762)
		(end 208.819242 140.630761)
		(width 0.148)
		(layer "In2.Cu")
		(net 51)
	)
	(segment
		(start 245.975 107.727)
		(end 246.55 107.152)
		(width 0.148)
		(layer "In2.Cu")
		(net 51)
	)
	(segment
		(start 198.385228 147.949499)
		(end 203.000501 147.949499)
		(width 0.148)
		(layer "In2.Cu")
		(net 51)
	)
	(segment
		(start 198.101 147.665271)
		(end 198.385228 147.949499)
		(width 0.148)
		(layer "In2.Cu")
		(net 51)
	)
	(segment
		(start 209.703127 138.297306)
		(end 210.198102 138.792281)
		(width 0.148)
		(layer "In2.Cu")
		(net 51)
	)
	(segment
		(start 203.000501 147.949499)
		(end 207.85 143.1)
		(width 0.148)
		(layer "In2.Cu")
		(net 51)
	)
	(segment
		(start 220.538311 130.161692)
		(end 220.53831 130.161691)
		(width 0.148)
		(layer "In2.Cu")
		(net 51)
	)
	(segment
		(start 216.295664 134.404339)
		(end 216.295662 134.404338)
		(width 0.148)
		(layer "In2.Cu")
		(net 51)
	)
	(segment
		(start 208.324266 139.216547)
		(end 208.324267 139.216546)
		(width 0.148)
		(layer "In2.Cu")
		(net 51)
	)
	(segment
		(start 219.934541 130.088252)
		(end 220.007981 130.161692)
		(width 0.148)
		(layer "In2.Cu")
		(net 51)
	)
	(segment
		(start 216.655311 131.05167)
		(end 217.886657 132.283016)
		(width 0.148)
		(layer "In2.Cu")
		(net 51)
	)
	(segment
		(start 207.864647 140.135786)
		(end 208.359622 140.630761)
		(width 0.148)
		(layer "In2.Cu")
		(net 51)
	)
	(segment
		(start 239.1 114.5)
		(end 244.05 114.5)
		(width 0.148)
		(layer "In2.Cu")
		(net 51)
	)
	(segment
		(start 196.819999 146.499999)
		(end 197.218999 146.898999)
		(width 0.148)
		(layer "In2.Cu")
		(net 51)
	)
	(segment
		(start 209.73848 139.251902)
		(end 209.738481 139.2519)
		(width 0.148)
		(layer "In2.Cu")
		(net 51)
	)
	(segment
		(start 215.064302 132.112318)
		(end 215.064304 132.112317)
		(width 0.148)
		(layer "In2.Cu")
		(net 51)
	)
	(segment
		(start 218.416987 132.283016)
		(end 218.416986 132.283014)
		(width 0.148)
		(layer "In2.Cu")
		(net 51)
	)
	(segment
		(start 216.295662 133.874008)
		(end 215.064302 132.642648)
		(width 0.148)
		(layer "In2.Cu")
		(net 51)
	)
	(segment
		(start 216.124979 131.051671)
		(end 216.124981 131.05167)
		(width 0.148)
		(layer "In2.Cu")
		(net 51)
	)
	(segment
		(start 207.9 141.090382)
		(end 207.900001 141.09038)
		(width 0.148)
		(layer "In2.Cu")
		(net 51)
	)
	(segment
		(start 217.185626 129.990994)
		(end 217.185628 129.990993)
		(width 0.148)
		(layer "In2.Cu")
		(net 51)
	)
	(segment
		(start 213.175 136.725)
		(end 211.494624 136.725)
		(width 0.148)
		(layer "In2.Cu")
		(net 51)
	)
	(segment
		(start 218.776613 128.930324)
		(end 219.298145 129.451856)
		(width 0.148)
		(layer "In2.Cu")
		(net 51)
	)
	(segment
		(start 208.81924 140.171142)
		(end 208.819241 140.17114)
		(width 0.148)
		(layer "In2.Cu")
		(net 51)
	)
	(segment
		(start 211.875 137.575)
		(end 213.175 137.575)
		(width 0.148)
		(layer "In2.Cu")
		(net 51)
	)
	(segment
		(start 214.15 135.6)
		(end 214.15 137.25)
		(width 0.148)
		(layer "In2.Cu")
		(net 51)
	)
	(segment
		(start 209.738481 139.711522)
		(end 209.738482 139.711521)
		(width 0.148)
		(layer "In2.Cu")
		(net 51)
	)
	(segment
		(start 207.85 143.1)
		(end 207.85 141.6)
		(width 0.148)
		(layer "In2.Cu")
		(net 51)
	)
	(segment
		(start 210.622367 137.378066)
		(end 211.117342 137.873041)
		(width 0.148)
		(layer "In2.Cu")
		(net 51)
	)
	(segment
		(start 208.819241 140.17114)
		(end 208.324267 139.676166)
		(width 0.148)
		(layer "In2.Cu")
		(net 51)
	)
	(segment
		(start 219.779592 129.933304)
		(end 219.934541 130.088252)
		(width 0.148)
		(layer "In2.Cu")
		(net 51)
	)
	(segment
		(start 217.356325 133.343678)
		(end 217.356324 133.343676)
		(width 0.148)
		(layer "In2.Cu")
		(net 51)
	)
	(segment
		(start 211.576962 137.873041)
		(end 211.875 137.575)
		(width 0.148)
		(layer "In2.Cu")
		(net 51)
	)
	(segment
		(start 209.738481 139.2519)
		(end 209.243507 138.756926)
		(width 0.148)
		(layer "In2.Cu")
		(net 51)
	)
	(segment
		(start 208.783887 139.216546)
		(end 209.278862 139.711521)
		(width 0.148)
		(layer "In2.Cu")
		(net 51)
	)
	(segment
		(start 214.003648 133.172988)
		(end 214.003649 133.172987)
		(width 0.148)
		(layer "In2.Cu")
		(net 51)
	)
	(segment
		(start 207.85 141.6)
		(end 207.9 141.55)
		(width 0.148)
		(layer "In2.Cu")
		(net 51)
	)
	(segment
		(start 210.657721 138.792282)
		(end 210.657722 138.792281)
		(width 0.148)
		(layer "In2.Cu")
		(net 51)
	)
	(segment
		(start 211.576961 137.873042)
		(end 211.576962 137.873041)
		(width 0.148)
		(layer "In2.Cu")
		(net 51)
	)
	(segment
		(start 218.246281 128.930325)
		(end 218.246283 128.930324)
		(width 0.148)
		(layer "In2.Cu")
		(net 51)
	)
	(segment
		(start 214.475 137.575)
		(end 214.95 137.1)
		(width 0.148)
		(layer "In2.Cu")
		(net 51)
	)
	(segment
		(start 197.218999 146.898999)
		(end 197.6005 146.898999)
		(width 0.148)
		(layer "In2.Cu")
		(net 51)
	)
	(segment
		(start 217.356324 132.813346)
		(end 216.124979 131.582001)
		(width 0.148)
		(layer "In2.Cu")
		(net 51)
	)
	(segment
		(start 198.101 147.399499)
		(end 198.101 147.665271)
		(width 0.148)
		(layer "In2.Cu")
		(net 51)
	)
	(segment
		(start 210.657722 138.792281)
		(end 210.65772 138.79228)
		(width 0.148)
		(layer "In2.Cu")
		(net 51)
	)
	(segment
		(start 214.95 137.1)
		(end 214.95 135.75)
		(width 0.148)
		(layer "In2.Cu")
		(net 51)
	)
	(segment
		(start 219.477649 131.222354)
		(end 219.477648 131.222352)
		(width 0.148)
		(layer "In2.Cu")
		(net 51)
	)
	(segment
		(start 213.5 135.75)
		(end 213.5 135.6)
		(width 0.148)
		(layer "In2.Cu")
		(net 51)
	)
	(segment
		(start 214.533979 133.172987)
		(end 215.765332 134.40434)
		(width 0.148)
		(layer "In2.Cu")
		(net 51)
	)
	(segment
		(start 246.6 110.9495)
		(end 245.975 110.3245)
		(width 0.148)
		(layer "In2.Cu")
		(net 51)
	)
	(segment
		(start 207.405026 140.135787)
		(end 207.405027 140.135786)
		(width 0.148)
		(layer "In2.Cu")
		(net 51)
	)
	(segment
		(start 217.715958 129.990993)
		(end 218.947319 131.222354)
		(width 0.148)
		(layer "In2.Cu")
		(net 51)
	)
	(segment
		(start 208.819242 140.630761)
		(end 208.81924 140.63076)
		(width 0.148)
		(layer "In2.Cu")
		(net 51)
	)
	(segment
		(start 244.05 114.5)
		(end 246.6 111.95)
		(width 0.148)
		(layer "In2.Cu")
		(net 51)
	)
	(segment
		(start 197.6005 146.898999)
		(end 198.101 147.399499)
		(width 0.148)
		(layer "In2.Cu")
		(net 51)
	)
	(segment
		(start 219.779592 129.770053)
		(end 219.779592 129.770054)
		(width 0.148)
		(layer "In2.Cu")
		(net 51)
	)
	(segment
		(start 213.5 137.25)
		(end 213.5 137.05)
		(width 0.148)
		(layer "In2.Cu")
		(net 51)
	)
	(segment
		(start 210.65772 138.332662)
		(end 210.657721 138.33266)
		(width 0.148)
		(layer "In2.Cu")
		(net 51)
	)
	(segment
		(start 210.162746 137.378067)
		(end 210.162747 137.378066)
		(width 0.148)
		(layer "In2.Cu")
		(net 51)
	)
	(segment
		(start 196.5 146.499999)
		(end 196.819999 146.499999)
		(width 0.148)
		(layer "In2.Cu")
		(net 51)
	)
	(segment
		(start 245.975 110.3245)
		(end 245.975 107.727)
		(width 0.148)
		(layer "In2.Cu")
		(net 51)
	)
	(segment
		(start 224.9 128.7)
		(end 239.1 114.5)
		(width 0.148)
		(layer "In2.Cu")
		(net 51)
	)
	(arc
		(start 208.81924 140.63076)
		(mid 208.914431 140.40095)
		(end 208.81924 140.171142)
		(width 0.148)
		(layer "In2.Cu")
		(net 51)
	)
	(arc
		(start 214.003649 133.172987)
		(mid 214.268814 133.063152)
		(end 214.533979 133.172987)
		(width 0.148)
		(layer "In2.Cu")
		(net 51)
	)
	(arc
		(start 213.175 137.575)
		(mid 213.40481 137.47981)
		(end 213.5 137.25)
		(width 0.148)
		(layer "In2.Cu")
		(net 51)
	)
	(arc
		(start 217.185628 129.990993)
		(mid 217.450793 129.881158)
		(end 217.715958 129.990993)
		(width 0.148)
		(layer "In2.Cu")
		(net 51)
	)
	(arc
		(start 218.246281 129.460655)
		(mid 218.136446 129.19549)
		(end 218.246281 128.930325)
		(width 0.148)
		(layer "In2.Cu")
		(net 51)
	)
	(arc
		(start 216.295662 134.404338)
		(mid 216.405497 134.139173)
		(end 216.295662 133.874008)
		(width 0.148)
		(layer "In2.Cu")
		(net 51)
	)
	(arc
		(start 217.185626 130.521324)
		(mid 217.075791 130.256159)
		(end 217.185626 129.990994)
		(width 0.148)
		(layer "In2.Cu")
		(net 51)
	)
	(arc
		(start 217.886657 132.283016)
		(mid 218.151822 132.392851)
		(end 218.416987 132.283016)
		(width 0.148)
		(layer "In2.Cu")
		(net 51)
	)
	(arc
		(start 213.175 136.075)
		(mid 213.40481 135.97981)
		(end 213.5 135.75)
		(width 0.148)
		(layer "In2.Cu")
		(net 51)
	)
	(arc
		(start 209.278862 139.711521)
		(mid 209.508671 139.806712)
		(end 209.738481 139.711522)
		(width 0.148)
		(layer "In2.Cu")
		(net 51)
	)
	(arc
		(start 219.779592 129.606803)
		(mid 219.813403 129.688429)
		(end 219.779592 129.770053)
		(width 0.148)
		(layer "In2.Cu")
		(net 51)
	)
	(arc
		(start 215.064302 132.642648)
		(mid 214.954467 132.377483)
		(end 215.064302 132.112318)
		(width 0.148)
		(layer "In2.Cu")
		(net 51)
	)
	(arc
		(start 209.243507 138.756926)
		(mid 209.148316 138.527117)
		(end 209.243506 138.297307)
		(width 0.148)
		(layer "In2.Cu")
		(net 51)
	)
	(arc
		(start 208.324267 139.216546)
		(mid 208.554077 139.121356)
		(end 208.783887 139.216546)
		(width 0.148)
		(layer "In2.Cu")
		(net 51)
	)
	(arc
		(start 213.5 137.05)
		(mid 213.40481 136.82019)
		(end 213.175 136.725)
		(width 0.148)
		(layer "In2.Cu")
		(net 51)
	)
	(arc
		(start 211.494624 136.725)
		(mid 211.264814 136.62981)
		(end 211.169624 136.4)
		(width 0.148)
		(layer "In2.Cu")
		(net 51)
	)
	(arc
		(start 219.461394 129.451855)
		(mid 219.54302 129.418046)
		(end 219.624644 129.451855)
		(width 0.148)
		(layer "In2.Cu")
		(net 51)
	)
	(arc
		(start 216.124981 131.05167)
		(mid 216.390146 130.941835)
		(end 216.655311 131.05167)
		(width 0.148)
		(layer "In2.Cu")
		(net 51)
	)
	(arc
		(start 218.416986 132.283014)
		(mid 218.526821 132.017849)
		(end 218.416986 131.752684)
		(width 0.148)
		(layer "In2.Cu")
		(net 51)
	)
	(arc
		(start 217.356324 133.343676)
		(mid 217.466159 133.078511)
		(end 217.356324 132.813346)
		(width 0.148)
		(layer "In2.Cu")
		(net 51)
	)
	(arc
		(start 209.73848 139.71152)
		(mid 209.833671 139.48171)
		(end 209.73848 139.251902)
		(width 0.148)
		(layer "In2.Cu")
		(net 51)
	)
	(arc
		(start 213.5 135.6)
		(mid 213.59519 135.37019)
		(end 213.825 135.275)
		(width 0.148)
		(layer "In2.Cu")
		(net 51)
	)
	(arc
		(start 218.947319 131.222354)
		(mid 219.212484 131.332189)
		(end 219.477649 131.222354)
		(width 0.148)
		(layer "In2.Cu")
		(net 51)
	)
	(arc
		(start 211.169624 136.4)
		(mid 211.264814 136.17019)
		(end 211.494624 136.075)
		(width 0.148)
		(layer "In2.Cu")
		(net 51)
	)
	(arc
		(start 219.477648 131.222352)
		(mid 219.587483 130.957187)
		(end 219.477648 130.692022)
		(width 0.148)
		(layer "In2.Cu")
		(net 51)
	)
	(arc
		(start 219.779592 129.770054)
		(mid 219.745781 129.851678)
		(end 219.779592 129.933304)
		(width 0.148)
		(layer "In2.Cu")
		(net 51)
	)
	(arc
		(start 219.298145 129.451856)
		(mid 219.37977 129.485665)
		(end 219.461394 129.451855)
		(width 0.148)
		(layer "In2.Cu")
		(net 51)
	)
	(arc
		(start 216.124979 131.582001)
		(mid 216.015144 131.316836)
		(end 216.124979 131.051671)
		(width 0.148)
		(layer "In2.Cu")
		(net 51)
	)
	(arc
		(start 216.825995 133.343678)
		(mid 217.09116 133.453513)
		(end 217.356325 133.343678)
		(width 0.148)
		(layer "In2.Cu")
		(net 51)
	)
	(arc
		(start 210.198102 138.792281)
		(mid 210.427911 138.887472)
		(end 210.657721 138.792282)
		(width 0.148)
		(layer "In2.Cu")
		(net 51)
	)
	(arc
		(start 215.235 135.465)
		(mid 215.344835 135.199835)
		(end 215.235 134.93467)
		(width 0.148)
		(layer "In2.Cu")
		(net 51)
	)
	(arc
		(start 211.117342 137.873041)
		(mid 211.347151 137.968232)
		(end 211.576961 137.873042)
		(width 0.148)
		(layer "In2.Cu")
		(net 51)
	)
	(arc
		(start 214.15 137.25)
		(mid 214.24519 137.47981)
		(end 214.475 137.575)
		(width 0.148)
		(layer "In2.Cu")
		(net 51)
	)
	(arc
		(start 215.064304 132.112317)
		(mid 215.329469 132.002482)
		(end 215.594634 132.112317)
		(width 0.148)
		(layer "In2.Cu")
		(net 51)
	)
	(arc
		(start 214.003648 133.703318)
		(mid 213.893813 133.438153)
		(end 214.003648 133.172988)
		(width 0.148)
		(layer "In2.Cu")
		(net 51)
	)
	(arc
		(start 213.825 135.275)
		(mid 214.05481 135.37019)
		(end 214.15 135.6)
		(width 0.148)
		(layer "In2.Cu")
		(net 51)
	)
	(arc
		(start 218.246283 128.930324)
		(mid 218.511448 128.820489)
		(end 218.776613 128.930324)
		(width 0.148)
		(layer "In2.Cu")
		(net 51)
	)
	(arc
		(start 207.9 141.55)
		(mid 207.995191 141.32019)
		(end 207.9 141.090382)
		(width 0.148)
		(layer "In2.Cu")
		(net 51)
	)
	(arc
		(start 209.243507 138.297306)
		(mid 209.473317 138.202116)
		(end 209.703127 138.297306)
		(width 0.148)
		(layer "In2.Cu")
		(net 51)
	)
	(arc
		(start 210.162747 137.378066)
		(mid 210.392557 137.282876)
		(end 210.622367 137.378066)
		(width 0.148)
		(layer "In2.Cu")
		(net 51)
	)
	(arc
		(start 208.324267 139.676166)
		(mid 208.229076 139.446357)
		(end 208.324266 139.216547)
		(width 0.148)
		(layer "In2.Cu")
		(net 51)
	)
	(arc
		(start 210.162747 137.837686)
		(mid 210.067556 137.607877)
		(end 210.162746 137.378067)
		(width 0.148)
		(layer "In2.Cu")
		(net 51)
	)
	(arc
		(start 220.007981 130.161692)
		(mid 220.273146 130.271527)
		(end 220.538311 130.161692)
		(width 0.148)
		(layer "In2.Cu")
		(net 51)
	)
	(arc
		(start 215.765332 134.40434)
		(mid 216.030497 134.514175)
		(end 216.295662 134.40434)
		(width 0.148)
		(layer "In2.Cu")
		(net 51)
	)
	(arc
		(start 210.65772 138.79228)
		(mid 210.752911 138.56247)
		(end 210.65772 138.332662)
		(width 0.148)
		(layer "In2.Cu")
		(net 51)
	)
	(arc
		(start 207.405027 140.135786)
		(mid 207.634837 140.040596)
		(end 207.864647 140.135786)
		(width 0.148)
		(layer "In2.Cu")
		(net 51)
	)
	(arc
		(start 207.405027 140.595406)
		(mid 207.309836 140.365597)
		(end 207.405026 140.135787)
		(width 0.148)
		(layer "In2.Cu")
		(net 51)
	)
	(arc
		(start 208.359622 140.630761)
		(mid 208.589431 140.725952)
		(end 208.819241 140.630762)
		(width 0.148)
		(layer "In2.Cu")
		(net 51)
	)
	(segment
		(start 244.85 106)
		(end 244.85 107.152)
		(width 0.38)
		(layer "F.Cu")
		(net 52)
	)
	(segment
		(start 196.0005 145.9995)
		(end 196.5 145.499999)
		(width 0.256)
		(layer "F.Cu")
		(net 52)
	)
	(via
		(at 244.85 107.152)
		(size 0.45)
		(drill 0.1)
		(layers "F.Cu" "B.Cu")
		(remove_unused_layers yes)
		(keep_end_layers yes)
		(zone_layer_connections)
		(net 52)
	)
	(via
		(at 196.5 145.499999)
		(size 0.45)
		(drill 0.1)
		(layers "F.Cu" "B.Cu")
		(remove_unused_layers yes)
		(keep_end_layers yes)
		(zone_layer_connections)
		(net 52)
	)
	(segment
		(start 233.9 103.45)
		(end 233.9 104.8)
		(width 0.148)
		(layer "In2.Cu")
		(net 52)
	)
	(segment
		(start 236.1 110.15)
		(end 236.1 107.4)
		(width 0.148)
		(layer "In2.Cu")
		(net 52)
	)
	(segment
		(start 205.8 129.86875)
		(end 205.8 142.75)
		(width 0.148)
		(layer "In2.Cu")
		(net 52)
	)
	(segment
		(start 235.885 103.425)
		(end 235.885 104.040306)
		(width 0.148)
		(layer "In2.Cu")
		(net 52)
	)
	(segment
		(start 230.8 104.55)
		(end 232.2 105.95)
		(width 0.148)
		(layer "In2.Cu")
		(net 52)
	)
	(segment
		(start 233.55 114.25)
		(end 233.55 117.25)
		(width 0.148)
		(layer "In2.Cu")
		(net 52)
	)
	(segment
		(start 233.1 104.8)
		(end 233.1 103.45)
		(width 0.148)
		(layer "In2.Cu")
		(net 52)
	)
	(segment
		(start 197.101 146.100999)
		(end 196.5 145.499999)
		(width 0.148)
		(layer "In2.Cu")
		(net 52)
	)
	(segment
		(start 236.62 103.05)
		(end 236.26 103.05)
		(width 0.148)
		(layer "In2.Cu")
		(net 52)
	)
	(segment
		(start 235.15 111.3)
		(end 235.15 112.65)
		(width 0.148)
		(layer "In2.Cu")
		(net 52)
	)
	(segment
		(start 236.35 107.15)
		(end 236.35 106.72)
		(width 0.148)
		(layer "In2.Cu")
		(net 52)
	)
	(segment
		(start 237.28 103.71)
		(end 236.62 103.05)
		(width 0.148)
		(layer "In2.Cu")
		(net 52)
	)
	(segment
		(start 232.7 103.05)
		(end 231.3 103.05)
		(width 0.148)
		(layer "In2.Cu")
		(net 52)
	)
	(segment
		(start 235.135 104.040306)
		(end 235.135 103.425)
		(width 0.148)
		(layer "In2.Cu")
		(net 52)
	)
	(segment
		(start 245.35 107.650999)
		(end 245.35 110.649)
		(width 0.148)
		(layer "In2.Cu")
		(net 52)
	)
	(segment
		(start 243.4 113.2)
		(end 241.03 113.2)
		(width 0.148)
		(layer "In2.Cu")
		(net 52)
	)
	(segment
		(start 238.88 111.05)
		(end 237 111.05)
		(width 0.148)
		(layer "In2.Cu")
		(net 52)
	)
	(segment
		(start 236.1 107.4)
		(end 236.35 107.15)
		(width 0.148)
		(layer "In2.Cu")
		(net 52)
	)
	(segment
		(start 208.66875 127)
		(end 205.8 129.86875)
		(width 0.148)
		(layer "In2.Cu")
		(net 52)
	)
	(segment
		(start 234.45 110.6)
		(end 235.15 111.3)
		(width 0.148)
		(layer "In2.Cu")
		(net 52)
	)
	(segment
		(start 232.2 105.95)
		(end 233.35 105.95)
		(width 0.148)
		(layer "In2.Cu")
		(net 52)
	)
	(segment
		(start 233.55 117.25)
		(end 223.8 127)
		(width 0.148)
		(layer "In2.Cu")
		(net 52)
	)
	(segment
		(start 244.925 111.074)
		(end 244.925 111.675)
		(width 0.148)
		(layer "In2.Cu")
		(net 52)
	)
	(segment
		(start 223.8 127)
		(end 208.66875 127)
		(width 0.148)
		(layer "In2.Cu")
		(net 52)
	)
	(segment
		(start 245.35 110.649)
		(end 244.925 111.074)
		(width 0.148)
		(layer "In2.Cu")
		(net 52)
	)
	(segment
		(start 234.76 103.05)
		(end 234.682429 103.05)
		(width 0.148)
		(layer "In2.Cu")
		(net 52)
	)
	(segment
		(start 237.28 105.79)
		(end 237.28 103.71)
		(width 0.148)
		(layer "In2.Cu")
		(net 52)
	)
	(segment
		(start 244.925 111.675)
		(end 243.4 113.2)
		(width 0.148)
		(layer "In2.Cu")
		(net 52)
	)
	(segment
		(start 237 111.05)
		(end 236.1 110.15)
		(width 0.148)
		(layer "In2.Cu")
		(net 52)
	)
	(segment
		(start 231.3 103.05)
		(end 230.8 103.55)
		(width 0.148)
		(layer "In2.Cu")
		(net 52)
	)
	(segment
		(start 205.8 142.75)
		(end 202.449001 146.100999)
		(width 0.148)
		(layer "In2.Cu")
		(net 52)
	)
	(segment
		(start 233.35 105.95)
		(end 234.45 107.05)
		(width 0.148)
		(layer "In2.Cu")
		(net 52)
	)
	(segment
		(start 230.8 103.55)
		(end 230.8 104.55)
		(width 0.148)
		(layer "In2.Cu")
		(net 52)
	)
	(segment
		(start 234.45 107.05)
		(end 234.45 110.6)
		(width 0.148)
		(layer "In2.Cu")
		(net 52)
	)
	(segment
		(start 244.8505 107.151499)
		(end 245.35 107.650999)
		(width 0.148)
		(layer "In2.Cu")
		(net 52)
	)
	(segment
		(start 235.15 112.65)
		(end 233.55 114.25)
		(width 0.148)
		(layer "In2.Cu")
		(net 52)
	)
	(segment
		(start 236.35 106.72)
		(end 237.28 105.79)
		(width 0.148)
		(layer "In2.Cu")
		(net 52)
	)
	(segment
		(start 241.03 113.2)
		(end 238.88 111.05)
		(width 0.148)
		(layer "In2.Cu")
		(net 52)
	)
	(segment
		(start 202.449001 146.100999)
		(end 197.101 146.100999)
		(width 0.148)
		(layer "In2.Cu")
		(net 52)
	)
	(segment
		(start 234.682429 103.05)
		(end 234.3 103.05)
		(width 0.148)
		(layer "In2.Cu")
		(net 52)
	)
	(arc
		(start 235.885 104.040306)
		(mid 235.775165 104.305471)
		(end 235.51 104.415306)
		(width 0.148)
		(layer "In2.Cu")
		(net 52)
	)
	(arc
		(start 235.135 103.425)
		(mid 235.025165 103.159835)
		(end 234.76 103.05)
		(width 0.148)
		(layer "In2.Cu")
		(net 52)
	)
	(arc
		(start 233.1 103.45)
		(mid 232.982843 103.167157)
		(end 232.7 103.05)
		(width 0.148)
		(layer "In2.Cu")
		(net 52)
	)
	(arc
		(start 233.5 105.2)
		(mid 233.217157 105.082843)
		(end 233.1 104.8)
		(width 0.148)
		(layer "In2.Cu")
		(net 52)
	)
	(arc
		(start 236.26 103.05)
		(mid 235.994835 103.159835)
		(end 235.885 103.425)
		(width 0.148)
		(layer "In2.Cu")
		(net 52)
	)
	(arc
		(start 235.51 104.415306)
		(mid 235.244835 104.305471)
		(end 235.135 104.040306)
		(width 0.148)
		(layer "In2.Cu")
		(net 52)
	)
	(arc
		(start 234.3 103.05)
		(mid 234.017157 103.167157)
		(end 233.9 103.45)
		(width 0.148)
		(layer "In2.Cu")
		(net 52)
	)
	(arc
		(start 233.9 104.8)
		(mid 233.782843 105.082843)
		(end 233.5 105.2)
		(width 0.148)
		(layer "In2.Cu")
		(net 52)
	)
	(segment
		(start 240.6 106)
		(end 240.6 107.152)
		(width 0.38)
		(layer "F.Cu")
		(net 53)
	)
	(segment
		(start 196.0005 147.9995)
		(end 196.5 147.5)
		(width 0.256)
		(layer "F.Cu")
		(net 53)
	)
	(via
		(at 196.5 147.5)
		(size 0.45)
		(drill 0.1)
		(layers "F.Cu" "B.Cu")
		(remove_unused_layers yes)
		(keep_end_layers yes)
		(zone_layer_connections)
		(net 53)
	)
	(via
		(at 240.6 107.152)
		(size 0.45)
		(drill 0.1)
		(layers "F.Cu" "B.Cu")
		(remove_unused_layers yes)
		(keep_end_layers yes)
		(zone_layer_connections)
		(net 53)
	)
	(segment
		(start 240.5 123.975)
		(end 240.750468 123.975)
		(width 0.148)
		(layer "In2.Cu")
		(net 53)
	)
	(segment
		(start 202.175 152.35)
		(end 202.9 151.625)
		(width 0.148)
		(layer "In2.Cu")
		(net 53)
	)
	(segment
		(start 244.075 119.5)
		(end 244.075 120.25)
		(width 0.148)
		(layer "In2.Cu")
		(net 53)
	)
	(segment
		(start 196.05 147.95)
		(end 195.446432 147.95)
		(width 0.148)
		(layer "In2.Cu")
		(net 53)
	)
	(segment
		(start 240.375 106.927)
		(end 240.6 107.152)
		(width 0.148)
		(layer "In2.Cu")
		(net 53)
	)
	(segment
		(start 243.375 120.25)
		(end 243.375 119.5)
		(width 0.148)
		(layer "In2.Cu")
		(net 53)
	)
	(segment
		(start 240.175 124.525)
		(end 240.175 124.3)
		(width 0.148)
		(layer "In2.Cu")
		(net 53)
	)
	(segment
		(start 245.089337 120.11066)
		(end 245.08934 120.11066)
		(width 0.148)
		(layer "In2.Cu")
		(net 53)
	)
	(segment
		(start 208.35 150.95)
		(end 216.45 142.85)
		(width 0.148)
		(layer "In2.Cu")
		(net 53)
	)
	(segment
		(start 252.05 105.2)
		(end 249.95 103.1)
		(width 0.148)
		(layer "In2.Cu")
		(net 53)
	)
	(segment
		(start 244.616731 118.71881)
		(end 244.616729 118.718811)
		(width 0.148)
		(layer "In2.Cu")
		(net 53)
	)
	(segment
		(start 246.00858 119.191422)
		(end 246.008581 119.191422)
		(width 0.148)
		(layer "In2.Cu")
		(net 53)
	)
	(segment
		(start 204.65 152.05)
		(end 206.05 152.05)
		(width 0.148)
		(layer "In2.Cu")
		(net 53)
	)
	(segment
		(start 242.35 120.6)
		(end 243.025 120.6)
		(width 0.148)
		(layer "In2.Cu")
		(net 53)
	)
	(segment
		(start 216.45 142.85)
		(end 221.85 142.85)
		(width 0.148)
		(layer "In2.Cu")
		(net 53)
	)
	(segment
		(start 195.446432 147.95)
		(end 195.025 148.371432)
		(width 0.148)
		(layer "In2.Cu")
		(net 53)
	)
	(segment
		(start 244.425 120.6)
		(end 244.6 120.6)
		(width 0.148)
		(layer "In2.Cu")
		(net 53)
	)
	(segment
		(start 204.225 151.625)
		(end 204.65 152.05)
		(width 0.148)
		(layer "In2.Cu")
		(net 53)
	)
	(segment
		(start 246.008581 119.191422)
		(end 246.216541 118.983459)
		(width 0.148)
		(layer "In2.Cu")
		(net 53)
	)
	(segment
		(start 206.05 152.05)
		(end 207.15 150.95)
		(width 0.148)
		(layer "In2.Cu")
		(net 53)
	)
	(segment
		(start 244.6 120.6)
		(end 245.089337 120.11066)
		(width 0.148)
		(layer "In2.Cu")
		(net 53)
	)
	(segment
		(start 195.675 152.35)
		(end 202.175 152.35)
		(width 0.148)
		(layer "In2.Cu")
		(net 53)
	)
	(segment
		(start 202.9 151.625)
		(end 204.225 151.625)
		(width 0.148)
		(layer "In2.Cu")
		(net 53)
	)
	(segment
		(start 196.5 147.5)
		(end 196.05 147.95)
		(width 0.148)
		(layer "In2.Cu")
		(net 53)
	)
	(segment
		(start 221.85 142.85)
		(end 240.175 124.525)
		(width 0.148)
		(layer "In2.Cu")
		(net 53)
	)
	(segment
		(start 246.216541 118.983459)
		(end 252.05 113.15)
		(width 0.148)
		(layer "In2.Cu")
		(net 53)
	)
	(segment
		(start 207.15 150.95)
		(end 208.35 150.95)
		(width 0.148)
		(layer "In2.Cu")
		(net 53)
	)
	(segment
		(start 195.025 151.7)
		(end 195.675 152.35)
		(width 0.148)
		(layer "In2.Cu")
		(net 53)
	)
	(segment
		(start 240.175 122.775)
		(end 242.35 120.6)
		(width 0.148)
		(layer "In2.Cu")
		(net 53)
	)
	(segment
		(start 245.089341 119.65104)
		(end 244.61673 119.178429)
		(width 0.148)
		(layer "In2.Cu")
		(net 53)
	)
	(segment
		(start 249.95 103.1)
		(end 242.541864 103.1)
		(width 0.148)
		(layer "In2.Cu")
		(net 53)
	)
	(segment
		(start 240.375 105.266864)
		(end 240.375 106.927)
		(width 0.148)
		(layer "In2.Cu")
		(net 53)
	)
	(segment
		(start 242.541864 103.1)
		(end 240.375 105.266864)
		(width 0.148)
		(layer "In2.Cu")
		(net 53)
	)
	(segment
		(start 245.076349 118.718811)
		(end 245.548961 119.191423)
		(width 0.148)
		(layer "In2.Cu")
		(net 53)
	)
	(segment
		(start 195.025 148.371432)
		(end 195.025 151.7)
		(width 0.148)
		(layer "In2.Cu")
		(net 53)
	)
	(segment
		(start 252.05 113.15)
		(end 252.05 105.2)
		(width 0.148)
		(layer "In2.Cu")
		(net 53)
	)
	(segment
		(start 245.08934 119.651042)
		(end 245.089341 119.65104)
		(width 0.148)
		(layer "In2.Cu")
		(net 53)
	)
	(segment
		(start 240.750468 123.325)
		(end 240.5 123.325)
		(width 0.148)
		(layer "In2.Cu")
		(net 53)
	)
	(segment
		(start 240.175 123)
		(end 240.175 122.775)
		(width 0.148)
		(layer "In2.Cu")
		(net 53)
	)
	(arc
		(start 243.725 119.15)
		(mid 243.972487 119.252513)
		(end 244.075 119.5)
		(width 0.148)
		(layer "In2.Cu")
		(net 53)
	)
	(arc
		(start 240.175 124.3)
		(mid 240.27019 124.07019)
		(end 240.5 123.975)
		(width 0.148)
		(layer "In2.Cu")
		(net 53)
	)
	(arc
		(start 240.5 123.325)
		(mid 240.27019 123.22981)
		(end 240.175 123)
		(width 0.148)
		(layer "In2.Cu")
		(net 53)
	)
	(arc
		(start 245.548961 119.191423)
		(mid 245.778771 119.286613)
		(end 246.00858 119.191422)
		(width 0.148)
		(layer "In2.Cu")
		(net 53)
	)
	(arc
		(start 244.075 120.25)
		(mid 244.177513 120.497487)
		(end 244.425 120.6)
		(width 0.148)
		(layer "In2.Cu")
		(net 53)
	)
	(arc
		(start 243.375 119.5)
		(mid 243.477513 119.252513)
		(end 243.725 119.15)
		(width 0.148)
		(layer "In2.Cu")
		(net 53)
	)
	(arc
		(start 241.075468 123.65)
		(mid 240.980278 123.42019)
		(end 240.750468 123.325)
		(width 0.148)
		(layer "In2.Cu")
		(net 53)
	)
	(arc
		(start 245.08934 120.11066)
		(mid 245.184531 119.88085)
		(end 245.08934 119.651042)
		(width 0.148)
		(layer "In2.Cu")
		(net 53)
	)
	(arc
		(start 243.025 120.6)
		(mid 243.272487 120.497487)
		(end 243.375 120.25)
		(width 0.148)
		(layer "In2.Cu")
		(net 53)
	)
	(arc
		(start 244.61673 119.178429)
		(mid 244.52154 118.948619)
		(end 244.616731 118.71881)
		(width 0.148)
		(layer "In2.Cu")
		(net 53)
	)
	(arc
		(start 240.750468 123.975)
		(mid 240.980278 123.87981)
		(end 241.075468 123.65)
		(width 0.148)
		(layer "In2.Cu")
		(net 53)
	)
	(arc
		(start 244.616729 118.718811)
		(mid 244.846539 118.623621)
		(end 245.076349 118.718811)
		(width 0.148)
		(layer "In2.Cu")
		(net 53)
	)
	(segment
		(start 195.0005 147.9995)
		(end 195.5 147.5)
		(width 0.256)
		(layer "F.Cu")
		(net 54)
	)
	(segment
		(start 238.9 106)
		(end 238.9 107.152)
		(width 0.38)
		(layer "F.Cu")
		(net 54)
	)
	(via
		(at 238.9 107.152)
		(size 0.45)
		(drill 0.1)
		(layers "F.Cu" "B.Cu")
		(remove_unused_layers yes)
		(keep_end_layers yes)
		(zone_layer_connections)
		(net 54)
	)
	(via
		(at 195.5 147.5)
		(size 0.45)
		(drill 0.1)
		(layers "F.Cu" "B.Cu")
		(remove_unused_layers yes)
		(keep_end_layers yes)
		(zone_layer_connections)
		(net 54)
	)
	(segment
		(start 194.3 147.975)
		(end 194 148.275)
		(width 0.148)
		(layer "In2.Cu")
		(net 54)
	)
	(segment
		(start 217.5 143.7)
		(end 222.575 143.7)
		(width 0.148)
		(layer "In2.Cu")
		(net 54)
	)
	(segment
		(start 242.275 102.525)
		(end 238.9 105.9)
		(width 0.148)
		(layer "In2.Cu")
		(net 54)
	)
	(segment
		(start 210.15 151.05)
		(end 210.15 150.45)
		(width 0.148)
		(layer "In2.Cu")
		(net 54)
	)
	(segment
		(start 195.2 147.5)
		(end 194.725 147.975)
		(width 0.148)
		(layer "In2.Cu")
		(net 54)
	)
	(segment
		(start 204.113772 152.45)
		(end 208.75 152.45)
		(width 0.148)
		(layer "In2.Cu")
		(net 54)
	)
	(segment
		(start 210.6 150)
		(end 211.2 150)
		(width 0.148)
		(layer "In2.Cu")
		(net 54)
	)
	(segment
		(start 195.125 152.75)
		(end 202.575 152.75)
		(width 0.148)
		(layer "In2.Cu")
		(net 54)
	)
	(segment
		(start 250.301087 102.525)
		(end 242.275 102.525)
		(width 0.148)
		(layer "In2.Cu")
		(net 54)
	)
	(segment
		(start 194.725 147.975)
		(end 194.3 147.975)
		(width 0.148)
		(layer "In2.Cu")
		(net 54)
	)
	(segment
		(start 202.575 152.75)
		(end 203.25 152.075)
		(width 0.148)
		(layer "In2.Cu")
		(net 54)
	)
	(segment
		(start 252.95 113.325)
		(end 252.95 105.173913)
		(width 0.148)
		(layer "In2.Cu")
		(net 54)
	)
	(segment
		(start 208.75 152.45)
		(end 210.15 151.05)
		(width 0.148)
		(layer "In2.Cu")
		(net 54)
	)
	(segment
		(start 194 148.275)
		(end 194 151.625)
		(width 0.148)
		(layer "In2.Cu")
		(net 54)
	)
	(segment
		(start 195.5 147.5)
		(end 195.2 147.5)
		(width 0.148)
		(layer "In2.Cu")
		(net 54)
	)
	(segment
		(start 211.2 150)
		(end 217.5 143.7)
		(width 0.148)
		(layer "In2.Cu")
		(net 54)
	)
	(segment
		(start 210.15 150.45)
		(end 210.6 150)
		(width 0.148)
		(layer "In2.Cu")
		(net 54)
	)
	(segment
		(start 203.738772 152.075)
		(end 204.113772 152.45)
		(width 0.148)
		(layer "In2.Cu")
		(net 54)
	)
	(segment
		(start 194 151.625)
		(end 195.125 152.75)
		(width 0.148)
		(layer "In2.Cu")
		(net 54)
	)
	(segment
		(start 238.9 105.9)
		(end 238.9 107.152)
		(width 0.148)
		(layer "In2.Cu")
		(net 54)
	)
	(segment
		(start 252.95 105.173913)
		(end 250.301087 102.525)
		(width 0.148)
		(layer "In2.Cu")
		(net 54)
	)
	(segment
		(start 203.25 152.075)
		(end 203.738772 152.075)
		(width 0.148)
		(layer "In2.Cu")
		(net 54)
	)
	(segment
		(start 222.575 143.7)
		(end 252.95 113.325)
		(width 0.148)
		(layer "In2.Cu")
		(net 54)
	)
	(segment
		(start 201.0005 147.9995)
		(end 201.5 147.5)
		(width 0.256)
		(layer "F.Cu")
		(net 55)
	)
	(segment
		(start 237.2 106)
		(end 237.2 107.152)
		(width 0.38)
		(layer "F.Cu")
		(net 55)
	)
	(via
		(at 237.2 107.152)
		(size 0.45)
		(drill 0.1)
		(layers "F.Cu" "B.Cu")
		(remove_unused_layers yes)
		(keep_end_layers yes)
		(zone_layer_connections)
		(net 55)
	)
	(via
		(at 201.5 147.5)
		(size 0.45)
		(drill 0.1)
		(layers "F.Cu" "B.Cu")
		(remove_unused_layers yes)
		(keep_end_layers yes)
		(zone_layer_connections)
		(net 55)
	)
	(segment
		(start 210.64283 144.8625)
		(end 211.218484 145.438154)
		(width 0.148)
		(layer "In4.Cu")
		(net 55)
	)
	(segment
		(start 213.55 141.425)
		(end 213.294482 141.680517)
		(width 0.148)
		(layer "In4.Cu")
		(net 55)
	)
	(segment
		(start 214.338107 144.243134)
		(end 212.782473 142.6875)
		(width 0.148)
		(layer "In4.Cu")
		(net 55)
	)
	(segment
		(start 214.374198 143.289275)
		(end 214.833082 143.748158)
		(width 0.148)
		(layer "In4.Cu")
		(net 55)
	)
	(segment
		(start 211.17316 143.801839)
		(end 211.173161 143.801839)
		(width 0.148)
		(layer "In4.Cu")
		(net 55)
	)
	(segment
		(start 236.65 110.451)
		(end 237 110.801)
		(width 0.148)
		(layer "In4.Cu")
		(net 55)
	)
	(segment
		(start 224.879353 131.905825)
		(end 225.149264 132.175736)
		(width 0.148)
		(layer "In4.Cu")
		(net 55)
	)
	(segment
		(start 214.621686 142.582169)
		(end 214.374199 142.829657)
		(width 0.148)
		(layer "In4.Cu")
		(net 55)
	)
	(segment
		(start 212.287499 142.6875)
		(end 212.233821 142.741176)
		(width 0.148)
		(layer "In4.Cu")
		(net 55)
	)
	(segment
		(start 237 110.801)
		(end 237 116.9)
		(width 0.148)
		(layer "In4.Cu")
		(net 55)
	)
	(segment
		(start 213.294482 141.680517)
		(end 213.277446 141.697549)
		(width 0.148)
		(layer "In4.Cu")
		(net 55)
	)
	(segment
		(start 211.748814 144.907822)
		(end 211.748814 144.907823)
		(width 0.148)
		(layer "In4.Cu")
		(net 55)
	)
	(segment
		(start 214.621687 142.12255)
		(end 214.621687 142.122551)
		(width 0.148)
		(layer "In4.Cu")
		(net 55)
	)
	(segment
		(start 211.703491 143.801839)
		(end 212.526621 144.624969)
		(width 0.148)
		(layer "In4.Cu")
		(net 55)
	)
	(segment
		(start 213.056952 144.094638)
		(end 212.233821 143.271507)
		(width 0.148)
		(layer "In4.Cu")
		(net 55)
	)
	(segment
		(start 213.914581 142.370039)
		(end 214.162067 142.12255)
		(width 0.148)
		(layer "In4.Cu")
		(net 55)
	)
	(segment
		(start 237.2 107.152)
		(end 236.65 107.702)
		(width 0.148)
		(layer "In4.Cu")
		(net 55)
	)
	(segment
		(start 211.748814 144.907823)
		(end 211.173159 144.332168)
		(width 0.148)
		(layer "In4.Cu")
		(net 55)
	)
	(segment
		(start 214.833082 144.243134)
		(end 214.833082 144.243135)
		(width 0.148)
		(layer "In4.Cu")
		(net 55)
	)
	(segment
		(start 213.91458 142.370037)
		(end 213.914581 142.370039)
		(width 0.148)
		(layer "In4.Cu")
		(net 55)
	)
	(segment
		(start 226.307216 133.942784)
		(end 218.825 141.425)
		(width 0.148)
		(layer "In4.Cu")
		(net 55)
	)
	(segment
		(start 224.937132 133.377817)
		(end 224.937131 133.377816)
		(width 0.148)
		(layer "In4.Cu")
		(net 55)
	)
	(segment
		(start 225.149264 132.67071)
		(end 224.937131 132.882842)
		(width 0.148)
		(layer "In4.Cu")
		(net 55)
	)
	(segment
		(start 225.432105 133.377816)
		(end 225.644237 133.165683)
		(width 0.148)
		(layer "In4.Cu")
		(net 55)
	)
	(segment
		(start 206.4 147.5)
		(end 208.8 145.1)
		(width 0.148)
		(layer "In4.Cu")
		(net 55)
	)
	(segment
		(start 213.277447 142.192524)
		(end 213.454961 142.370038)
		(width 0.148)
		(layer "In4.Cu")
		(net 55)
	)
	(segment
		(start 226.139211 133.165683)
		(end 226.307216 133.333688)
		(width 0.148)
		(layer "In4.Cu")
		(net 55)
	)
	(segment
		(start 201.5 147.5)
		(end 206.4 147.5)
		(width 0.148)
		(layer "In4.Cu")
		(net 55)
	)
	(segment
		(start 214.374199 143.289277)
		(end 214.374198 143.289275)
		(width 0.148)
		(layer "In4.Cu")
		(net 55)
	)
	(segment
		(start 236.65 107.702)
		(end 236.65 110.451)
		(width 0.148)
		(layer "In4.Cu")
		(net 55)
	)
	(segment
		(start 236.5 123.75)
		(end 227.853485 132.396518)
		(width 0.148)
		(layer "In4.Cu")
		(net 55)
	)
	(segment
		(start 227.067105 132.396518)
		(end 225.727883 131.057296)
		(width 0.148)
		(layer "In4.Cu")
		(net 55)
	)
	(segment
		(start 225.432106 133.377815)
		(end 225.432105 133.377816)
		(width 0.148)
		(layer "In4.Cu")
		(net 55)
	)
	(segment
		(start 208.8 145.1)
		(end 209.875 145.1)
		(width 0.148)
		(layer "In4.Cu")
		(net 55)
	)
	(segment
		(start 211.173159 143.801838)
		(end 211.17316 143.801839)
		(width 0.148)
		(layer "In4.Cu")
		(net 55)
	)
	(segment
		(start 225.149263 132.670711)
		(end 225.149264 132.67071)
		(width 0.148)
		(layer "In4.Cu")
		(net 55)
	)
	(segment
		(start 213.056952 144.094637)
		(end 213.056952 144.094638)
		(width 0.148)
		(layer "In4.Cu")
		(net 55)
	)
	(segment
		(start 236.5 117.4)
		(end 236.5 123.75)
		(width 0.148)
		(layer "In4.Cu")
		(net 55)
	)
	(segment
		(start 213.056952 144.62497)
		(end 213.056952 144.624969)
		(width 0.148)
		(layer "In4.Cu")
		(net 55)
	)
	(segment
		(start 209.875 145.1)
		(end 210.1125 144.8625)
		(width 0.148)
		(layer "In4.Cu")
		(net 55)
	)
	(segment
		(start 214.621686 142.58217)
		(end 214.621686 142.582169)
		(width 0.148)
		(layer "In4.Cu")
		(net 55)
	)
	(segment
		(start 225.727883 131.057296)
		(end 225.727883 131.057297)
		(width 0.148)
		(layer "In4.Cu")
		(net 55)
	)
	(segment
		(start 218.825 141.425)
		(end 213.55 141.425)
		(width 0.148)
		(layer "In4.Cu")
		(net 55)
	)
	(segment
		(start 237 116.9)
		(end 236.5 117.4)
		(width 0.148)
		(layer "In4.Cu")
		(net 55)
	)
	(segment
		(start 226.139212 133.165684)
		(end 226.139211 133.165683)
		(width 0.148)
		(layer "In4.Cu")
		(net 55)
	)
	(arc
		(start 213.056952 144.624969)
		(mid 213.166787 144.359803)
		(end 213.056952 144.094637)
		(width 0.148)
		(layer "In4.Cu")
		(net 55)
	)
	(arc
		(start 211.173161 143.801839)
		(mid 211.438326 143.692004)
		(end 211.703491 143.801839)
		(width 0.148)
		(layer "In4.Cu")
		(net 55)
	)
	(arc
		(start 226.307216 133.333688)
		(mid 226.433364 133.638236)
		(end 226.307216 133.942784)
		(width 0.148)
		(layer "In4.Cu")
		(net 55)
	)
	(arc
		(start 211.748814 145.438154)
		(mid 211.858649 145.172988)
		(end 211.748814 144.907822)
		(width 0.148)
		(layer "In4.Cu")
		(net 55)
	)
	(arc
		(start 211.218484 145.438154)
		(mid 211.483649 145.547989)
		(end 211.748814 145.438154)
		(width 0.148)
		(layer "In4.Cu")
		(net 55)
	)
	(arc
		(start 212.526621 144.624969)
		(mid 212.791786 144.734805)
		(end 213.056952 144.62497)
		(width 0.148)
		(layer "In4.Cu")
		(net 55)
	)
	(arc
		(start 212.782473 142.6875)
		(mid 212.534986 142.584988)
		(end 212.287499 142.6875)
		(width 0.148)
		(layer "In4.Cu")
		(net 55)
	)
	(arc
		(start 213.454961 142.370038)
		(mid 213.684771 142.465228)
		(end 213.91458 142.370037)
		(width 0.148)
		(layer "In4.Cu")
		(net 55)
	)
	(arc
		(start 224.937131 133.377816)
		(mid 225.184619 133.480328)
		(end 225.432106 133.377815)
		(width 0.148)
		(layer "In4.Cu")
		(net 55)
	)
	(arc
		(start 225.727883 131.057297)
		(mid 225.303619 130.88156)
		(end 224.879353 131.057297)
		(width 0.148)
		(layer "In4.Cu")
		(net 55)
	)
	(arc
		(start 214.621687 142.122551)
		(mid 214.716877 142.352361)
		(end 214.621686 142.58217)
		(width 0.148)
		(layer "In4.Cu")
		(net 55)
	)
	(arc
		(start 225.149264 132.175736)
		(mid 225.251776 132.423224)
		(end 225.149263 132.670711)
		(width 0.148)
		(layer "In4.Cu")
		(net 55)
	)
	(arc
		(start 213.277446 141.697549)
		(mid 213.174934 141.945037)
		(end 213.277447 142.192524)
		(width 0.148)
		(layer "In4.Cu")
		(net 55)
	)
	(arc
		(start 214.833082 143.748158)
		(mid 214.935595 143.995646)
		(end 214.833082 144.243134)
		(width 0.148)
		(layer "In4.Cu")
		(net 55)
	)
	(arc
		(start 210.1125 144.8625)
		(mid 210.377665 144.752665)
		(end 210.64283 144.8625)
		(width 0.148)
		(layer "In4.Cu")
		(net 55)
	)
	(arc
		(start 224.879353 131.057297)
		(mid 224.703617 131.481561)
		(end 224.879353 131.905825)
		(width 0.148)
		(layer "In4.Cu")
		(net 55)
	)
	(arc
		(start 227.853485 132.396518)
		(mid 227.460295 132.559383)
		(end 227.067105 132.396518)
		(width 0.148)
		(layer "In4.Cu")
		(net 55)
	)
	(arc
		(start 212.233821 143.271507)
		(mid 212.123985 143.006342)
		(end 212.23382 142.741176)
		(width 0.148)
		(layer "In4.Cu")
		(net 55)
	)
	(arc
		(start 214.374199 142.829657)
		(mid 214.279009 143.059467)
		(end 214.374199 143.289277)
		(width 0.148)
		(layer "In4.Cu")
		(net 55)
	)
	(arc
		(start 211.173159 144.332168)
		(mid 211.063324 144.067003)
		(end 211.173159 143.801838)
		(width 0.148)
		(layer "In4.Cu")
		(net 55)
	)
	(arc
		(start 214.162067 142.12255)
		(mid 214.391877 142.02736)
		(end 214.621687 142.12255)
		(width 0.148)
		(layer "In4.Cu")
		(net 55)
	)
	(arc
		(start 225.644237 133.165683)
		(mid 225.891725 133.063171)
		(end 226.139212 133.165684)
		(width 0.148)
		(layer "In4.Cu")
		(net 55)
	)
	(arc
		(start 224.937131 132.882842)
		(mid 224.834619 133.13033)
		(end 224.937132 133.377817)
		(width 0.148)
		(layer "In4.Cu")
		(net 55)
	)
	(arc
		(start 214.833082 144.243135)
		(mid 214.585594 144.345647)
		(end 214.338107 144.243134)
		(width 0.148)
		(layer "In4.Cu")
		(net 55)
	)
	(segment
		(start 201.0005 146.9995)
		(end 201.5 146.5)
		(width 0.256)
		(layer "F.Cu")
		(net 56)
	)
	(segment
		(start 235.5 106)
		(end 235.5 107.152)
		(width 0.38)
		(layer "F.Cu")
		(net 56)
	)
	(via
		(at 201.5 146.5)
		(size 0.45)
		(drill 0.1)
		(layers "F.Cu" "B.Cu")
		(remove_unused_layers yes)
		(keep_end_layers yes)
		(zone_layer_connections)
		(net 56)
	)
	(via
		(at 235.5 107.152)
		(size 0.45)
		(drill 0.1)
		(layers "F.Cu" "B.Cu")
		(remove_unused_layers yes)
		(keep_end_layers yes)
		(zone_layer_connections)
		(net 56)
	)
	(segment
		(start 201.5 146.5)
		(end 205.25 146.5)
		(width 0.148)
		(layer "In4.Cu")
		(net 56)
	)
	(segment
		(start 226.85 127.85)
		(end 227.3 127.85)
		(width 0.148)
		(layer "In4.Cu")
		(net 56)
	)
	(segment
		(start 235.602 107.152)
		(end 235.5 107.152)
		(width 0.148)
		(layer "In4.Cu")
		(net 56)
	)
	(segment
		(start 221.425 133.275)
		(end 222.640881 133.275)
		(width 0.148)
		(layer "In4.Cu")
		(net 56)
	)
	(segment
		(start 222.725 128.225)
		(end 222.725 128.825)
		(width 0.148)
		(layer "In4.Cu")
		(net 56)
	)
	(segment
		(start 222.640881 129.775)
		(end 221.425 129.775)
		(width 0.148)
		(layer "In4.Cu")
		(net 56)
	)
	(segment
		(start 236 107.55)
		(end 235.602 107.152)
		(width 0.148)
		(layer "In4.Cu")
		(net 56)
	)
	(segment
		(start 221.075 129.425)
		(end 221.075 128.8)
		(width 0.148)
		(layer "In4.Cu")
		(net 56)
	)
	(segment
		(start 222.025 127.85)
		(end 222.35 127.85)
		(width 0.148)
		(layer "In4.Cu")
		(net 56)
	)
	(segment
		(start 222.640881 132.575)
		(end 221.425 132.575)
		(width 0.148)
		(layer "In4.Cu")
		(net 56)
	)
	(segment
		(start 221.425 130.475)
		(end 222.640881 130.475)
		(width 0.148)
		(layer "In4.Cu")
		(net 56)
	)
	(segment
		(start 223.475 128.825)
		(end 223.475 128.225)
		(width 0.148)
		(layer "In4.Cu")
		(net 56)
	)
	(segment
		(start 222.640881 131.175)
		(end 221.425 131.175)
		(width 0.148)
		(layer "In4.Cu")
		(net 56)
	)
	(segment
		(start 227.3 127.85)
		(end 234.275 120.875)
		(width 0.148)
		(layer "In4.Cu")
		(net 56)
	)
	(segment
		(start 224.225 128.225)
		(end 224.225 128.825)
		(width 0.148)
		(layer "In4.Cu")
		(net 56)
	)
	(segment
		(start 236 110.1)
		(end 236 107.55)
		(width 0.148)
		(layer "In4.Cu")
		(net 56)
	)
	(segment
		(start 235.55 110.55)
		(end 236 110.1)
		(width 0.148)
		(layer "In4.Cu")
		(net 56)
	)
	(segment
		(start 212.375 139.375)
		(end 216.925 139.375)
		(width 0.148)
		(layer "In4.Cu")
		(net 56)
	)
	(segment
		(start 224.975 128.825)
		(end 224.975 128.225)
		(width 0.148)
		(layer "In4.Cu")
		(net 56)
	)
	(segment
		(start 222.640866 133.975)
		(end 221.425 133.975)
		(width 0.148)
		(layer "In4.Cu")
		(net 56)
	)
	(segment
		(start 225.725 128.225)
		(end 225.725 128.825)
		(width 0.148)
		(layer "In4.Cu")
		(net 56)
	)
	(segment
		(start 221.425 134.675)
		(end 222.640866 134.675)
		(width 0.148)
		(layer "In4.Cu")
		(net 56)
	)
	(segment
		(start 221.075 128.8)
		(end 222.025 127.85)
		(width 0.148)
		(layer "In4.Cu")
		(net 56)
	)
	(segment
		(start 226.475 128.825)
		(end 226.475 128.225)
		(width 0.148)
		(layer "In4.Cu")
		(net 56)
	)
	(segment
		(start 221.425 131.875)
		(end 222.640881 131.875)
		(width 0.148)
		(layer "In4.Cu")
		(net 56)
	)
	(segment
		(start 234.275 117.15)
		(end 235.55 115.875)
		(width 0.148)
		(layer "In4.Cu")
		(net 56)
	)
	(segment
		(start 221.075 135.225)
		(end 221.075 135.025)
		(width 0.148)
		(layer "In4.Cu")
		(net 56)
	)
	(segment
		(start 216.925 139.375)
		(end 221.075 135.225)
		(width 0.148)
		(layer "In4.Cu")
		(net 56)
	)
	(segment
		(start 235.55 115.875)
		(end 235.55 110.55)
		(width 0.148)
		(layer "In4.Cu")
		(net 56)
	)
	(segment
		(start 205.25 146.5)
		(end 212.375 139.375)
		(width 0.148)
		(layer "In4.Cu")
		(net 56)
	)
	(segment
		(start 234.275 120.875)
		(end 234.275 117.15)
		(width 0.148)
		(layer "In4.Cu")
		(net 56)
	)
	(arc
		(start 221.425 129.775)
		(mid 221.177513 129.672487)
		(end 221.075 129.425)
		(width 0.148)
		(layer "In4.Cu")
		(net 56)
	)
	(arc
		(start 222.640881 133.275)
		(mid 222.888368 133.172487)
		(end 222.990881 132.925)
		(width 0.148)
		(layer "In4.Cu")
		(net 56)
	)
	(arc
		(start 224.975 128.225)
		(mid 225.084835 127.959835)
		(end 225.35 127.85)
		(width 0.148)
		(layer "In4.Cu")
		(net 56)
	)
	(arc
		(start 226.1 129.2)
		(mid 226.365165 129.090165)
		(end 226.475 128.825)
		(width 0.148)
		(layer "In4.Cu")
		(net 56)
	)
	(arc
		(start 221.075 135.025)
		(mid 221.177513 134.777513)
		(end 221.425 134.675)
		(width 0.148)
		(layer "In4.Cu")
		(net 56)
	)
	(arc
		(start 225.35 127.85)
		(mid 225.615165 127.959835)
		(end 225.725 128.225)
		(width 0.148)
		(layer "In4.Cu")
		(net 56)
	)
	(arc
		(start 221.075 133.625)
		(mid 221.177513 133.377513)
		(end 221.425 133.275)
		(width 0.148)
		(layer "In4.Cu")
		(net 56)
	)
	(arc
		(start 225.725 128.825)
		(mid 225.834835 129.090165)
		(end 226.1 129.2)
		(width 0.148)
		(layer "In4.Cu")
		(net 56)
	)
	(arc
		(start 222.990881 130.125)
		(mid 222.888368 129.877513)
		(end 222.640881 129.775)
		(width 0.148)
		(layer "In4.Cu")
		(net 56)
	)
	(arc
		(start 223.1 129.2)
		(mid 223.365165 129.090165)
		(end 223.475 128.825)
		(width 0.148)
		(layer "In4.Cu")
		(net 56)
	)
	(arc
		(start 222.640866 134.675)
		(mid 222.888353 134.572487)
		(end 222.990866 134.325)
		(width 0.148)
		(layer "In4.Cu")
		(net 56)
	)
	(arc
		(start 226.475 128.225)
		(mid 226.584835 127.959835)
		(end 226.85 127.85)
		(width 0.148)
		(layer "In4.Cu")
		(net 56)
	)
	(arc
		(start 222.990866 134.325)
		(mid 222.888353 134.077513)
		(end 222.640866 133.975)
		(width 0.148)
		(layer "In4.Cu")
		(net 56)
	)
	(arc
		(start 222.640881 130.475)
		(mid 222.888368 130.372487)
		(end 222.990881 130.125)
		(width 0.148)
		(layer "In4.Cu")
		(net 56)
	)
	(arc
		(start 222.35 127.85)
		(mid 222.615165 127.959835)
		(end 222.725 128.225)
		(width 0.148)
		(layer "In4.Cu")
		(net 56)
	)
	(arc
		(start 221.425 133.975)
		(mid 221.177513 133.872487)
		(end 221.075 133.625)
		(width 0.148)
		(layer "In4.Cu")
		(net 56)
	)
	(arc
		(start 221.075 130.825)
		(mid 221.177513 130.577513)
		(end 221.425 130.475)
		(width 0.148)
		(layer "In4.Cu")
		(net 56)
	)
	(arc
		(start 222.990881 132.925)
		(mid 222.888368 132.677513)
		(end 222.640881 132.575)
		(width 0.148)
		(layer "In4.Cu")
		(net 56)
	)
	(arc
		(start 221.425 131.175)
		(mid 221.177513 131.072487)
		(end 221.075 130.825)
		(width 0.148)
		(layer "In4.Cu")
		(net 56)
	)
	(arc
		(start 221.425 132.575)
		(mid 221.177513 132.472487)
		(end 221.075 132.225)
		(width 0.148)
		(layer "In4.Cu")
		(net 56)
	)
	(arc
		(start 222.640881 131.875)
		(mid 222.888368 131.772487)
		(end 222.990881 131.525)
		(width 0.148)
		(layer "In4.Cu")
		(net 56)
	)
	(arc
		(start 224.6 129.2)
		(mid 224.865165 129.090165)
		(end 224.975 128.825)
		(width 0.148)
		(layer "In4.Cu")
		(net 56)
	)
	(arc
		(start 222.725 128.825)
		(mid 222.834835 129.090165)
		(end 223.1 129.2)
		(width 0.148)
		(layer "In4.Cu")
		(net 56)
	)
	(arc
		(start 223.85 127.85)
		(mid 224.115165 127.959835)
		(end 224.225 128.225)
		(width 0.148)
		(layer "In4.Cu")
		(net 56)
	)
	(arc
		(start 223.475 128.225)
		(mid 223.584835 127.959835)
		(end 223.85 127.85)
		(width 0.148)
		(layer "In4.Cu")
		(net 56)
	)
	(arc
		(start 224.225 128.825)
		(mid 224.334835 129.090165)
		(end 224.6 129.2)
		(width 0.148)
		(layer "In4.Cu")
		(net 56)
	)
	(arc
		(start 221.075 132.225)
		(mid 221.177513 131.977513)
		(end 221.425 131.875)
		(width 0.148)
		(layer "In4.Cu")
		(net 56)
	)
	(arc
		(start 222.990881 131.525)
		(mid 222.888368 131.277513)
		(end 222.640881 131.175)
		(width 0.148)
		(layer "In4.Cu")
		(net 56)
	)
	(segment
		(start 200.0005 149.9995)
		(end 200.500001 149.5)
		(width 0.256)
		(layer "F.Cu")
		(net 57)
	)
	(segment
		(start 231.25 106)
		(end 231.25 107.152)
		(width 0.38)
		(layer "F.Cu")
		(net 57)
	)
	(via
		(at 200.500001 149.5)
		(size 0.45)
		(drill 0.1)
		(layers "F.Cu" "B.Cu")
		(remove_unused_layers yes)
		(keep_end_layers yes)
		(zone_layer_connections)
		(net 57)
	)
	(via
		(at 231.25 107.152)
		(size 0.45)
		(drill 0.1)
		(layers "F.Cu" "B.Cu")
		(remove_unused_layers yes)
		(keep_end_layers yes)
		(zone_layer_connections)
		(net 57)
	)
	(segment
		(start 218.163824 143.016945)
		(end 218.322918 143.176039)
		(width 0.148)
		(layer "In4.Cu")
		(net 57)
	)
	(segment
		(start 218.322917 143.77708)
		(end 218.322918 143.777079)
		(width 0.148)
		(layer "In4.Cu")
		(net 57)
	)
	(segment
		(start 218.923959 142.575)
		(end 218.764864 142.415905)
		(width 0.148)
		(layer "In4.Cu")
		(net 57)
	)
	(segment
		(start 216.924997 145.175)
		(end 213.95 145.175)
		(width 0.148)
		(layer "In4.Cu")
		(net 57)
	)
	(segment
		(start 200.899001 149.101)
		(end 200.500001 149.5)
		(width 0.148)
		(layer "In4.Cu")
		(net 57)
	)
	(segment
		(start 231.25 106.55)
		(end 232.3 105.5)
		(width 0.148)
		(layer "In4.Cu")
		(net 57)
	)
	(segment
		(start 215.79503 143.052315)
		(end 217.120836 144.378121)
		(width 0.148)
		(layer "In4.Cu")
		(net 57)
	)
	(segment
		(start 236.3 105.5)
		(end 237.599 106.799)
		(width 0.148)
		(layer "In4.Cu")
		(net 57)
	)
	(segment
		(start 218.163823 142.415906)
		(end 218.163824 142.415905)
		(width 0.148)
		(layer "In4.Cu")
		(net 57)
	)
	(segment
		(start 237.599 106.799)
		(end 237.599 124.501)
		(width 0.148)
		(layer "In4.Cu")
		(net 57)
	)
	(segment
		(start 201.799 149.101)
		(end 200.899001 149.101)
		(width 0.148)
		(layer "In4.Cu")
		(net 57)
	)
	(segment
		(start 215.795029 142.451276)
		(end 215.79503 142.451275)
		(width 0.148)
		(layer "In4.Cu")
		(net 57)
	)
	(segment
		(start 217.721877 143.777082)
		(end 216.39607 142.451275)
		(width 0.148)
		(layer "In4.Cu")
		(net 57)
	)
	(segment
		(start 231.25 107.152)
		(end 231.25 106.55)
		(width 0.148)
		(layer "In4.Cu")
		(net 57)
	)
	(segment
		(start 212.75 146.375)
		(end 208.575 146.375)
		(width 0.148)
		(layer "In4.Cu")
		(net 57)
	)
	(segment
		(start 217.120835 144.979162)
		(end 216.924997 145.175)
		(width 0.148)
		(layer "In4.Cu")
		(net 57)
	)
	(segment
		(start 218.923958 142.575)
		(end 218.923959 142.575)
		(width 0.148)
		(layer "In4.Cu")
		(net 57)
	)
	(segment
		(start 208.575 146.375)
		(end 207 147.95)
		(width 0.148)
		(layer "In4.Cu")
		(net 57)
	)
	(segment
		(start 202.95 147.95)
		(end 201.799 149.101)
		(width 0.148)
		(layer "In4.Cu")
		(net 57)
	)
	(segment
		(start 218.322918 143.777079)
		(end 218.322918 143.777082)
		(width 0.148)
		(layer "In4.Cu")
		(net 57)
	)
	(segment
		(start 207 147.95)
		(end 202.95 147.95)
		(width 0.148)
		(layer "In4.Cu")
		(net 57)
	)
	(segment
		(start 237.599 124.501)
		(end 219.525 142.575)
		(width 0.148)
		(layer "In4.Cu")
		(net 57)
	)
	(segment
		(start 232.3 105.5)
		(end 236.3 105.5)
		(width 0.148)
		(layer "In4.Cu")
		(net 57)
	)
	(segment
		(start 213.95 145.175)
		(end 212.75 146.375)
		(width 0.148)
		(layer "In4.Cu")
		(net 57)
	)
	(segment
		(start 217.721876 143.777082)
		(end 217.721877 143.777082)
		(width 0.148)
		(layer "In4.Cu")
		(net 57)
	)
	(arc
		(start 218.322918 143.777082)
		(mid 218.022397 143.901562)
		(end 217.721876 143.777082)
		(width 0.148)
		(layer "In4.Cu")
		(net 57)
	)
	(arc
		(start 217.120836 144.378121)
		(mid 217.245315 144.678642)
		(end 217.120835 144.979162)
		(width 0.148)
		(layer "In4.Cu")
		(net 57)
	)
	(arc
		(start 218.163824 142.415905)
		(mid 218.039345 142.716425)
		(end 218.163824 143.016945)
		(width 0.148)
		(layer "In4.Cu")
		(net 57)
	)
	(arc
		(start 218.764864 142.415905)
		(mid 218.464343 142.291426)
		(end 218.163823 142.415906)
		(width 0.148)
		(layer "In4.Cu")
		(net 57)
	)
	(arc
		(start 215.79503 142.451275)
		(mid 215.670551 142.751795)
		(end 215.79503 143.052315)
		(width 0.148)
		(layer "In4.Cu")
		(net 57)
	)
	(arc
		(start 219.525 142.575)
		(mid 219.224479 142.69948)
		(end 218.923958 142.575)
		(width 0.148)
		(layer "In4.Cu")
		(net 57)
	)
	(arc
		(start 218.322918 143.176039)
		(mid 218.447397 143.47656)
		(end 218.322917 143.77708)
		(width 0.148)
		(layer "In4.Cu")
		(net 57)
	)
	(arc
		(start 216.39607 142.451275)
		(mid 216.095549 142.326796)
		(end 215.795029 142.451276)
		(width 0.148)
		(layer "In4.Cu")
		(net 57)
	)
	(segment
		(start 229.55 106)
		(end 229.55 107.152)
		(width 0.38)
		(layer "F.Cu")
		(net 58)
	)
	(segment
		(start 199.0005 149.9995)
		(end 199.5 149.5)
		(width 0.256)
		(layer "F.Cu")
		(net 58)
	)
	(via
		(at 229.55 107.152)
		(size 0.45)
		(drill 0.1)
		(layers "F.Cu" "B.Cu")
		(remove_unused_layers yes)
		(keep_end_layers yes)
		(zone_layer_connections)
		(net 58)
	)
	(via
		(at 199.5 149.5)
		(size 0.45)
		(drill 0.1)
		(layers "F.Cu" "B.Cu")
		(remove_unused_layers yes)
		(keep_end_layers yes)
		(zone_layer_connections)
		(net 58)
	)
	(segment
		(start 203.4 148.4)
		(end 207.5 148.4)
		(width 0.148)
		(layer "In4.Cu")
		(net 58)
	)
	(segment
		(start 229.55 106.6875)
		(end 229.55 107.152)
		(width 0.148)
		(layer "In4.Cu")
		(net 58)
	)
	(segment
		(start 213.45 147.45)
		(end 214.65 146.25)
		(width 0.148)
		(layer "In4.Cu")
		(net 58)
	)
	(segment
		(start 236.55 104.3)
		(end 231.9375 104.3)
		(width 0.148)
		(layer "In4.Cu")
		(net 58)
	)
	(segment
		(start 238.25 108.6)
		(end 238.25 106)
		(width 0.148)
		(layer "In4.Cu")
		(net 58)
	)
	(segment
		(start 238.65 110.1)
		(end 238.65 109)
		(width 0.148)
		(layer "In4.Cu")
		(net 58)
	)
	(segment
		(start 238.35 110.4)
		(end 238.65 110.1)
		(width 0.148)
		(layer "In4.Cu")
		(net 58)
	)
	(segment
		(start 238.55 125.3)
		(end 238.55 112.45)
		(width 0.148)
		(layer "In4.Cu")
		(net 58)
	)
	(segment
		(start 238.35 112.25)
		(end 238.35 110.4)
		(width 0.148)
		(layer "In4.Cu")
		(net 58)
	)
	(segment
		(start 238.25 106)
		(end 236.55 104.3)
		(width 0.148)
		(layer "In4.Cu")
		(net 58)
	)
	(segment
		(start 208.45 147.45)
		(end 213.45 147.45)
		(width 0.148)
		(layer "In4.Cu")
		(net 58)
	)
	(segment
		(start 207.5 148.4)
		(end 208.45 147.45)
		(width 0.148)
		(layer "In4.Cu")
		(net 58)
	)
	(segment
		(start 238.55 112.45)
		(end 238.35 112.25)
		(width 0.148)
		(layer "In4.Cu")
		(net 58)
	)
	(segment
		(start 214.65 146.25)
		(end 217.6 146.25)
		(width 0.148)
		(layer "In4.Cu")
		(net 58)
	)
	(segment
		(start 200 150)
		(end 201.8 150)
		(width 0.148)
		(layer "In4.Cu")
		(net 58)
	)
	(segment
		(start 201.8 150)
		(end 203.4 148.4)
		(width 0.148)
		(layer "In4.Cu")
		(net 58)
	)
	(segment
		(start 217.6 146.25)
		(end 238.55 125.3)
		(width 0.148)
		(layer "In4.Cu")
		(net 58)
	)
	(segment
		(start 199.5 149.5)
		(end 200 150)
		(width 0.148)
		(layer "In4.Cu")
		(net 58)
	)
	(segment
		(start 231.9375 104.3)
		(end 229.55 106.6875)
		(width 0.148)
		(layer "In4.Cu")
		(net 58)
	)
	(segment
		(start 238.65 109)
		(end 238.25 108.6)
		(width 0.148)
		(layer "In4.Cu")
		(net 58)
	)
	(segment
		(start 227.85 106)
		(end 227.85 107.152)
		(width 0.38)
		(layer "F.Cu")
		(net 59)
	)
	(segment
		(start 199.0005 142.999499)
		(end 199.5 142.5)
		(width 0.256)
		(layer "F.Cu")
		(net 59)
	)
	(via
		(at 227.85 107.152)
		(size 0.45)
		(drill 0.1)
		(layers "F.Cu" "B.Cu")
		(remove_unused_layers yes)
		(keep_end_layers yes)
		(zone_layer_connections)
		(net 59)
	)
	(via
		(at 199.5 142.5)
		(size 0.45)
		(drill 0.1)
		(layers "F.Cu" "B.Cu")
		(remove_unused_layers yes)
		(keep_end_layers yes)
		(zone_layer_connections)
		(net 59)
	)
	(segment
		(start 202.985771 121.551457)
		(end 204.134314 122.7)
		(width 0.148)
		(layer "In2.Cu")
		(net 59)
	)
	(segment
		(start 207.45735 121.892649)
		(end 207.51 121.892649)
		(width 0.148)
		(layer "In2.Cu")
		(net 59)
	)
	(segment
		(start 207.133675 122.216325)
		(end 207.133675 122.216324)
		(width 0.148)
		(layer "In2.Cu")
		(net 59)
	)
	(segment
		(start 208.15735 122.54)
		(end 208.21 122.54)
		(width 0.148)
		(layer "In2.Cu")
		(net 59)
	)
	(segment
		(start 200.520101 122.479899)
		(end 200.157356 122.117154)
		(width 0.148)
		(layer "In2.Cu")
		(net 59)
	)
	(segment
		(start 228.25 115.1)
		(end 228.25 111.03)
		(width 0.148)
		(layer "In2.Cu")
		(net 59)
	)
	(segment
		(start 202.1 141.585499)
		(end 202.1 125.3)
		(width 0.148)
		(layer "In2.Cu")
		(net 59)
	)
	(segment
		(start 209.61 122.54)
		(end 220.81 122.54)
		(width 0.148)
		(layer "In2.Cu")
		(net 59)
	)
	(segment
		(start 201.7 141.985499)
		(end 202.1 141.585499)
		(width 0.148)
		(layer "In2.Cu")
		(net 59)
	)
	(segment
		(start 228.25 111.03)
		(end 228.64 110.64)
		(width 0.148)
		(layer "In2.Cu")
		(net 59)
	)
	(segment
		(start 209.55735 122.54)
		(end 209.61 122.54)
		(width 0.148)
		(layer "In2.Cu")
		(net 59)
	)
	(segment
		(start 206.757264 122.54)
		(end 206.81 122.54)
		(width 0.148)
		(layer "In2.Cu")
		(net 59)
	)
	(segment
		(start 206.057264 121.892735)
		(end 206.11 121.892735)
		(width 0.148)
		(layer "In2.Cu")
		(net 59)
	)
	(segment
		(start 201 142.3)
		(end 201 142.661999)
		(width 0.15)
		(layer "In2.Cu")
		(net 59)
	)
	(segment
		(start 204.86 122.54)
		(end 205.41 122.54)
		(width 0.148)
		(layer "In2.Cu")
		(net 59)
	)
	(segment
		(start 201.345602 123.775717)
		(end 201.368628 123.752692)
		(width 0.148)
		(layer "In2.Cu")
		(net 59)
	)
	(segment
		(start 206.433632 122.216367)
		(end 206.433632 122.216368)
		(width 0.148)
		(layer "In2.Cu")
		(net 59)
	)
	(segment
		(start 220.81 122.54)
		(end 228.25 115.1)
		(width 0.148)
		(layer "In2.Cu")
		(net 59)
	)
	(segment
		(start 201.368629 123.328427)
		(end 201.368628 123.328426)
		(width 0.148)
		(layer "In2.Cu")
		(net 59)
	)
	(segment
		(start 200.944364 123.328426)
		(end 200.92141 123.351381)
		(width 0.148)
		(layer "In2.Cu")
		(net 59)
	)
	(segment
		(start 200.157356 121.551469)
		(end 200.157356 121.55147)
		(width 0.148)
		(layer "In2.Cu")
		(net 59)
	)
	(segment
		(start 227.85 108.05)
		(end 227.85 107.152)
		(width 0.148)
		(layer "In2.Cu")
		(net 59)
	)
	(segment
		(start 209.233675 122.216324)
		(end 209.233675 122.216325)
		(width 0.148)
		(layer "In2.Cu")
		(net 59)
	)
	(segment
		(start 202.437257 124.397055)
		(end 202.217157 124.176955)
		(width 0.148)
		(layer "In2.Cu")
		(net 59)
	)
	(segment
		(start 207.833675 122.216324)
		(end 207.833675 122.216325)
		(width 0.148)
		(layer "In2.Cu")
		(net 59)
	)
	(segment
		(start 203.568627 123.83137)
		(end 203.568628 123.831369)
		(width 0.148)
		(layer "In2.Cu")
		(net 59)
	)
	(segment
		(start 200.157356 122.117154)
		(end 200.157356 122.117153)
		(width 0.148)
		(layer "In2.Cu")
		(net 59)
	)
	(segment
		(start 202.217157 124.176955)
		(end 202.217156 124.176955)
		(width 0.148)
		(layer "In2.Cu")
		(net 59)
	)
	(segment
		(start 202.420085 121.551457)
		(end 202.420086 121.551456)
		(width 0.148)
		(layer "In2.Cu")
		(net 59)
	)
	(segment
		(start 201.792892 124.176955)
		(end 201.769867 124.199981)
		(width 0.148)
		(layer "In2.Cu")
		(net 59)
	)
	(segment
		(start 200.6605 143.001499)
		(end 200.0015 143.001499)
		(width 0.15)
		(layer "In2.Cu")
		(net 59)
	)
	(segment
		(start 202.1 125.3)
		(end 202.437256 124.96274)
		(width 0.148)
		(layer "In2.Cu")
		(net 59)
	)
	(segment
		(start 204.7 122.7)
		(end 204.86 122.54)
		(width 0.148)
		(layer "In2.Cu")
		(net 59)
	)
	(segment
		(start 228.64 110.64)
		(end 228.64 108.84)
		(width 0.148)
		(layer "In2.Cu")
		(net 59)
	)
	(segment
		(start 205.733632 122.216368)
		(end 205.733632 122.216367)
		(width 0.148)
		(layer "In2.Cu")
		(net 59)
	)
	(segment
		(start 208.85735 121.892649)
		(end 208.91 121.892649)
		(width 0.148)
		(layer "In2.Cu")
		(net 59)
	)
	(segment
		(start 201 142.661999)
		(end 200.6605 143.001499)
		(width 0.15)
		(layer "In2.Cu")
		(net 59)
	)
	(segment
		(start 201.345602 124.199982)
		(end 201.345602 124.199981)
		(width 0.148)
		(layer "In2.Cu")
		(net 59)
	)
	(segment
		(start 203.568627 123.265684)
		(end 202.420085 122.117142)
		(width 0.148)
		(layer "In2.Cu")
		(net 59)
	)
	(segment
		(start 201.314501 141.985499)
		(end 201 142.3)
		(width 0.15)
		(layer "In2.Cu")
		(net 59)
	)
	(segment
		(start 201.7 141.985499)
		(end 201.314501 141.985499)
		(width 0.15)
		(layer "In2.Cu")
		(net 59)
	)
	(segment
		(start 208.533675 122.216325)
		(end 208.533675 122.216324)
		(width 0.148)
		(layer "In2.Cu")
		(net 59)
	)
	(segment
		(start 202.420085 122.117142)
		(end 202.420085 122.117141)
		(width 0.148)
		(layer "In2.Cu")
		(net 59)
	)
	(segment
		(start 203.568629 123.831371)
		(end 203.568627 123.83137)
		(width 0.148)
		(layer "In2.Cu")
		(net 59)
	)
	(segment
		(start 200.0015 143.001499)
		(end 199.5 142.499999)
		(width 0.15)
		(layer "In2.Cu")
		(net 59)
	)
	(segment
		(start 200.723041 121.551469)
		(end 203.002943 123.831371)
		(width 0.148)
		(layer "In2.Cu")
		(net 59)
	)
	(segment
		(start 228.64 108.84)
		(end 227.85 108.05)
		(width 0.148)
		(layer "In2.Cu")
		(net 59)
	)
	(segment
		(start 200.497145 122.927118)
		(end 200.5201 122.904164)
		(width 0.148)
		(layer "In2.Cu")
		(net 59)
	)
	(arc
		(start 202.420085 122.117141)
		(mid 202.302928 121.834299)
		(end 202.420085 121.551457)
		(width 0.148)
		(layer "In2.Cu")
		(net 59)
	)
	(arc
		(start 208.91 121.892649)
		(mid 209.138873 121.987451)
		(end 209.233675 122.216324)
		(width 0.148)
		(layer "In2.Cu")
		(net 59)
	)
	(arc
		(start 200.92141 123.351381)
		(mid 200.709278 123.43925)
		(end 200.497145 123.351382)
		(width 0.148)
		(layer "In2.Cu")
		(net 59)
	)
	(arc
		(start 201.769867 124.199981)
		(mid 201.557735 124.28785)
		(end 201.345602 124.199982)
		(width 0.148)
		(layer "In2.Cu")
		(net 59)
	)
	(arc
		(start 209.233675 122.216325)
		(mid 209.328477 122.445198)
		(end 209.55735 122.54)
		(width 0.148)
		(layer "In2.Cu")
		(net 59)
	)
	(arc
		(start 200.497145 123.351382)
		(mid 200.409277 123.13925)
		(end 200.497145 122.927118)
		(width 0.148)
		(layer "In2.Cu")
		(net 59)
	)
	(arc
		(start 206.433632 122.216368)
		(mid 206.528422 122.44521)
		(end 206.757264 122.54)
		(width 0.148)
		(layer "In2.Cu")
		(net 59)
	)
	(arc
		(start 205.733632 122.216367)
		(mid 205.828422 121.987525)
		(end 206.057264 121.892735)
		(width 0.148)
		(layer "In2.Cu")
		(net 59)
	)
	(arc
		(start 207.133675 122.216324)
		(mid 207.228477 121.987451)
		(end 207.45735 121.892649)
		(width 0.148)
		(layer "In2.Cu")
		(net 59)
	)
	(arc
		(start 202.420086 121.551456)
		(mid 202.702929 121.434299)
		(end 202.985771 121.551457)
		(width 0.148)
		(layer "In2.Cu")
		(net 59)
	)
	(arc
		(start 208.533675 122.216324)
		(mid 208.628477 121.987451)
		(end 208.85735 121.892649)
		(width 0.148)
		(layer "In2.Cu")
		(net 59)
	)
	(arc
		(start 201.345602 124.199981)
		(mid 201.257734 123.987849)
		(end 201.345602 123.775717)
		(width 0.148)
		(layer "In2.Cu")
		(net 59)
	)
	(arc
		(start 200.157356 122.117153)
		(mid 200.040199 121.834311)
		(end 200.157356 121.551469)
		(width 0.148)
		(layer "In2.Cu")
		(net 59)
	)
	(arc
		(start 200.5201 122.904164)
		(mid 200.607969 122.692032)
		(end 200.520101 122.479899)
		(width 0.148)
		(layer "In2.Cu")
		(net 59)
	)
	(arc
		(start 203.568628 123.831369)
		(mid 203.685785 123.548526)
		(end 203.568627 123.265684)
		(width 0.148)
		(layer "In2.Cu")
		(net 59)
	)
	(arc
		(start 208.21 122.54)
		(mid 208.438873 122.445198)
		(end 208.533675 122.216325)
		(width 0.148)
		(layer "In2.Cu")
		(net 59)
	)
	(arc
		(start 206.81 122.54)
		(mid 207.038873 122.445198)
		(end 207.133675 122.216325)
		(width 0.148)
		(layer "In2.Cu")
		(net 59)
	)
	(arc
		(start 207.833675 122.216325)
		(mid 207.928477 122.445198)
		(end 208.15735 122.54)
		(width 0.148)
		(layer "In2.Cu")
		(net 59)
	)
	(arc
		(start 205.41 122.54)
		(mid 205.638842 122.44521)
		(end 205.733632 122.216368)
		(width 0.148)
		(layer "In2.Cu")
		(net 59)
	)
	(arc
		(start 207.51 121.892649)
		(mid 207.738873 121.987451)
		(end 207.833675 122.216324)
		(width 0.148)
		(layer "In2.Cu")
		(net 59)
	)
	(arc
		(start 203.002943 123.831371)
		(mid 203.285786 123.948528)
		(end 203.568629 123.831371)
		(width 0.148)
		(layer "In2.Cu")
		(net 59)
	)
	(arc
		(start 204.134314 122.7)
		(mid 204.417157 122.817157)
		(end 204.7 122.7)
		(width 0.148)
		(layer "In2.Cu")
		(net 59)
	)
	(arc
		(start 200.157356 121.55147)
		(mid 200.440198 121.434312)
		(end 200.723041 121.551469)
		(width 0.148)
		(layer "In2.Cu")
		(net 59)
	)
	(arc
		(start 202.217156 124.176955)
		(mid 202.005024 124.089087)
		(end 201.792892 124.176955)
		(width 0.148)
		(layer "In2.Cu")
		(net 59)
	)
	(arc
		(start 201.368628 123.752692)
		(mid 201.456497 123.54056)
		(end 201.368629 123.328427)
		(width 0.148)
		(layer "In2.Cu")
		(net 59)
	)
	(arc
		(start 201.368628 123.328426)
		(mid 201.156496 123.240558)
		(end 200.944364 123.328426)
		(width 0.148)
		(layer "In2.Cu")
		(net 59)
	)
	(arc
		(start 206.11 121.892735)
		(mid 206.338842 121.987525)
		(end 206.433632 122.216367)
		(width 0.148)
		(layer "In2.Cu")
		(net 59)
	)
	(arc
		(start 202.437256 124.96274)
		(mid 202.554414 124.679898)
		(end 202.437257 124.397055)
		(width 0.148)
		(layer "In2.Cu")
		(net 59)
	)
	(segment
		(start 226.15 106)
		(end 226.15 107.152)
		(width 0.38)
		(layer "F.Cu")
		(net 60)
	)
	(segment
		(start 200.0005 142.9995)
		(end 200.5 142.5)
		(width 0.256)
		(layer "F.Cu")
		(net 60)
	)
	(via
		(at 226.15 107.152)
		(size 0.45)
		(drill 0.1)
		(layers "F.Cu" "B.Cu")
		(remove_unused_layers yes)
		(keep_end_layers yes)
		(zone_layer_connections)
		(net 60)
	)
	(via
		(at 200.5 142.5)
		(size 0.45)
		(drill 0.1)
		(layers "F.Cu" "B.Cu")
		(remove_unused_layers yes)
		(keep_end_layers yes)
		(zone_layer_connections)
		(net 60)
	)
	(segment
		(start 217.979825 121.239826)
		(end 217.979825 121.239825)
		(width 0.148)
		(layer "In2.Cu")
		(net 60)
	)
	(segment
		(start 226.7 108.75)
		(end 225.000145 108.75)
		(width 0.148)
		(layer "In2.Cu")
		(net 60)
	)
	(segment
		(start 213.11965 121.629651)
		(end 213.39 121.629651)
		(width 0.148)
		(layer "In2.Cu")
		(net 60)
	)
	(segment
		(start 227.65 111.45)
		(end 227.1 110.9)
		(width 0.148)
		(layer "In2.Cu")
		(net 60)
	)
	(segment
		(start 217.31965 121.629651)
		(end 217.59 121.629651)
		(width 0.148)
		(layer "In2.Cu")
		(net 60)
	)
	(segment
		(start 219.41965 121.629651)
		(end 219.69 121.629651)
		(width 0.148)
		(layer "In2.Cu")
		(net 60)
	)
	(segment
		(start 220.46965 120.85)
		(end 220.74 120.85)
		(width 0.148)
		(layer "In2.Cu")
		(net 60)
	)
	(segment
		(start 225.000145 107.95)
		(end 226.7 107.95)
		(width 0.148)
		(layer "In2.Cu")
		(net 60)
	)
	(segment
		(start 198.849999 123.025735)
		(end 198.85 123.025735)
		(width 0.148)
		(layer "In2.Cu")
		(net 60)
	)
	(segment
		(start 227.65 114.2)
		(end 227.65 111.45)
		(width 0.148)
		(layer "In2.Cu")
		(net 60)
	)
	(segment
		(start 198.15 120.85)
		(end 210.24 120.85)
		(width 0.148)
		(layer "In2.Cu")
		(net 60)
	)
	(segment
		(start 215.21965 121.629651)
		(end 215.49 121.629651)
		(width 0.148)
		(layer "In2.Cu")
		(net 60)
	)
	(segment
		(start 201 141.5)
		(end 201 125.6)
		(width 0.148)
		(layer "In2.Cu")
		(net 60)
	)
	(segment
		(start 214.829825 121.239825)
		(end 214.829825 121.239826)
		(width 0.148)
		(layer "In2.Cu")
		(net 60)
	)
	(segment
		(start 216.26965 120.85)
		(end 216.54 120.85)
		(width 0.148)
		(layer "In2.Cu")
		(net 60)
	)
	(segment
		(start 213.779825 121.239826)
		(end 213.779825 121.239825)
		(width 0.148)
		(layer "In2.Cu")
		(net 60)
	)
	(segment
		(start 198.00147 122.60147)
		(end 198.001471 122.601471)
		(width 0.148)
		(layer "In2.Cu")
		(net 60)
	)
	(segment
		(start 227.1 107.55)
		(end 227.1 107.45)
		(width 0.148)
		(layer "In2.Cu")
		(net 60)
	)
	(segment
		(start 220.079825 121.239826)
		(end 220.079825 121.239825)
		(width 0.148)
		(layer "In2.Cu")
		(net 60)
	)
	(segment
		(start 198.448754 122.57845)
		(end 198.448754 122.578451)
		(width 0.148)
		(layer "In2.Cu")
		(net 60)
	)
	(segment
		(start 198.001471 122.601471)
		(end 197.65 122.25)
		(width 0.148)
		(layer "In2.Cu")
		(net 60)
	)
	(segment
		(start 201 125.6)
		(end 198.85 123.45)
		(width 0.148)
		(layer "In2.Cu")
		(net 60)
	)
	(segment
		(start 221 120.85)
		(end 227.65 114.2)
		(width 0.148)
		(layer "In2.Cu")
		(net 60)
	)
	(segment
		(start 220.74 120.85)
		(end 221 120.85)
		(width 0.148)
		(layer "In2.Cu")
		(net 60)
	)
	(segment
		(start 214.16965 120.85)
		(end 214.44 120.85)
		(width 0.148)
		(layer "In2.Cu")
		(net 60)
	)
	(segment
		(start 216.929825 121.239825)
		(end 216.929825 121.239826)
		(width 0.148)
		(layer "In2.Cu")
		(net 60)
	)
	(segment
		(start 197.65 122.25)
		(end 197.65 121.35)
		(width 0.148)
		(layer "In2.Cu")
		(net 60)
	)
	(segment
		(start 200.5 142.5)
		(end 200.5 142.2)
		(width 0.15)
		(layer "In2.Cu")
		(net 60)
	)
	(segment
		(start 211.019558 121.629558)
		(end 211.29 121.629558)
		(width 0.148)
		(layer "In2.Cu")
		(net 60)
	)
	(segment
		(start 201 141.7)
		(end 201 141.5)
		(width 0.15)
		(layer "In2.Cu")
		(net 60)
	)
	(segment
		(start 219.029825 121.239825)
		(end 219.029825 121.239826)
		(width 0.148)
		(layer "In2.Cu")
		(net 60)
	)
	(segment
		(start 197.65 121.35)
		(end 198.15 120.85)
		(width 0.148)
		(layer "In2.Cu")
		(net 60)
	)
	(segment
		(start 227.1 107.45)
		(end 226.802 107.152)
		(width 0.148)
		(layer "In2.Cu")
		(net 60)
	)
	(segment
		(start 198.448754 122.578451)
		(end 198.425734 122.60147)
		(width 0.148)
		(layer "In2.Cu")
		(net 60)
	)
	(segment
		(start 227.1 110.9)
		(end 227.1 109.15)
		(width 0.148)
		(layer "In2.Cu")
		(net 60)
	)
	(segment
		(start 198.85 123.025735)
		(end 198.873019 123.002715)
		(width 0.148)
		(layer "In2.Cu")
		(net 60)
	)
	(segment
		(start 212.069558 120.85)
		(end 212.34 120.85)
		(width 0.148)
		(layer "In2.Cu")
		(net 60)
	)
	(segment
		(start 226.802 107.152)
		(end 226.15 107.152)
		(width 0.148)
		(layer "In2.Cu")
		(net 60)
	)
	(segment
		(start 215.879825 121.239826)
		(end 215.879825 121.239825)
		(width 0.148)
		(layer "In2.Cu")
		(net 60)
	)
	(segment
		(start 212.729825 121.239825)
		(end 212.729825 121.239826)
		(width 0.148)
		(layer "In2.Cu")
		(net 60)
	)
	(segment
		(start 218.36965 120.85)
		(end 218.64 120.85)
		(width 0.148)
		(layer "In2.Cu")
		(net 60)
	)
	(segment
		(start 200.5 142.2)
		(end 201 141.7)
		(width 0.15)
		(layer "In2.Cu")
		(net 60)
	)
	(arc
		(start 218.64 120.85)
		(mid 218.915648 120.964177)
		(end 219.029825 121.239825)
		(width 0.148)
		(layer "In2.Cu")
		(net 60)
	)
	(arc
		(start 198.873019 122.578451)
		(mid 198.660887 122.490582)
		(end 198.448754 122.57845)
		(width 0.148)
		(layer "In2.Cu")
		(net 60)
	)
	(arc
		(start 214.44 120.85)
		(mid 214.715648 120.964177)
		(end 214.829825 121.239825)
		(width 0.148)
		(layer "In2.Cu")
		(net 60)
	)
	(arc
		(start 198.873019 123.002715)
		(mid 198.960887 122.790583)
		(end 198.873019 122.578451)
		(width 0.148)
		(layer "In2.Cu")
		(net 60)
	)
	(arc
		(start 224.600145 108.35)
		(mid 224.717302 108.067157)
		(end 225.000145 107.95)
		(width 0.148)
		(layer "In2.Cu")
		(net 60)
	)
	(arc
		(start 226.7 107.95)
		(mid 226.982843 107.832843)
		(end 227.1 107.55)
		(width 0.148)
		(layer "In2.Cu")
		(net 60)
	)
	(arc
		(start 212.34 120.85)
		(mid 212.615648 120.964177)
		(end 212.729825 121.239825)
		(width 0.148)
		(layer "In2.Cu")
		(net 60)
	)
	(arc
		(start 216.929825 121.239826)
		(mid 217.044002 121.515474)
		(end 217.31965 121.629651)
		(width 0.148)
		(layer "In2.Cu")
		(net 60)
	)
	(arc
		(start 217.979825 121.239825)
		(mid 218.094002 120.964177)
		(end 218.36965 120.85)
		(width 0.148)
		(layer "In2.Cu")
		(net 60)
	)
	(arc
		(start 211.29 121.629558)
		(mid 211.565615 121.515394)
		(end 211.679779 121.239779)
		(width 0.148)
		(layer "In2.Cu")
		(net 60)
	)
	(arc
		(start 213.779825 121.239825)
		(mid 213.894002 120.964177)
		(end 214.16965 120.85)
		(width 0.148)
		(layer "In2.Cu")
		(net 60)
	)
	(arc
		(start 198.85 123.45)
		(mid 198.762131 123.237868)
		(end 198.849999 123.025735)
		(width 0.148)
		(layer "In2.Cu")
		(net 60)
	)
	(arc
		(start 216.54 120.85)
		(mid 216.815648 120.964177)
		(end 216.929825 121.239825)
		(width 0.148)
		(layer "In2.Cu")
		(net 60)
	)
	(arc
		(start 211.679779 121.239779)
		(mid 211.793943 120.964164)
		(end 212.069558 120.85)
		(width 0.148)
		(layer "In2.Cu")
		(net 60)
	)
	(arc
		(start 219.69 121.629651)
		(mid 219.965648 121.515474)
		(end 220.079825 121.239826)
		(width 0.148)
		(layer "In2.Cu")
		(net 60)
	)
	(arc
		(start 215.49 121.629651)
		(mid 215.765648 121.515474)
		(end 215.879825 121.239826)
		(width 0.148)
		(layer "In2.Cu")
		(net 60)
	)
	(arc
		(start 212.729825 121.239826)
		(mid 212.844002 121.515474)
		(end 213.11965 121.629651)
		(width 0.148)
		(layer "In2.Cu")
		(net 60)
	)
	(arc
		(start 210.24 120.85)
		(mid 210.515615 120.964164)
		(end 210.629779 121.239779)
		(width 0.148)
		(layer "In2.Cu")
		(net 60)
	)
	(arc
		(start 210.629779 121.239779)
		(mid 210.743943 121.515394)
		(end 211.019558 121.629558)
		(width 0.148)
		(layer "In2.Cu")
		(net 60)
	)
	(arc
		(start 213.39 121.629651)
		(mid 213.665648 121.515474)
		(end 213.779825 121.239826)
		(width 0.148)
		(layer "In2.Cu")
		(net 60)
	)
	(arc
		(start 198.425734 122.60147)
		(mid 198.213602 122.689338)
		(end 198.00147 122.60147)
		(width 0.148)
		(layer "In2.Cu")
		(net 60)
	)
	(arc
		(start 227.1 109.15)
		(mid 226.982843 108.867157)
		(end 226.7 108.75)
		(width 0.148)
		(layer "In2.Cu")
		(net 60)
	)
	(arc
		(start 225.000145 108.75)
		(mid 224.717302 108.632843)
		(end 224.600145 108.35)
		(width 0.148)
		(layer "In2.Cu")
		(net 60)
	)
	(arc
		(start 214.829825 121.239826)
		(mid 214.944002 121.515474)
		(end 215.21965 121.629651)
		(width 0.148)
		(layer "In2.Cu")
		(net 60)
	)
	(arc
		(start 219.029825 121.239826)
		(mid 219.144002 121.515474)
		(end 219.41965 121.629651)
		(width 0.148)
		(layer "In2.Cu")
		(net 60)
	)
	(arc
		(start 217.59 121.629651)
		(mid 217.865648 121.515474)
		(end 217.979825 121.239826)
		(width 0.148)
		(layer "In2.Cu")
		(net 60)
	)
	(arc
		(start 215.879825 121.239825)
		(mid 215.994002 120.964177)
		(end 216.26965 120.85)
		(width 0.148)
		(layer "In2.Cu")
		(net 60)
	)
	(arc
		(start 220.079825 121.239825)
		(mid 220.194002 120.964177)
		(end 220.46965 120.85)
		(width 0.148)
		(layer "In2.Cu")
		(net 60)
	)
	(segment
		(start 221.9 106)
		(end 221.9 107.152)
		(width 0.38)
		(layer "F.Cu")
		(net 61)
	)
	(segment
		(start 199.0005 144.9995)
		(end 199.5 144.5)
		(width 0.256)
		(layer "F.Cu")
		(net 61)
	)
	(via
		(at 221.9 107.152)
		(size 0.45)
		(drill 0.1)
		(layers "F.Cu" "B.Cu")
		(remove_unused_layers yes)
		(keep_end_layers yes)
		(zone_layer_connections)
		(net 61)
	)
	(via
		(at 199.5 144.5)
		(size 0.45)
		(drill 0.1)
		(layers "F.Cu" "B.Cu")
		(remove_unused_layers yes)
		(keep_end_layers yes)
		(zone_layer_connections)
		(net 61)
	)
	(segment
		(start 196.5 116.7)
		(end 193.9 119.3)
		(width 0.148)
		(layer "In2.Cu")
		(net 61)
	)
	(segment
		(start 223.091358 109.031739)
		(end 223.57011 108.552984)
		(width 0.148)
		(layer "In2.Cu")
		(net 61)
	)
	(segment
		(start 224.525 110.925)
		(end 224.525 113.325)
		(width 0.148)
		(layer "In2.Cu")
		(net 61)
	)
	(segment
		(start 223.110532 108.093324)
		(end 222.631738 108.572119)
		(width 0.148)
		(layer "In2.Cu")
		(net 61)
	)
	(segment
		(start 224.525 113.325)
		(end 221.15 116.7)
		(width 0.148)
		(layer "In2.Cu")
		(net 61)
	)
	(segment
		(start 222.17212 108.112501)
		(end 222.650913 107.633705)
		(width 0.148)
		(layer "In2.Cu")
		(net 61)
	)
	(segment
		(start 221.6 108)
		(end 221.7125 108.1125)
		(width 0.148)
		(layer "In2.Cu")
		(net 61)
	)
	(segment
		(start 222.172119 108.112499)
		(end 222.17212 108.112501)
		(width 0.148)
		(layer "In2.Cu")
		(net 61)
	)
	(segment
		(start 224.029729 109.012604)
		(end 224.029729 109.012603)
		(width 0.148)
		(layer "In2.Cu")
		(net 61)
	)
	(segment
		(start 222.631737 109.031737)
		(end 222.631738 109.031738)
		(width 0.148)
		(layer "In2.Cu")
		(net 61)
	)
	(segment
		(start 223.550975 109.950975)
		(end 224.525 110.925)
		(width 0.148)
		(layer "In2.Cu")
		(net 61)
	)
	(segment
		(start 199.299999 144.499999)
		(end 199.5 144.499999)
		(width 0.148)
		(layer "In2.Cu")
		(net 61)
	)
	(segment
		(start 198.0505 128)
		(end 198.0505 143.8505)
		(width 0.148)
		(layer "In2.Cu")
		(net 61)
	)
	(segment
		(start 224.029729 108.552985)
		(end 224.02973 108.552985)
		(width 0.148)
		(layer "In2.Cu")
		(net 61)
	)
	(segment
		(start 221.9005 107.151499)
		(end 221.6 107.451999)
		(width 0.148)
		(layer "In2.Cu")
		(net 61)
	)
	(segment
		(start 221.6 107.451999)
		(end 221.6 108)
		(width 0.148)
		(layer "In2.Cu")
		(net 61)
	)
	(segment
		(start 198.8 144)
		(end 199.299999 144.499999)
		(width 0.148)
		(layer "In2.Cu")
		(net 61)
	)
	(segment
		(start 223.110532 108.093325)
		(end 223.110532 108.093324)
		(width 0.148)
		(layer "In2.Cu")
		(net 61)
	)
	(segment
		(start 222.631739 109.031738)
		(end 222.631737 109.031737)
		(width 0.148)
		(layer "In2.Cu")
		(net 61)
	)
	(segment
		(start 223.110532 107.633706)
		(end 223.110533 107.633706)
		(width 0.148)
		(layer "In2.Cu")
		(net 61)
	)
	(segment
		(start 221.15 116.7)
		(end 196.5 116.7)
		(width 0.148)
		(layer "In2.Cu")
		(net 61)
	)
	(segment
		(start 198.2 144)
		(end 198.8 144)
		(width 0.148)
		(layer "In2.Cu")
		(net 61)
	)
	(segment
		(start 223.091357 109.031737)
		(end 223.091358 109.031739)
		(width 0.148)
		(layer "In2.Cu")
		(net 61)
	)
	(segment
		(start 224.029729 109.012603)
		(end 223.550976 109.491357)
		(width 0.148)
		(layer "In2.Cu")
		(net 61)
	)
	(segment
		(start 193.9 119.3)
		(end 193.9 123.8495)
		(width 0.148)
		(layer "In2.Cu")
		(net 61)
	)
	(segment
		(start 193.9 123.8495)
		(end 198.0505 128)
		(width 0.148)
		(layer "In2.Cu")
		(net 61)
	)
	(segment
		(start 198.0505 143.8505)
		(end 198.2 144)
		(width 0.148)
		(layer "In2.Cu")
		(net 61)
	)
	(segment
		(start 223.550977 109.950976)
		(end 223.550975 109.950975)
		(width 0.148)
		(layer "In2.Cu")
		(net 61)
	)
	(arc
		(start 222.650913 107.633705)
		(mid 222.880723 107.538515)
		(end 223.110532 107.633706)
		(width 0.148)
		(layer "In2.Cu")
		(net 61)
	)
	(arc
		(start 223.550976 109.491357)
		(mid 223.455786 109.721167)
		(end 223.550977 109.950976)
		(width 0.148)
		(layer "In2.Cu")
		(net 61)
	)
	(arc
		(start 224.02973 108.552985)
		(mid 224.12492 108.782795)
		(end 224.029729 109.012604)
		(width 0.148)
		(layer "In2.Cu")
		(net 61)
	)
	(arc
		(start 222.631738 108.572119)
		(mid 222.536548 108.801929)
		(end 222.631739 109.031738)
		(width 0.148)
		(layer "In2.Cu")
		(net 61)
	)
	(arc
		(start 223.57011 108.552984)
		(mid 223.79992 108.457794)
		(end 224.029729 108.552985)
		(width 0.148)
		(layer "In2.Cu")
		(net 61)
	)
	(arc
		(start 222.631738 109.031738)
		(mid 222.861548 109.126928)
		(end 223.091357 109.031737)
		(width 0.148)
		(layer "In2.Cu")
		(net 61)
	)
	(arc
		(start 221.7125 108.1125)
		(mid 221.94231 108.20769)
		(end 222.172119 108.112499)
		(width 0.148)
		(layer "In2.Cu")
		(net 61)
	)
	(arc
		(start 223.110533 107.633706)
		(mid 223.205723 107.863516)
		(end 223.110532 108.093325)
		(width 0.148)
		(layer "In2.Cu")
		(net 61)
	)
	(segment
		(start 220.2 106)
		(end 220.2 107.152)
		(width 0.38)
		(layer "F.Cu")
		(net 62)
	)
	(segment
		(start 200.0005 144.9995)
		(end 200.5 144.500001)
		(width 0.256)
		(layer "F.Cu")
		(net 62)
	)
	(via
		(at 200.5 144.500001)
		(size 0.45)
		(drill 0.1)
		(layers "F.Cu" "B.Cu")
		(remove_unused_layers yes)
		(keep_end_layers yes)
		(zone_layer_connections)
		(net 62)
	)
	(via
		(at 220.2 107.152)
		(size 0.45)
		(drill 0.1)
		(layers "F.Cu" "B.Cu")
		(remove_unused_layers yes)
		(keep_end_layers yes)
		(zone_layer_connections)
		(net 62)
	)
	(segment
		(start 201.0005 143.999499)
		(end 200.5 144.499999)
		(width 0.15)
		(layer "In2.Cu")
		(net 62)
	)
	(segment
		(start 227.45 104.3)
		(end 231.75 108.6)
		(width 0.148)
		(layer "In2.Cu")
		(net 62)
	)
	(segment
		(start 231.025 116.025)
		(end 222.1 124.95)
		(width 0.148)
		(layer "In2.Cu")
		(net 62)
	)
	(segment
		(start 231.025 110.5)
		(end 231.025 116.025)
		(width 0.148)
		(layer "In2.Cu")
		(net 62)
	)
	(segment
		(start 220.2005 106.5195)
		(end 222.42 104.3)
		(width 0.148)
		(layer "In2.Cu")
		(net 62)
	)
	(segment
		(start 220.2005 107.151499)
		(end 220.2005 106.619499)
		(width 0.15)
		(layer "In2.Cu")
		(net 62)
	)
	(segment
		(start 204 128.9)
		(end 204 142.4)
		(width 0.148)
		(layer "In2.Cu")
		(net 62)
	)
	(segment
		(start 202.400501 143.999499)
		(end 201.0005 143.999499)
		(width 0.148)
		(layer "In2.Cu")
		(net 62)
	)
	(segment
		(start 231.75 108.6)
		(end 231.75 109.775)
		(width 0.148)
		(layer "In2.Cu")
		(net 62)
	)
	(segment
		(start 204 142.4)
		(end 202.400501 143.999499)
		(width 0.148)
		(layer "In2.Cu")
		(net 62)
	)
	(segment
		(start 207.95 124.95)
		(end 204 128.9)
		(width 0.148)
		(layer "In2.Cu")
		(net 62)
	)
	(segment
		(start 222.42 104.3)
		(end 227.45 104.3)
		(width 0.148)
		(layer "In2.Cu")
		(net 62)
	)
	(segment
		(start 231.75 109.775)
		(end 231.025 110.5)
		(width 0.148)
		(layer "In2.Cu")
		(net 62)
	)
	(segment
		(start 220.2005 106.619499)
		(end 220.2005 106.5195)
		(width 0.148)
		(layer "In2.Cu")
		(net 62)
	)
	(segment
		(start 222.1 124.95)
		(end 207.95 124.95)
		(width 0.148)
		(layer "In2.Cu")
		(net 62)
	)
	(segment
		(start 218.5 106)
		(end 218.5 107.152)
		(width 0.38)
		(layer "F.Cu")
		(net 63)
	)
	(segment
		(start 197.0005 140.9995)
		(end 197.5 140.5)
		(width 0.256)
		(layer "F.Cu")
		(net 63)
	)
	(via
		(at 197.5 140.5)
		(size 0.45)
		(drill 0.1)
		(layers "F.Cu" "B.Cu")
		(remove_unused_layers yes)
		(keep_end_layers yes)
		(zone_layer_connections)
		(net 63)
	)
	(via
		(at 218.5 107.152)
		(size 0.45)
		(drill 0.1)
		(layers "F.Cu" "B.Cu")
		(remove_unused_layers yes)
		(keep_end_layers yes)
		(zone_layer_connections)
		(net 63)
	)
	(segment
		(start 220.825 108.975)
		(end 219.002 107.152)
		(width 0.148)
		(layer "In6.Cu")
		(net 63)
	)
	(segment
		(start 219.002 107.152)
		(end 218.5 107.152)
		(width 0.148)
		(layer "In6.Cu")
		(net 63)
	)
	(segment
		(start 198 141.7)
		(end 198.3 142)
		(width 0.148)
		(layer "In6.Cu")
		(net 63)
	)
	(segment
		(start 197.5 140.9)
		(end 198 141.4)
		(width 0.148)
		(layer "In6.Cu")
		(net 63)
	)
	(segment
		(start 215.7125 126.0875)
		(end 220.2 121.6)
		(width 0.148)
		(layer "In6.Cu")
		(net 63)
	)
	(segment
		(start 220.825 110.525)
		(end 220.825 108.975)
		(width 0.148)
		(layer "In6.Cu")
		(net 63)
	)
	(segment
		(start 208.7375 126.0875)
		(end 215.7125 126.0875)
		(width 0.148)
		(layer "In6.Cu")
		(net 63)
	)
	(segment
		(start 202.3 142)
		(end 206.2 138.1)
		(width 0.148)
		(layer "In6.Cu")
		(net 63)
	)
	(segment
		(start 220.2 111.15)
		(end 220.825 110.525)
		(width 0.148)
		(layer "In6.Cu")
		(net 63)
	)
	(segment
		(start 198.3 142)
		(end 202.3 142)
		(width 0.148)
		(layer "In6.Cu")
		(net 63)
	)
	(segment
		(start 206.2 138.1)
		(end 206.2 128.625)
		(width 0.148)
		(layer "In6.Cu")
		(net 63)
	)
	(segment
		(start 198 141.4)
		(end 198 141.7)
		(width 0.148)
		(layer "In6.Cu")
		(net 63)
	)
	(segment
		(start 220.2 121.6)
		(end 220.2 111.15)
		(width 0.148)
		(layer "In6.Cu")
		(net 63)
	)
	(segment
		(start 197.5 140.5)
		(end 197.5 140.9)
		(width 0.148)
		(layer "In6.Cu")
		(net 63)
	)
	(segment
		(start 206.2 128.625)
		(end 208.7375 126.0875)
		(width 0.148)
		(layer "In6.Cu")
		(net 63)
	)
	(segment
		(start 201.0005 141.9995)
		(end 201.5 141.5)
		(width 0.256)
		(layer "F.Cu")
		(net 64)
	)
	(segment
		(start 216.8 106)
		(end 216.8 107.152)
		(width 0.38)
		(layer "F.Cu")
		(net 64)
	)
	(via
		(at 201.5 141.5)
		(size 0.45)
		(drill 0.1)
		(layers "F.Cu" "B.Cu")
		(remove_unused_layers yes)
		(keep_end_layers yes)
		(zone_layer_connections)
		(net 64)
	)
	(via
		(at 216.8 107.152)
		(size 0.45)
		(drill 0.1)
		(layers "F.Cu" "B.Cu")
		(remove_unused_layers yes)
		(keep_end_layers yes)
		(zone_layer_connections)
		(net 64)
	)
	(segment
		(start 218.656876 118.193124)
		(end 218.656875 118.193124)
		(width 0.148)
		(layer "In6.Cu")
		(net 64)
	)
	(segment
		(start 217.402 107.152)
		(end 219.3 109.05)
		(width 0.148)
		(layer "In6.Cu")
		(net 64)
	)
	(segment
		(start 218.26374 116.28626)
		(end 218.26374 116.65)
		(width 0.148)
		(layer "In6.Cu")
		(net 64)
	)
	(segment
		(start 218.656845 114.743154)
		(end 218.656846 114.743154)
		(width 0.148)
		(layer "In6.Cu")
		(net 64)
	)
	(segment
		(start 219.05 119.736248)
		(end 219.05 121.075)
		(width 0.148)
		(layer "In6.Cu")
		(net 64)
	)
	(segment
		(start 218.263691 113.986308)
		(end 218.263691 114.35)
		(width 0.148)
		(layer "In6.Cu")
		(net 64)
	)
	(segment
		(start 203.365444 139.684556)
		(end 203.365441 139.684556)
		(width 0.148)
		(layer "In6.Cu")
		(net 64)
	)
	(segment
		(start 219.3 110.425)
		(end 218.6 111.125)
		(width 0.148)
		(layer "In6.Cu")
		(net 64)
	)
	(segment
		(start 218.656875 119.343124)
		(end 218.656876 119.343124)
		(width 0.148)
		(layer "In6.Cu")
		(net 64)
	)
	(segment
		(start 218.6 111.125)
		(end 218.6 112.475)
		(width 0.148)
		(layer "In6.Cu")
		(net 64)
	)
	(segment
		(start 219.05 121.075)
		(end 215.325 124.8)
		(width 0.148)
		(layer "In6.Cu")
		(net 64)
	)
	(segment
		(start 201.55 141.5)
		(end 201.5 141.5)
		(width 0.148)
		(layer "In6.Cu")
		(net 64)
	)
	(segment
		(start 205.1 137.95)
		(end 203.365444 139.684556)
		(width 0.148)
		(layer "In6.Cu")
		(net 64)
	)
	(segment
		(start 208.725 124.8)
		(end 205.1 128.425)
		(width 0.148)
		(layer "In6.Cu")
		(net 64)
	)
	(segment
		(start 219.3 109.05)
		(end 219.3 110.425)
		(width 0.148)
		(layer "In6.Cu")
		(net 64)
	)
	(segment
		(start 205.1 128.425)
		(end 205.1 137.95)
		(width 0.148)
		(layer "In6.Cu")
		(net 64)
	)
	(segment
		(start 218.263751 118.586248)
		(end 218.263751 118.95)
		(width 0.148)
		(layer "In6.Cu")
		(net 64)
	)
	(segment
		(start 219.05 115.136308)
		(end 219.05 115.5)
		(width 0.148)
		(layer "In6.Cu")
		(net 64)
	)
	(segment
		(start 216.8 107.152)
		(end 217.402 107.152)
		(width 0.148)
		(layer "In6.Cu")
		(net 64)
	)
	(segment
		(start 203.365441 139.684556)
		(end 201.55 141.5)
		(width 0.148)
		(layer "In6.Cu")
		(net 64)
	)
	(segment
		(start 218.656846 113.593154)
		(end 218.656845 113.593154)
		(width 0.148)
		(layer "In6.Cu")
		(net 64)
	)
	(segment
		(start 219.05 117.43626)
		(end 219.05 117.8)
		(width 0.148)
		(layer "In6.Cu")
		(net 64)
	)
	(segment
		(start 218.6 112.475)
		(end 219.05 112.925)
		(width 0.148)
		(layer "In6.Cu")
		(net 64)
	)
	(segment
		(start 215.325 124.8)
		(end 208.725 124.8)
		(width 0.148)
		(layer "In6.Cu")
		(net 64)
	)
	(segment
		(start 219.05 112.925)
		(end 219.05 113.2)
		(width 0.148)
		(layer "In6.Cu")
		(net 64)
	)
	(arc
		(start 218.263691 114.35)
		(mid 218.378843 114.628002)
		(end 218.656845 114.743154)
		(width 0.148)
		(layer "In6.Cu")
		(net 64)
	)
	(arc
		(start 218.26374 116.65)
		(mid 218.378885 116.927985)
		(end 218.65687 117.04313)
		(width 0.148)
		(layer "In6.Cu")
		(net 64)
	)
	(arc
		(start 219.05 117.8)
		(mid 218.934857 118.077981)
		(end 218.656876 118.193124)
		(width 0.148)
		(layer "In6.Cu")
		(net 64)
	)
	(arc
		(start 218.65687 115.89313)
		(mid 218.378885 116.008275)
		(end 218.26374 116.28626)
		(width 0.148)
		(layer "In6.Cu")
		(net 64)
	)
	(arc
		(start 218.656876 119.343124)
		(mid 218.934857 119.458267)
		(end 219.05 119.736248)
		(width 0.148)
		(layer "In6.Cu")
		(net 64)
	)
	(arc
		(start 218.65687 117.04313)
		(mid 218.934855 117.158275)
		(end 219.05 117.43626)
		(width 0.148)
		(layer "In6.Cu")
		(net 64)
	)
	(arc
		(start 219.05 115.5)
		(mid 218.934855 115.777985)
		(end 218.65687 115.89313)
		(width 0.148)
		(layer "In6.Cu")
		(net 64)
	)
	(arc
		(start 218.656875 118.193124)
		(mid 218.378894 118.308267)
		(end 218.263751 118.586248)
		(width 0.148)
		(layer "In6.Cu")
		(net 64)
	)
	(arc
		(start 218.656845 113.593154)
		(mid 218.378843 113.708306)
		(end 218.263691 113.986308)
		(width 0.148)
		(layer "In6.Cu")
		(net 64)
	)
	(arc
		(start 218.656846 114.743154)
		(mid 218.934848 114.858306)
		(end 219.05 115.136308)
		(width 0.148)
		(layer "In6.Cu")
		(net 64)
	)
	(arc
		(start 218.263751 118.95)
		(mid 218.378894 119.227981)
		(end 218.656875 119.343124)
		(width 0.148)
		(layer "In6.Cu")
		(net 64)
	)
	(arc
		(start 219.05 113.2)
		(mid 218.934848 113.478002)
		(end 218.656846 113.593154)
		(width 0.148)
		(layer "In6.Cu")
		(net 64)
	)
	(segment
		(start 199.0005 141.999501)
		(end 199.5 141.5)
		(width 0.256)
		(layer "F.Cu")
		(net 65)
	)
	(segment
		(start 212.55 106)
		(end 212.55 107.152)
		(width 0.38)
		(layer "F.Cu")
		(net 65)
	)
	(via
		(at 212.55 107.152)
		(size 0.45)
		(drill 0.1)
		(layers "F.Cu" "B.Cu")
		(remove_unused_layers yes)
		(keep_end_layers yes)
		(zone_layer_connections)
		(net 65)
	)
	(via
		(at 199.5 141.5)
		(size 0.45)
		(drill 0.1)
		(layers "F.Cu" "B.Cu")
		(remove_unused_layers yes)
		(keep_end_layers yes)
		(zone_layer_connections)
		(net 65)
	)
	(segment
		(start 210.2625 121.1625)
		(end 210.85 120.575)
		(width 0.148)
		(layer "In6.Cu")
		(net 65)
	)
	(segment
		(start 213.125 117.175)
		(end 214.375 117.175)
		(width 0.148)
		(layer "In6.Cu")
		(net 65)
	)
	(segment
		(start 214.044668 109.949999)
		(end 212.984008 111.01066)
		(width 0.148)
		(layer "In6.Cu")
		(net 65)
	)
	(segment
		(start 201.75 127.549252)
		(end 201.75 127.325)
		(width 0.148)
		(layer "In6.Cu")
		(net 65)
	)
	(segment
		(start 214.8 116.75)
		(end 214.8 110.175)
		(width 0.148)
		(layer "In6.Cu")
		(net 65)
	)
	(segment
		(start 201.287156 132.612157)
		(end 201.287157 132.612157)
		(width 0.148)
		(layer "In6.Cu")
		(net 65)
	)
	(segment
		(start 201.75 127.325)
		(end 201.75 126.9)
		(width 0.148)
		(layer "In6.Cu")
		(net 65)
	)
	(segment
		(start 201.75 136.775)
		(end 201.75 136.525)
		(width 0.148)
		(layer "In6.Cu")
		(net 65)
	)
	(segment
		(start 200 138.525)
		(end 201.75 136.775)
		(width 0.148)
		(layer "In6.Cu")
		(net 65)
	)
	(segment
		(start 201.75 129.849314)
		(end 201.75 129.625)
		(width 0.148)
		(layer "In6.Cu")
		(net 65)
	)
	(segment
		(start 210.85 119.45)
		(end 213.125 117.175)
		(width 0.148)
		(layer "In6.Cu")
		(net 65)
	)
	(segment
		(start 212.453677 110.480329)
		(end 212.453677 110.480328)
		(width 0.148)
		(layer "In6.Cu")
		(net 65)
	)
	(segment
		(start 213.514339 108.889339)
		(end 212.55 107.925)
		(width 0.148)
		(layer "In6.Cu")
		(net 65)
	)
	(segment
		(start 210.85 120.575)
		(end 210.85 119.45)
		(width 0.148)
		(layer "In6.Cu")
		(net 65)
	)
	(segment
		(start 201.75 132.149314)
		(end 201.75 131.925)
		(width 0.148)
		(layer "In6.Cu")
		(net 65)
	)
	(segment
		(start 200 141)
		(end 200 138.525)
		(width 0.148)
		(layer "In6.Cu")
		(net 65)
	)
	(segment
		(start 213.514338 108.889338)
		(end 213.514339 108.889339)
		(width 0.148)
		(layer "In6.Cu")
		(net 65)
	)
	(segment
		(start 200.824251 128.699252)
		(end 200.824251 128.475)
		(width 0.148)
		(layer "In6.Cu")
		(net 65)
	)
	(segment
		(start 201.287157 136.062157)
		(end 201.287156 136.062157)
		(width 0.148)
		(layer "In6.Cu")
		(net 65)
	)
	(segment
		(start 201.287125 128.012126)
		(end 201.287126 128.012126)
		(width 0.148)
		(layer "In6.Cu")
		(net 65)
	)
	(segment
		(start 212.55 107.925)
		(end 212.55 107.152)
		(width 0.148)
		(layer "In6.Cu")
		(net 65)
	)
	(segment
		(start 207.4875 121.1625)
		(end 210.2625 121.1625)
		(width 0.148)
		(layer "In6.Cu")
		(net 65)
	)
	(segment
		(start 212.453677 110.480328)
		(end 213.514338 109.419668)
		(width 0.148)
		(layer "In6.Cu")
		(net 65)
	)
	(segment
		(start 214.044669 109.949999)
		(end 214.044668 109.949999)
		(width 0.148)
		(layer "In6.Cu")
		(net 65)
	)
	(segment
		(start 214.375 117.175)
		(end 214.8 116.75)
		(width 0.148)
		(layer "In6.Cu")
		(net 65)
	)
	(segment
		(start 201.75 134.449314)
		(end 201.75 134.225)
		(width 0.148)
		(layer "In6.Cu")
		(net 65)
	)
	(segment
		(start 200.824313 133.299314)
		(end 200.824313 133.075)
		(width 0.148)
		(layer "In6.Cu")
		(net 65)
	)
	(segment
		(start 201.287156 130.312157)
		(end 201.287157 130.312157)
		(width 0.148)
		(layer "In6.Cu")
		(net 65)
	)
	(segment
		(start 201.75 126.9)
		(end 207.4875 121.1625)
		(width 0.148)
		(layer "In6.Cu")
		(net 65)
	)
	(segment
		(start 214.8 110.175)
		(end 214.575 109.95)
		(width 0.148)
		(layer "In6.Cu")
		(net 65)
	)
	(segment
		(start 201.287126 129.162126)
		(end 201.287125 129.162126)
		(width 0.148)
		(layer "In6.Cu")
		(net 65)
	)
	(segment
		(start 199.5 141.5)
		(end 200 141)
		(width 0.148)
		(layer "In6.Cu")
		(net 65)
	)
	(segment
		(start 201.287156 134.912157)
		(end 201.287157 134.912157)
		(width 0.148)
		(layer "In6.Cu")
		(net 65)
	)
	(segment
		(start 201.287157 131.462157)
		(end 201.287156 131.462157)
		(width 0.148)
		(layer "In6.Cu")
		(net 65)
	)
	(segment
		(start 200.824313 130.999314)
		(end 200.824313 130.775)
		(width 0.148)
		(layer "In6.Cu")
		(net 65)
	)
	(segment
		(start 200.824313 135.599314)
		(end 200.824313 135.375)
		(width 0.148)
		(layer "In6.Cu")
		(net 65)
	)
	(segment
		(start 201.287157 133.762157)
		(end 201.287156 133.762157)
		(width 0.148)
		(layer "In6.Cu")
		(net 65)
	)
	(arc
		(start 201.287125 129.162126)
		(mid 200.959824 129.026553)
		(end 200.824251 128.699252)
		(width 0.148)
		(layer "In6.Cu")
		(net 65)
	)
	(arc
		(start 200.824313 135.375)
		(mid 200.959877 135.047721)
		(end 201.287156 134.912157)
		(width 0.148)
		(layer "In6.Cu")
		(net 65)
	)
	(arc
		(start 200.824313 130.775)
		(mid 200.959877 130.447721)
		(end 201.287156 130.312157)
		(width 0.148)
		(layer "In6.Cu")
		(net 65)
	)
	(arc
		(start 214.575 109.95)
		(mid 214.309834 109.840163)
		(end 214.044669 109.949999)
		(width 0.148)
		(layer "In6.Cu")
		(net 65)
	)
	(arc
		(start 201.287156 136.062157)
		(mid 200.959877 135.926593)
		(end 200.824313 135.599314)
		(width 0.148)
		(layer "In6.Cu")
		(net 65)
	)
	(arc
		(start 201.287157 132.612157)
		(mid 201.614436 132.476593)
		(end 201.75 132.149314)
		(width 0.148)
		(layer "In6.Cu")
		(net 65)
	)
	(arc
		(start 200.824313 133.075)
		(mid 200.959877 132.747721)
		(end 201.287156 132.612157)
		(width 0.148)
		(layer "In6.Cu")
		(net 65)
	)
	(arc
		(start 213.514338 109.419668)
		(mid 213.624173 109.154503)
		(end 213.514338 108.889338)
		(width 0.148)
		(layer "In6.Cu")
		(net 65)
	)
	(arc
		(start 201.287156 133.762157)
		(mid 200.959877 133.626593)
		(end 200.824313 133.299314)
		(width 0.148)
		(layer "In6.Cu")
		(net 65)
	)
	(arc
		(start 212.984008 111.01066)
		(mid 212.718843 111.120495)
		(end 212.453678 111.01066)
		(width 0.148)
		(layer "In6.Cu")
		(net 65)
	)
	(arc
		(start 201.75 129.625)
		(mid 201.614427 129.297699)
		(end 201.287126 129.162126)
		(width 0.148)
		(layer "In6.Cu")
		(net 65)
	)
	(arc
		(start 200.824251 128.475)
		(mid 200.959824 128.147699)
		(end 201.287125 128.012126)
		(width 0.148)
		(layer "In6.Cu")
		(net 65)
	)
	(arc
		(start 201.287157 134.912157)
		(mid 201.614436 134.776593)
		(end 201.75 134.449314)
		(width 0.148)
		(layer "In6.Cu")
		(net 65)
	)
	(arc
		(start 212.453678 111.01066)
		(mid 212.343841 110.745494)
		(end 212.453677 110.480329)
		(width 0.148)
		(layer "In6.Cu")
		(net 65)
	)
	(arc
		(start 201.75 134.225)
		(mid 201.614436 133.897721)
		(end 201.287157 133.762157)
		(width 0.148)
		(layer "In6.Cu")
		(net 65)
	)
	(arc
		(start 201.75 136.525)
		(mid 201.614436 136.197721)
		(end 201.287157 136.062157)
		(width 0.148)
		(layer "In6.Cu")
		(net 65)
	)
	(arc
		(start 201.287126 128.012126)
		(mid 201.614427 127.876553)
		(end 201.75 127.549252)
		(width 0.148)
		(layer "In6.Cu")
		(net 65)
	)
	(arc
		(start 201.287157 130.312157)
		(mid 201.614436 130.176593)
		(end 201.75 129.849314)
		(width 0.148)
		(layer "In6.Cu")
		(net 65)
	)
	(arc
		(start 201.287156 131.462157)
		(mid 200.959877 131.326593)
		(end 200.824313 130.999314)
		(width 0.148)
		(layer "In6.Cu")
		(net 65)
	)
	(arc
		(start 201.75 131.925)
		(mid 201.614436 131.597721)
		(end 201.287157 131.462157)
		(width 0.148)
		(layer "In6.Cu")
		(net 65)
	)
	(segment
		(start 210.85 106)
		(end 210.85 107.152)
		(width 0.38)
		(layer "F.Cu")
		(net 66)
	)
	(segment
		(start 198.0005 141.9995)
		(end 198.5 141.5)
		(width 0.256)
		(layer "F.Cu")
		(net 66)
	)
	(via
		(at 210.85 107.152)
		(size 0.45)
		(drill 0.1)
		(layers "F.Cu" "B.Cu")
		(remove_unused_layers yes)
		(keep_end_layers yes)
		(zone_layer_connections)
		(net 66)
	)
	(via
		(at 198.5 141.5)
		(size 0.45)
		(drill 0.1)
		(layers "F.Cu" "B.Cu")
		(remove_unused_layers yes)
		(keep_end_layers yes)
		(zone_layer_connections)
		(net 66)
	)
	(segment
		(start 196.6 136.025)
		(end 196.6 138.7)
		(width 0.148)
		(layer "In6.Cu")
		(net 66)
	)
	(segment
		(start 195.944722 117.030282)
		(end 195.15 117.825)
		(width 0.148)
		(layer "In6.Cu")
		(net 66)
	)
	(segment
		(start 195.725 122.275)
		(end 195.675 122.275)
		(width 0.148)
		(layer "In6.Cu")
		(net 66)
	)
	(segment
		(start 198.3625 115.015024)
		(end 198.362501 115.015025)
		(width 0.148)
		(layer "In6.Cu")
		(net 66)
	)
	(segment
		(start 197.018998 116.761052)
		(end 197.018997 116.761053)
		(width 0.148)
		(layer "In6.Cu")
		(net 66)
	)
	(segment
		(start 197.018997 116.761053)
		(end 196.749768 117.030283)
		(width 0.148)
		(layer "In6.Cu")
		(net 66)
	)
	(segment
		(start 195.944723 117.030281)
		(end 195.944722 117.030282)
		(width 0.148)
		(layer "In6.Cu")
		(net 66)
	)
	(segment
		(start 210.6 112.575)
		(end 209.025 114.15)
		(width 0.148)
		(layer "In6.Cu")
		(net 66)
	)
	(segment
		(start 197.25 140)
		(end 197.707136 140)
		(width 0.148)
		(layer "In6.Cu")
		(net 66)
	)
	(segment
		(start 197.707136 140)
		(end 198.05 140.342864)
		(width 0.148)
		(layer "In6.Cu")
		(net 66)
	)
	(segment
		(start 195.675 119.125)
		(end 195.725 119.125)
		(width 0.148)
		(layer "In6.Cu")
		(net 66)
	)
	(segment
		(start 195.15 122.8)
		(end 195.15 123.4)
		(width 0.148)
		(layer "In6.Cu")
		(net 66)
	)
	(segment
		(start 210.2 110.85)
		(end 210.6 111.25)
		(width 0.148)
		(layer "In6.Cu")
		(net 66)
	)
	(segment
		(start 198.05 140.342864)
		(end 198.05 140.7)
		(width 0.148)
		(layer "In6.Cu")
		(net 66)
	)
	(segment
		(start 195.15 123.4)
		(end 196.9 125.15)
		(width 0.148)
		(layer "In6.Cu")
		(net 66)
	)
	(segment
		(start 198.362502 115.417548)
		(end 198.362501 115.417549)
		(width 0.148)
		(layer "In6.Cu")
		(net 66)
	)
	(segment
		(start 196.95 139.05)
		(end 196.95 139.7)
		(width 0.148)
		(layer "In6.Cu")
		(net 66)
	)
	(segment
		(start 195.675 121.225)
		(end 195.725 121.225)
		(width 0.148)
		(layer "In6.Cu")
		(net 66)
	)
	(segment
		(start 210.85 107.152)
		(end 210.2 107.802)
		(width 0.148)
		(layer "In6.Cu")
		(net 66)
	)
	(segment
		(start 197.690749 115.686778)
		(end 197.69075 115.686778)
		(width 0.148)
		(layer "In6.Cu")
		(net 66)
	)
	(segment
		(start 196.6 138.7)
		(end 196.95 139.05)
		(width 0.148)
		(layer "In6.Cu")
		(net 66)
	)
	(segment
		(start 195.15 117.825)
		(end 195.15 118.6)
		(width 0.148)
		(layer "In6.Cu")
		(net 66)
	)
	(segment
		(start 197.018996 116.358528)
		(end 197.018997 116.358529)
		(width 0.148)
		(layer "In6.Cu")
		(net 66)
	)
	(segment
		(start 196.9 125.15)
		(end 196.9 135.725)
		(width 0.148)
		(layer "In6.Cu")
		(net 66)
	)
	(segment
		(start 210.6 111.25)
		(end 210.6 112.575)
		(width 0.148)
		(layer "In6.Cu")
		(net 66)
	)
	(segment
		(start 196.95 139.7)
		(end 197.25 140)
		(width 0.148)
		(layer "In6.Cu")
		(net 66)
	)
	(segment
		(start 198.362501 115.417549)
		(end 198.093272 115.686779)
		(width 0.148)
		(layer "In6.Cu")
		(net 66)
	)
	(segment
		(start 198.825 114.15)
		(end 198.3625 114.6125)
		(width 0.148)
		(layer "In6.Cu")
		(net 66)
	)
	(segment
		(start 195.725 120.175)
		(end 195.675 120.175)
		(width 0.148)
		(layer "In6.Cu")
		(net 66)
	)
	(segment
		(start 196.347245 117.030282)
		(end 196.347246 117.030282)
		(width 0.148)
		(layer "In6.Cu")
		(net 66)
	)
	(segment
		(start 197.288226 115.686778)
		(end 197.018996 115.956004)
		(width 0.148)
		(layer "In6.Cu")
		(net 66)
	)
	(segment
		(start 209.025 114.15)
		(end 198.825 114.15)
		(width 0.148)
		(layer "In6.Cu")
		(net 66)
	)
	(segment
		(start 210.2 107.802)
		(end 210.2 110.85)
		(width 0.148)
		(layer "In6.Cu")
		(net 66)
	)
	(segment
		(start 197.288227 115.686777)
		(end 197.288226 115.686778)
		(width 0.148)
		(layer "In6.Cu")
		(net 66)
	)
	(segment
		(start 198.05 140.7)
		(end 198.5 141.15)
		(width 0.148)
		(layer "In6.Cu")
		(net 66)
	)
	(segment
		(start 196.9 135.725)
		(end 196.6 136.025)
		(width 0.148)
		(layer "In6.Cu")
		(net 66)
	)
	(segment
		(start 198.5 141.15)
		(end 198.5 141.5)
		(width 0.148)
		(layer "In6.Cu")
		(net 66)
	)
	(arc
		(start 195.725 119.125)
		(mid 196.096231 119.278769)
		(end 196.25 119.65)
		(width 0.148)
		(layer "In6.Cu")
		(net 66)
	)
	(arc
		(start 195.675 122.275)
		(mid 195.303769 122.428769)
		(end 195.15 122.8)
		(width 0.148)
		(layer "In6.Cu")
		(net 66)
	)
	(arc
		(start 197.018996 115.956004)
		(mid 196.93563 116.157267)
		(end 197.018996 116.358528)
		(width 0.148)
		(layer "In6.Cu")
		(net 66)
	)
	(arc
		(start 196.749768 117.030283)
		(mid 196.548507 117.113647)
		(end 196.347245 117.030282)
		(width 0.148)
		(layer "In6.Cu")
		(net 66)
	)
	(arc
		(start 195.725 121.225)
		(mid 196.096231 121.378769)
		(end 196.25 121.75)
		(width 0.148)
		(layer "In6.Cu")
		(net 66)
	)
	(arc
		(start 196.25 119.65)
		(mid 196.096231 120.021231)
		(end 195.725 120.175)
		(width 0.148)
		(layer "In6.Cu")
		(net 66)
	)
	(arc
		(start 198.362501 115.015025)
		(mid 198.445866 115.216287)
		(end 198.362502 115.417548)
		(width 0.148)
		(layer "In6.Cu")
		(net 66)
	)
	(arc
		(start 197.69075 115.686778)
		(mid 197.489488 115.603413)
		(end 197.288227 115.686777)
		(width 0.148)
		(layer "In6.Cu")
		(net 66)
	)
	(arc
		(start 195.675 120.175)
		(mid 195.303769 120.328769)
		(end 195.15 120.7)
		(width 0.148)
		(layer "In6.Cu")
		(net 66)
	)
	(arc
		(start 197.018997 116.358529)
		(mid 197.102362 116.559791)
		(end 197.018998 116.761052)
		(width 0.148)
		(layer "In6.Cu")
		(net 66)
	)
	(arc
		(start 195.15 120.7)
		(mid 195.303769 121.071231)
		(end 195.675 121.225)
		(width 0.148)
		(layer "In6.Cu")
		(net 66)
	)
	(arc
		(start 198.093272 115.686779)
		(mid 197.892011 115.770143)
		(end 197.690749 115.686778)
		(width 0.148)
		(layer "In6.Cu")
		(net 66)
	)
	(arc
		(start 196.25 121.75)
		(mid 196.096231 122.121231)
		(end 195.725 122.275)
		(width 0.148)
		(layer "In6.Cu")
		(net 66)
	)
	(arc
		(start 198.3625 114.6125)
		(mid 198.279134 114.813763)
		(end 198.3625 115.015024)
		(width 0.148)
		(layer "In6.Cu")
		(net 66)
	)
	(arc
		(start 196.347246 117.030282)
		(mid 196.145984 116.946917)
		(end 195.944723 117.030281)
		(width 0.148)
		(layer "In6.Cu")
		(net 66)
	)
	(arc
		(start 195.15 118.6)
		(mid 195.303769 118.971231)
		(end 195.675 119.125)
		(width 0.148)
		(layer "In6.Cu")
		(net 66)
	)
	(segment
		(start 192.0005 143.9995)
		(end 192.5 143.5)
		(width 0.256)
		(layer "F.Cu")
		(net 67)
	)
	(segment
		(start 209.15 106)
		(end 209.15 107.152)
		(width 0.38)
		(layer "F.Cu")
		(net 67)
	)
	(via
		(at 192.5 143.5)
		(size 0.45)
		(drill 0.1)
		(layers "F.Cu" "B.Cu")
		(remove_unused_layers yes)
		(keep_end_layers yes)
		(zone_layer_connections)
		(net 67)
	)
	(via
		(at 209.15 107.152)
		(size 0.45)
		(drill 0.1)
		(layers "F.Cu" "B.Cu")
		(remove_unused_layers yes)
		(keep_end_layers yes)
		(zone_layer_connections)
		(net 67)
	)
	(segment
		(start 205.852648 122.257353)
		(end 205.852648 122.257352)
		(width 0.15)
		(layer "In4.Cu")
		(net 67)
	)
	(segment
		(start 192.5 143.5)
		(end 193 143)
		(width 0.15)
		(layer "In4.Cu")
		(net 67)
	)
	(segment
		(start 203.731324 124.378677)
		(end 203.731324 124.378676)
		(width 0.15)
		(layer "In4.Cu")
		(net 67)
	)
	(segment
		(start 202.670662 124.909008)
		(end 202.047269 124.285615)
		(width 0.15)
		(layer "In4.Cu")
		(net 67)
	)
	(segment
		(start 200.986634 124.815974)
		(end 200.986636 124.815973)
		(width 0.15)
		(layer "In4.Cu")
		(net 67)
	)
	(segment
		(start 210.325 109.6)
		(end 211.2 110.475)
		(width 0.148)
		(layer "In4.Cu")
		(net 67)
	)
	(segment
		(start 193 143)
		(end 193 134.1)
		(width 0.15)
		(layer "In4.Cu")
		(net 67)
	)
	(segment
		(start 202.670662 125.439339)
		(end 202.670662 125.439338)
		(width 0.15)
		(layer "In4.Cu")
		(net 67)
	)
	(segment
		(start 205.852649 122.257354)
		(end 205.852648 122.257353)
		(width 0.15)
		(layer "In4.Cu")
		(net 67)
	)
	(segment
		(start 204.168615 121.633983)
		(end 204.168617 121.633982)
		(width 0.15)
		(layer "In4.Cu")
		(net 67)
	)
	(segment
		(start 210.325 108.325)
		(end 210.325 109.6)
		(width 0.148)
		(layer "In4.Cu")
		(net 67)
	)
	(segment
		(start 204.791986 123.318015)
		(end 204.791986 123.318014)
		(width 0.15)
		(layer "In4.Cu")
		(net 67)
	)
	(segment
		(start 209.15 107.152)
		(end 209.152 107.152)
		(width 0.15)
		(layer "In4.Cu")
		(net 67)
	)
	(segment
		(start 209.034635 119.075368)
		(end 209.034634 119.075367)
		(width 0.15)
		(layer "In4.Cu")
		(net 67)
	)
	(segment
		(start 206.820292 119.51268)
		(end 207.443642 120.13603)
		(width 0.15)
		(layer "In4.Cu")
		(net 67)
	)
	(segment
		(start 193 134.1)
		(end 200.23 126.87)
		(width 0.15)
		(layer "In4.Cu")
		(net 67)
	)
	(segment
		(start 206.28996 119.51268)
		(end 206.289962 119.512679)
		(width 0.15)
		(layer "In4.Cu")
		(net 67)
	)
	(segment
		(start 204.791987 123.318016)
		(end 204.791986 123.318015)
		(width 0.15)
		(layer "In4.Cu")
		(net 67)
	)
	(segment
		(start 201.516966 124.815973)
		(end 202.140333 125.43934)
		(width 0.15)
		(layer "In4.Cu")
		(net 67)
	)
	(segment
		(start 201.61 125.96967)
		(end 200.986634 125.346304)
		(width 0.15)
		(layer "In4.Cu")
		(net 67)
	)
	(segment
		(start 209.152 107.152)
		(end 210.325 108.325)
		(width 0.15)
		(layer "In4.Cu")
		(net 67)
	)
	(segment
		(start 205.852648 121.727022)
		(end 205.229282 121.103656)
		(width 0.15)
		(layer "In4.Cu")
		(net 67)
	)
	(segment
		(start 207.350586 118.451982)
		(end 207.350588 118.451981)
		(width 0.15)
		(layer "In4.Cu")
		(net 67)
	)
	(segment
		(start 203.731324 123.848346)
		(end 203.107958 123.22498)
		(width 0.15)
		(layer "In4.Cu")
		(net 67)
	)
	(segment
		(start 204.791986 122.787684)
		(end 204.168615 122.164313)
		(width 0.15)
		(layer "In4.Cu")
		(net 67)
	)
	(segment
		(start 207.880918 118.451981)
		(end 208.504305 119.075368)
		(width 0.15)
		(layer "In4.Cu")
		(net 67)
	)
	(segment
		(start 209.034634 119.075367)
		(end 211.2 116.91)
		(width 0.15)
		(layer "In4.Cu")
		(net 67)
	)
	(segment
		(start 205.229282 120.573326)
		(end 205.229284 120.573325)
		(width 0.15)
		(layer "In4.Cu")
		(net 67)
	)
	(segment
		(start 205.759614 120.573325)
		(end 206.382981 121.196692)
		(width 0.15)
		(layer "In4.Cu")
		(net 67)
	)
	(segment
		(start 211.2 110.475)
		(end 211.2 110.6)
		(width 0.148)
		(layer "In4.Cu")
		(net 67)
	)
	(segment
		(start 206.289962 119.512679)
		(end 206.289962 119.51268)
		(width 0.15)
		(layer "In4.Cu")
		(net 67)
	)
	(segment
		(start 200.23 126.87)
		(end 201.24 126.87)
		(width 0.15)
		(layer "In4.Cu")
		(net 67)
	)
	(segment
		(start 204.698947 121.633982)
		(end 205.322319 122.257354)
		(width 0.15)
		(layer "In4.Cu")
		(net 67)
	)
	(segment
		(start 201.24 126.87)
		(end 201.61 126.5)
		(width 0.15)
		(layer "In4.Cu")
		(net 67)
	)
	(segment
		(start 206.91331 121.196691)
		(end 206.91331 121.19669)
		(width 0.15)
		(layer "In4.Cu")
		(net 67)
	)
	(segment
		(start 206.91331 120.66636)
		(end 206.289961 120.043011)
		(width 0.15)
		(layer "In4.Cu")
		(net 67)
	)
	(segment
		(start 207.973973 120.136031)
		(end 207.973974 120.136029)
		(width 0.15)
		(layer "In4.Cu")
		(net 67)
	)
	(segment
		(start 202.577601 123.755284)
		(end 203.200995 124.378678)
		(width 0.15)
		(layer "In4.Cu")
		(net 67)
	)
	(segment
		(start 203.107958 122.69465)
		(end 203.10796 122.694649)
		(width 0.15)
		(layer "In4.Cu")
		(net 67)
	)
	(segment
		(start 202.670663 125.43934)
		(end 202.670662 125.439339)
		(width 0.15)
		(layer "In4.Cu")
		(net 67)
	)
	(segment
		(start 207.973974 120.136029)
		(end 207.973972 120.136028)
		(width 0.15)
		(layer "In4.Cu")
		(net 67)
	)
	(segment
		(start 207.973972 119.605698)
		(end 207.350586 118.982312)
		(width 0.15)
		(layer "In4.Cu")
		(net 67)
	)
	(segment
		(start 206.913311 121.196692)
		(end 206.91331 121.196691)
		(width 0.15)
		(layer "In4.Cu")
		(net 67)
	)
	(segment
		(start 211.2 116.91)
		(end 211.2 110.6)
		(width 0.15)
		(layer "In4.Cu")
		(net 67)
	)
	(segment
		(start 202.047269 123.755285)
		(end 202.047271 123.755284)
		(width 0.15)
		(layer "In4.Cu")
		(net 67)
	)
	(segment
		(start 203.731325 124.378678)
		(end 203.731324 124.378677)
		(width 0.15)
		(layer "In4.Cu")
		(net 67)
	)
	(segment
		(start 203.63829 122.694649)
		(end 204.261657 123.318016)
		(width 0.15)
		(layer "In4.Cu")
		(net 67)
	)
	(arc
		(start 204.261657 123.318016)
		(mid 204.526822 123.427851)
		(end 204.791987 123.318016)
		(width 0.15)
		(layer "In4.Cu")
		(net 67)
	)
	(arc
		(start 204.168615 122.164313)
		(mid 204.05878 121.899148)
		(end 204.168615 121.633983)
		(width 0.15)
		(layer "In4.Cu")
		(net 67)
	)
	(arc
		(start 200.986634 125.346304)
		(mid 200.876799 125.081139)
		(end 200.986634 124.815974)
		(width 0.15)
		(layer "In4.Cu")
		(net 67)
	)
	(arc
		(start 204.791986 123.318014)
		(mid 204.901821 123.052849)
		(end 204.791986 122.787684)
		(width 0.15)
		(layer "In4.Cu")
		(net 67)
	)
	(arc
		(start 206.91331 121.19669)
		(mid 207.023145 120.931525)
		(end 206.91331 120.66636)
		(width 0.15)
		(layer "In4.Cu")
		(net 67)
	)
	(arc
		(start 202.047269 124.285615)
		(mid 201.937434 124.02045)
		(end 202.047269 123.755285)
		(width 0.15)
		(layer "In4.Cu")
		(net 67)
	)
	(arc
		(start 200.986636 124.815973)
		(mid 201.251801 124.706138)
		(end 201.516966 124.815973)
		(width 0.15)
		(layer "In4.Cu")
		(net 67)
	)
	(arc
		(start 203.10796 122.694649)
		(mid 203.373125 122.584814)
		(end 203.63829 122.694649)
		(width 0.15)
		(layer "In4.Cu")
		(net 67)
	)
	(arc
		(start 202.140333 125.43934)
		(mid 202.405498 125.549175)
		(end 202.670663 125.43934)
		(width 0.15)
		(layer "In4.Cu")
		(net 67)
	)
	(arc
		(start 205.229284 120.573325)
		(mid 205.494449 120.46349)
		(end 205.759614 120.573325)
		(width 0.15)
		(layer "In4.Cu")
		(net 67)
	)
	(arc
		(start 206.382981 121.196692)
		(mid 206.648146 121.306527)
		(end 206.913311 121.196692)
		(width 0.15)
		(layer "In4.Cu")
		(net 67)
	)
	(arc
		(start 206.289962 119.51268)
		(mid 206.555127 119.402845)
		(end 206.820292 119.51268)
		(width 0.15)
		(layer "In4.Cu")
		(net 67)
	)
	(arc
		(start 205.322319 122.257354)
		(mid 205.587484 122.367189)
		(end 205.852649 122.257354)
		(width 0.15)
		(layer "In4.Cu")
		(net 67)
	)
	(arc
		(start 207.443642 120.13603)
		(mid 207.708808 120.245865)
		(end 207.973973 120.136031)
		(width 0.15)
		(layer "In4.Cu")
		(net 67)
	)
	(arc
		(start 208.504305 119.075368)
		(mid 208.76947 119.185203)
		(end 209.034635 119.075368)
		(width 0.15)
		(layer "In4.Cu")
		(net 67)
	)
	(arc
		(start 202.047271 123.755284)
		(mid 202.312436 123.645449)
		(end 202.577601 123.755284)
		(width 0.15)
		(layer "In4.Cu")
		(net 67)
	)
	(arc
		(start 203.731324 124.378676)
		(mid 203.841159 124.113511)
		(end 203.731324 123.848346)
		(width 0.15)
		(layer "In4.Cu")
		(net 67)
	)
	(arc
		(start 207.350586 118.982312)
		(mid 207.240751 118.717147)
		(end 207.350586 118.451982)
		(width 0.15)
		(layer "In4.Cu")
		(net 67)
	)
	(arc
		(start 206.289961 120.043011)
		(mid 206.180126 119.777845)
		(end 206.28996 119.51268)
		(width 0.15)
		(layer "In4.Cu")
		(net 67)
	)
	(arc
		(start 205.229282 121.103656)
		(mid 205.119447 120.838491)
		(end 205.229282 120.573326)
		(width 0.15)
		(layer "In4.Cu")
		(net 67)
	)
	(arc
		(start 201.61 126.5)
		(mid 201.719835 126.234835)
		(end 201.61 125.96967)
		(width 0.15)
		(layer "In4.Cu")
		(net 67)
	)
	(arc
		(start 203.200995 124.378678)
		(mid 203.46616 124.488513)
		(end 203.731325 124.378678)
		(width 0.15)
		(layer "In4.Cu")
		(net 67)
	)
	(arc
		(start 204.168617 121.633982)
		(mid 204.433782 121.524147)
		(end 204.698947 121.633982)
		(width 0.15)
		(layer "In4.Cu")
		(net 67)
	)
	(arc
		(start 205.852648 122.257352)
		(mid 205.962483 121.992187)
		(end 205.852648 121.727022)
		(width 0.15)
		(layer "In4.Cu")
		(net 67)
	)
	(arc
		(start 203.107958 123.22498)
		(mid 202.998123 122.959815)
		(end 203.107958 122.69465)
		(width 0.15)
		(layer "In4.Cu")
		(net 67)
	)
	(arc
		(start 207.973972 120.136028)
		(mid 208.083807 119.870863)
		(end 207.973972 119.605698)
		(width 0.15)
		(layer "In4.Cu")
		(net 67)
	)
	(arc
		(start 202.670662 125.439338)
		(mid 202.780497 125.174173)
		(end 202.670662 124.909008)
		(width 0.15)
		(layer "In4.Cu")
		(net 67)
	)
	(arc
		(start 207.350588 118.451981)
		(mid 207.615753 118.342146)
		(end 207.880918 118.451981)
		(width 0.15)
		(layer "In4.Cu")
		(net 67)
	)
	(segment
		(start 192.0005 144.999499)
		(end 192.5 144.5)
		(width 0.256)
		(layer "F.Cu")
		(net 68)
	)
	(segment
		(start 207.45 106)
		(end 207.45 107.152)
		(width 0.38)
		(layer "F.Cu")
		(net 68)
	)
	(via
		(at 207.45 107.152)
		(size 0.45)
		(drill 0.1)
		(layers "F.Cu" "B.Cu")
		(remove_unused_layers yes)
		(keep_end_layers yes)
		(zone_layer_connections)
		(net 68)
	)
	(via
		(at 192.5 144.5)
		(size 0.45)
		(drill 0.1)
		(layers "F.Cu" "B.Cu")
		(remove_unused_layers yes)
		(keep_end_layers yes)
		(zone_layer_connections)
		(net 68)
	)
	(segment
		(start 210.5 110.65)
		(end 210.5 116)
		(width 0.15)
		(layer "In4.Cu")
		(net 68)
	)
	(segment
		(start 210.5 116)
		(end 208.94 117.56)
		(width 0.15)
		(layer "In4.Cu")
		(net 68)
	)
	(segment
		(start 206.73 117.56)
		(end 199.54 124.75)
		(width 0.15)
		(layer "In4.Cu")
		(net 68)
	)
	(segment
		(start 195.440391 128.414026)
		(end 196.068016 129.041651)
		(width 0.15)
		(layer "In4.Cu")
		(net 68)
	)
	(segment
		(start 196.068017 129.571982)
		(end 196.068017 129.571983)
		(width 0.15)
		(layer "In4.Cu")
		(net 68)
	)
	(segment
		(start 193.416363 131.693305)
		(end 193.416364 131.693305)
		(width 0.15)
		(layer "In4.Cu")
		(net 68)
	)
	(segment
		(start 196.068016 129.571981)
		(end 196.068017 129.571982)
		(width 0.15)
		(layer "In4.Cu")
		(net 68)
	)
	(segment
		(start 197.128678 128.511321)
		(end 197.128678 128.511322)
		(width 0.15)
		(layer "In4.Cu")
		(net 68)
	)
	(segment
		(start 208.94 117.56)
		(end 206.73 117.56)
		(width 0.15)
		(layer "In4.Cu")
		(net 68)
	)
	(segment
		(start 192.258382 131.595983)
		(end 192.886033 132.223634)
		(width 0.15)
		(layer "In4.Cu")
		(net 68)
	)
	(segment
		(start 193.416364 131.693305)
		(end 192.788712 131.065653)
		(width 0.15)
		(layer "In4.Cu")
		(net 68)
	)
	(segment
		(start 207.777 107.152)
		(end 207.45 107.152)
		(width 0.15)
		(layer "In4.Cu")
		(net 68)
	)
	(segment
		(start 194.37973 129.474687)
		(end 195.007355 130.102312)
		(width 0.15)
		(layer "In4.Cu")
		(net 68)
	)
	(segment
		(start 195.007356 130.632643)
		(end 195.007356 130.632644)
		(width 0.15)
		(layer "In4.Cu")
		(net 68)
	)
	(segment
		(start 209.7625 109.1375)
		(end 209.7625 109.9125)
		(width 0.148)
		(layer "In4.Cu")
		(net 68)
	)
	(segment
		(start 192.886034 132.753965)
		(end 192 133.64)
		(width 0.15)
		(layer "In4.Cu")
		(net 68)
	)
	(segment
		(start 195.007355 130.632642)
		(end 195.007356 130.632643)
		(width 0.15)
		(layer "In4.Cu")
		(net 68)
	)
	(segment
		(start 192.886033 132.753964)
		(end 192.886034 132.753965)
		(width 0.15)
		(layer "In4.Cu")
		(net 68)
	)
	(segment
		(start 198.719668 126.39)
		(end 198.719669 126.39)
		(width 0.15)
		(layer "In4.Cu")
		(net 68)
	)
	(segment
		(start 194.477025 130.632644)
		(end 193.849408 130.005027)
		(width 0.15)
		(layer "In4.Cu")
		(net 68)
	)
	(segment
		(start 199.54 124.75)
		(end 199.54 126.1)
		(width 0.15)
		(layer "In4.Cu")
		(net 68)
	)
	(segment
		(start 195.537686 129.571983)
		(end 194.91006 128.944357)
		(width 0.15)
		(layer "In4.Cu")
		(net 68)
	)
	(segment
		(start 197.128677 128.51132)
		(end 197.128678 128.511321)
		(width 0.15)
		(layer "In4.Cu")
		(net 68)
	)
	(segment
		(start 198.719669 126.39)
		(end 198.092017 125.762348)
		(width 0.15)
		(layer "In4.Cu")
		(net 68)
	)
	(segment
		(start 192 133.64)
		(end 192 144)
		(width 0.15)
		(layer "In4.Cu")
		(net 68)
	)
	(segment
		(start 193.946695 131.693304)
		(end 193.946695 131.693305)
		(width 0.15)
		(layer "In4.Cu")
		(net 68)
	)
	(segment
		(start 209.7625 109.9125)
		(end 210.5 110.65)
		(width 0.148)
		(layer "In4.Cu")
		(net 68)
	)
	(segment
		(start 199.54 126.1)
		(end 199.25 126.39)
		(width 0.15)
		(layer "In4.Cu")
		(net 68)
	)
	(segment
		(start 197.561687 126.292678)
		(end 198.189338 126.920329)
		(width 0.15)
		(layer "In4.Cu")
		(net 68)
	)
	(segment
		(start 193.946694 131.693303)
		(end 193.946695 131.693304)
		(width 0.15)
		(layer "In4.Cu")
		(net 68)
	)
	(segment
		(start 196.598346 128.511322)
		(end 196.598347 128.511322)
		(width 0.15)
		(layer "In4.Cu")
		(net 68)
	)
	(segment
		(start 197.659007 127.450661)
		(end 197.659008 127.450661)
		(width 0.15)
		(layer "In4.Cu")
		(net 68)
	)
	(segment
		(start 197.659008 127.450661)
		(end 197.031382 126.823035)
		(width 0.15)
		(layer "In4.Cu")
		(net 68)
	)
	(segment
		(start 198.189339 127.45066)
		(end 198.189339 127.450661)
		(width 0.15)
		(layer "In4.Cu")
		(net 68)
	)
	(segment
		(start 196.501052 127.353365)
		(end 197.128677 127.98099)
		(width 0.15)
		(layer "In4.Cu")
		(net 68)
	)
	(segment
		(start 192 144)
		(end 192.5 144.5)
		(width 0.15)
		(layer "In4.Cu")
		(net 68)
	)
	(segment
		(start 196.598347 128.511322)
		(end 195.970721 127.883696)
		(width 0.15)
		(layer "In4.Cu")
		(net 68)
	)
	(segment
		(start 194.477024 130.632644)
		(end 194.477025 130.632644)
		(width 0.15)
		(layer "In4.Cu")
		(net 68)
	)
	(segment
		(start 209.7625 109.1375)
		(end 207.777 107.152)
		(width 0.15)
		(layer "In4.Cu")
		(net 68)
	)
	(segment
		(start 195.537685 129.571983)
		(end 195.537686 129.571983)
		(width 0.15)
		(layer "In4.Cu")
		(net 68)
	)
	(segment
		(start 198.189338 127.450659)
		(end 198.189339 127.45066)
		(width 0.15)
		(layer "In4.Cu")
		(net 68)
	)
	(segment
		(start 193.319078 130.535357)
		(end 193.946694 131.162973)
		(width 0.15)
		(layer "In4.Cu")
		(net 68)
	)
	(arc
		(start 198.189338 126.920329)
		(mid 198.299173 127.185494)
		(end 198.189338 127.450659)
		(width 0.15)
		(layer "In4.Cu")
		(net 68)
	)
	(arc
		(start 192.258382 131.065653)
		(mid 192.148547 131.330818)
		(end 192.258382 131.595983)
		(width 0.15)
		(layer "In4.Cu")
		(net 68)
	)
	(arc
		(start 198.189339 127.450661)
		(mid 197.924173 127.560496)
		(end 197.659007 127.450661)
		(width 0.15)
		(layer "In4.Cu")
		(net 68)
	)
	(arc
		(start 199.25 126.39)
		(mid 198.984834 126.499835)
		(end 198.719668 126.39)
		(width 0.15)
		(layer "In4.Cu")
		(net 68)
	)
	(arc
		(start 197.031382 126.823035)
		(mid 196.766217 126.7132)
		(end 196.501052 126.823035)
		(width 0.15)
		(layer "In4.Cu")
		(net 68)
	)
	(arc
		(start 197.128678 128.511322)
		(mid 196.863512 128.621157)
		(end 196.598346 128.511322)
		(width 0.15)
		(layer "In4.Cu")
		(net 68)
	)
	(arc
		(start 193.849408 130.005027)
		(mid 193.584243 129.895192)
		(end 193.319078 130.005027)
		(width 0.15)
		(layer "In4.Cu")
		(net 68)
	)
	(arc
		(start 194.37973 128.944357)
		(mid 194.269895 129.209522)
		(end 194.37973 129.474687)
		(width 0.15)
		(layer "In4.Cu")
		(net 68)
	)
	(arc
		(start 195.007355 130.102312)
		(mid 195.11719 130.367477)
		(end 195.007355 130.632642)
		(width 0.15)
		(layer "In4.Cu")
		(net 68)
	)
	(arc
		(start 195.440391 127.883696)
		(mid 195.330556 128.148861)
		(end 195.440391 128.414026)
		(width 0.15)
		(layer "In4.Cu")
		(net 68)
	)
	(arc
		(start 193.946695 131.693305)
		(mid 193.681529 131.80314)
		(end 193.416363 131.693305)
		(width 0.15)
		(layer "In4.Cu")
		(net 68)
	)
	(arc
		(start 194.91006 128.944357)
		(mid 194.644895 128.834522)
		(end 194.37973 128.944357)
		(width 0.15)
		(layer "In4.Cu")
		(net 68)
	)
	(arc
		(start 192.788712 131.065653)
		(mid 192.523547 130.955818)
		(end 192.258382 131.065653)
		(width 0.15)
		(layer "In4.Cu")
		(net 68)
	)
	(arc
		(start 195.007356 130.632644)
		(mid 194.74219 130.742479)
		(end 194.477024 130.632644)
		(width 0.15)
		(layer "In4.Cu")
		(net 68)
	)
	(arc
		(start 193.946694 131.162973)
		(mid 194.056529 131.428138)
		(end 193.946694 131.693303)
		(width 0.15)
		(layer "In4.Cu")
		(net 68)
	)
	(arc
		(start 195.970721 127.883696)
		(mid 195.705556 127.773861)
		(end 195.440391 127.883696)
		(width 0.15)
		(layer "In4.Cu")
		(net 68)
	)
	(arc
		(start 196.068016 129.041651)
		(mid 196.177851 129.306816)
		(end 196.068016 129.571981)
		(width 0.15)
		(layer "In4.Cu")
		(net 68)
	)
	(arc
		(start 193.319078 130.005027)
		(mid 193.209243 130.270192)
		(end 193.319078 130.535357)
		(width 0.15)
		(layer "In4.Cu")
		(net 68)
	)
	(arc
		(start 196.068017 129.571983)
		(mid 195.802851 129.681818)
		(end 195.537685 129.571983)
		(width 0.15)
		(layer "In4.Cu")
		(net 68)
	)
	(arc
		(start 197.128677 127.98099)
		(mid 197.238512 128.246155)
		(end 197.128677 128.51132)
		(width 0.15)
		(layer "In4.Cu")
		(net 68)
	)
	(arc
		(start 192.886033 132.223634)
		(mid 192.995868 132.488799)
		(end 192.886033 132.753964)
		(width 0.15)
		(layer "In4.Cu")
		(net 68)
	)
	(arc
		(start 197.561687 125.762348)
		(mid 197.451852 126.027513)
		(end 197.561687 126.292678)
		(width 0.15)
		(layer "In4.Cu")
		(net 68)
	)
	(arc
		(start 196.501052 126.823035)
		(mid 196.391217 127.0882)
		(end 196.501052 127.353365)
		(width 0.15)
		(layer "In4.Cu")
		(net 68)
	)
	(arc
		(start 198.092017 125.762348)
		(mid 197.826852 125.652513)
		(end 197.561687 125.762348)
		(width 0.15)
		(layer "In4.Cu")
		(net 68)
	)
	(segment
		(start 262.228499 146.296999)
		(end 261.376499 146.296999)
		(width 0.4)
		(layer "F.Cu")
		(net 69)
	)
	(segment
		(start 262.228499 142.199)
		(end 261.376499 142.199)
		(width 0.4)
		(layer "F.Cu")
		(net 69)
	)
	(segment
		(start 262.428499 144.27)
		(end 262.428499 142.399)
		(width 0.256)
		(layer "F.Cu")
		(net 69)
	)
	(segment
		(start 257.79 144.27)
		(end 262.428499 144.27)
		(width 0.256)
		(layer "F.Cu")
		(net 69)
	)
	(segment
		(start 262.428499 142.399)
		(end 262.228499 142.199)
		(width 0.256)
		(layer "F.Cu")
		(net 69)
	)
	(segment
		(start 257.79 144.27)
		(end 257.79 143.670001)
		(width 0.256)
		(layer "F.Cu")
		(net 69)
	)
	(segment
		(start 262.428499 146.096999)
		(end 262.428499 144.27)
		(width 0.256)
		(layer "F.Cu")
		(net 69)
	)
	(segment
		(start 262.428499 146.096999)
		(end 262.228499 146.296999)
		(width 0.256)
		(layer "F.Cu")
		(net 69)
	)
	(segment
		(start 201.0005 153.0005)
		(end 201.5 153.5)
		(width 0.256)
		(layer "F.Cu")
		(net 69)
	)
	(segment
		(start 257.79 144.901001)
		(end 257.79 144.27)
		(width 0.256)
		(layer "F.Cu")
		(net 69)
	)
	(via
		(at 262.228499 146.296999)
		(size 0.45)
		(drill 0.1)
		(layers "F.Cu" "B.Cu")
		(remove_unused_layers yes)
		(keep_end_layers yes)
		(zone_layer_connections)
		(net 69)
	)
	(via
		(at 201.5 153.5)
		(size 0.45)
		(drill 0.1)
		(layers "F.Cu" "B.Cu")
		(remove_unused_layers yes)
		(keep_end_layers yes)
		(zone_layer_connections)
		(net 69)
	)
	(segment
		(start 218.85 145.75)
		(end 231.4 145.75)
		(width 0.1)
		(layer "In2.Cu")
		(net 69)
	)
	(segment
		(start 211.0625 152.3125)
		(end 214.0875 152.3125)
		(width 0.1)
		(layer "In2.Cu")
		(net 69)
	)
	(segment
		(start 208.7 153.55)
		(end 209.825 153.55)
		(width 0.1)
		(layer "In2.Cu")
		(net 69)
	)
	(segment
		(start 251.475 138.949)
		(end 252.199 138.949)
		(width 0.1)
		(layer "In2.Cu")
		(net 69)
	)
	(segment
		(start 204.225 153.125)
		(end 204.8 153.125)
		(width 0.1)
		(layer "In2.Cu")
		(net 69)
	)
	(segment
		(start 252.199 138.949)
		(end 259.546999 146.296999)
		(width 0.1)
		(layer "In2.Cu")
		(net 69)
	)
	(segment
		(start 235.5 141.65)
		(end 246.35 141.65)
		(width 0.1)
		(layer "In2.Cu")
		(net 69)
	)
	(segment
		(start 215.2 150.15)
		(end 216.75 148.6)
		(width 0.1)
		(layer "In2.Cu")
		(net 69)
	)
	(segment
		(start 217.875 146.725)
		(end 218.85 145.75)
		(width 0.1)
		(layer "In2.Cu")
		(net 69)
	)
	(segment
		(start 214.0875 152.3125)
		(end 215.2 151.2)
		(width 0.1)
		(layer "In2.Cu")
		(net 69)
	)
	(segment
		(start 208.35 153.9)
		(end 208.7 153.55)
		(width 0.1)
		(layer "In2.Cu")
		(net 69)
	)
	(segment
		(start 216.75 148.6)
		(end 217.4 148.6)
		(width 0.1)
		(layer "In2.Cu")
		(net 69)
	)
	(segment
		(start 247.274 140.726)
		(end 249.698 140.726)
		(width 0.1)
		(layer "In2.Cu")
		(net 69)
	)
	(segment
		(start 215.2 151.2)
		(end 215.2 150.15)
		(width 0.1)
		(layer "In2.Cu")
		(net 69)
	)
	(segment
		(start 201.5 153.5)
		(end 203.85 153.5)
		(width 0.1)
		(layer "In2.Cu")
		(net 69)
	)
	(segment
		(start 231.4 145.75)
		(end 235.5 141.65)
		(width 0.1)
		(layer "In2.Cu")
		(net 69)
	)
	(segment
		(start 204.8 153.125)
		(end 205.125 153.45)
		(width 0.1)
		(layer "In2.Cu")
		(net 69)
	)
	(segment
		(start 217.875 148.125)
		(end 217.875 146.725)
		(width 0.1)
		(layer "In2.Cu")
		(net 69)
	)
	(segment
		(start 217.4 148.6)
		(end 217.875 148.125)
		(width 0.1)
		(layer "In2.Cu")
		(net 69)
	)
	(segment
		(start 205.125 153.45)
		(end 205.95 153.45)
		(width 0.1)
		(layer "In2.Cu")
		(net 69)
	)
	(segment
		(start 249.698 140.726)
		(end 251.475 138.949)
		(width 0.1)
		(layer "In2.Cu")
		(net 69)
	)
	(segment
		(start 209.825 153.55)
		(end 211.0625 152.3125)
		(width 0.1)
		(layer "In2.Cu")
		(net 69)
	)
	(segment
		(start 205.95 153.45)
		(end 206.4 153.9)
		(width 0.1)
		(layer "In2.Cu")
		(net 69)
	)
	(segment
		(start 203.85 153.5)
		(end 204.225 153.125)
		(width 0.1)
		(layer "In2.Cu")
		(net 69)
	)
	(segment
		(start 259.546999 146.296999)
		(end 262.228499 146.296999)
		(width 0.1)
		(layer "In2.Cu")
		(net 69)
	)
	(segment
		(start 246.35 141.65)
		(end 247.274 140.726)
		(width 0.1)
		(layer "In2.Cu")
		(net 69)
	)
	(segment
		(start 206.4 153.9)
		(end 208.35 153.9)
		(width 0.1)
		(layer "In2.Cu")
		(net 69)
	)
	(segment
		(start 203.2 106)
		(end 203.2 107.152)
		(width 0.38)
		(layer "F.Cu")
		(net 70)
	)
	(segment
		(start 191.0005 142.9995)
		(end 191.5 142.5)
		(width 0.256)
		(layer "F.Cu")
		(net 70)
	)
	(via
		(at 203.2 107.152)
		(size 0.45)
		(drill 0.1)
		(layers "F.Cu" "B.Cu")
		(remove_unused_layers yes)
		(keep_end_layers yes)
		(zone_layer_connections)
		(net 70)
	)
	(via
		(at 191.5 142.5)
		(size 0.45)
		(drill 0.1)
		(layers "F.Cu" "B.Cu")
		(remove_unused_layers yes)
		(keep_end_layers yes)
		(zone_layer_connections)
		(net 70)
	)
	(segment
		(start 193.147713 128.151246)
		(end 193.011486 128.015019)
		(width 0.15)
		(layer "In4.Cu")
		(net 70)
	)
	(segment
		(start 193.612484 127.413933)
		(end 193.748754 127.550203)
		(width 0.15)
		(layer "In4.Cu")
		(net 70)
	)
	(segment
		(start 191.208358 129.818136)
		(end 191.344589 129.954367)
		(width 0.15)
		(layer "In4.Cu")
		(net 70)
	)
	(segment
		(start 193.612483 126.812894)
		(end 193.612484 126.812893)
		(width 0.15)
		(layer "In4.Cu")
		(net 70)
	)
	(segment
		(start 191.344589 130.555408)
		(end 191 130.9)
		(width 0.15)
		(layer "In4.Cu")
		(net 70)
	)
	(segment
		(start 196.01668 125.009802)
		(end 196.152917 125.146039)
		(width 0.15)
		(layer "In4.Cu")
		(net 70)
	)
	(segment
		(start 197.585 124.315)
		(end 197.355 124.545)
		(width 0.15)
		(layer "In4.Cu")
		(net 70)
	)
	(segment
		(start 205 113)
		(end 205.5 112.5)
		(width 0.15)
		(layer "In4.Cu")
		(net 70)
	)
	(segment
		(start 206.1 109.9)
		(end 208.9 109.9)
		(width 0.15)
		(layer "In4.Cu")
		(net 70)
	)
	(segment
		(start 203.2 111.25)
		(end 202.57 110.62)
		(width 0.148)
		(layer "In4.Cu")
		(net 70)
	)
	(segment
		(start 192.410445 128.616059)
		(end 192.546671 128.752285)
		(width 0.15)
		(layer "In4.Cu")
		(net 70)
	)
	(segment
		(start 194.814565 125.610812)
		(end 194.814566 125.610811)
		(width 0.15)
		(layer "In4.Cu")
		(net 70)
	)
	(segment
		(start 192.546672 129.353326)
		(end 192.546671 129.353326)
		(width 0.15)
		(layer "In4.Cu")
		(net 70)
	)
	(segment
		(start 194.950835 126.949162)
		(end 194.950836 126.949161)
		(width 0.15)
		(layer "In4.Cu")
		(net 70)
	)
	(segment
		(start 209.74 115.26)
		(end 208.37 116.63)
		(width 0.15)
		(layer "In4.Cu")
		(net 70)
	)
	(segment
		(start 203.2 111.25)
		(end 203.2 112.6)
		(width 0.15)
		(layer "In4.Cu")
		(net 70)
	)
	(segment
		(start 192.410445 128.015018)
		(end 192.410445 128.015019)
		(width 0.15)
		(layer "In4.Cu")
		(net 70)
	)
	(segment
		(start 198.285 124.315)
		(end 197.585 124.315)
		(width 0.15)
		(layer "In4.Cu")
		(net 70)
	)
	(segment
		(start 196.753959 124.545)
		(end 196.617721 124.408762)
		(width 0.15)
		(layer "In4.Cu")
		(net 70)
	)
	(segment
		(start 193.147712 128.151246)
		(end 193.147713 128.151246)
		(width 0.15)
		(layer "In4.Cu")
		(net 70)
	)
	(segment
		(start 203.2 112.6)
		(end 203.6 113)
		(width 0.15)
		(layer "In4.Cu")
		(net 70)
	)
	(segment
		(start 191.208358 129.217095)
		(end 191.208358 129.217096)
		(width 0.15)
		(layer "In4.Cu")
		(net 70)
	)
	(segment
		(start 193.748753 128.151244)
		(end 193.748754 128.151243)
		(width 0.15)
		(layer "In4.Cu")
		(net 70)
	)
	(segment
		(start 203.6 113)
		(end 205 113)
		(width 0.15)
		(layer "In4.Cu")
		(net 70)
	)
	(segment
		(start 205.5 110.5)
		(end 206.1 109.9)
		(width 0.15)
		(layer "In4.Cu")
		(net 70)
	)
	(segment
		(start 196.016681 124.408762)
		(end 196.01668 124.408762)
		(width 0.15)
		(layer "In4.Cu")
		(net 70)
	)
	(segment
		(start 194.950836 126.949161)
		(end 194.950836 126.949164)
		(width 0.15)
		(layer "In4.Cu")
		(net 70)
	)
	(segment
		(start 196.152917 125.74708)
		(end 196.152918 125.747082)
		(width 0.15)
		(layer "In4.Cu")
		(net 70)
	)
	(segment
		(start 209.74 112.55)
		(end 209.74 115.26)
		(width 0.15)
		(layer "In4.Cu")
		(net 70)
	)
	(segment
		(start 202.57 107.782)
		(end 203.2 107.152)
		(width 0.148)
		(layer "In4.Cu")
		(net 70)
	)
	(segment
		(start 194.814566 126.211851)
		(end 194.950836 126.348121)
		(width 0.15)
		(layer "In4.Cu")
		(net 70)
	)
	(segment
		(start 191 130.9)
		(end 191 142)
		(width 0.15)
		(layer "In4.Cu")
		(net 70)
	)
	(segment
		(start 205.5 112.5)
		(end 205.5 110.5)
		(width 0.15)
		(layer "In4.Cu")
		(net 70)
	)
	(segment
		(start 205.97 116.63)
		(end 198.285 124.315)
		(width 0.15)
		(layer "In4.Cu")
		(net 70)
	)
	(segment
		(start 202.57 110.62)
		(end 202.57 107.782)
		(width 0.148)
		(layer "In4.Cu")
		(net 70)
	)
	(segment
		(start 209.5 112.31)
		(end 209.74 112.55)
		(width 0.15)
		(layer "In4.Cu")
		(net 70)
	)
	(segment
		(start 196.753958 124.545)
		(end 196.753959 124.545)
		(width 0.15)
		(layer "In4.Cu")
		(net 70)
	)
	(segment
		(start 196.152917 125.747079)
		(end 196.152917 125.74708)
		(width 0.15)
		(layer "In4.Cu")
		(net 70)
	)
	(segment
		(start 191.34459 130.555408)
		(end 191.344589 130.555408)
		(width 0.15)
		(layer "In4.Cu")
		(net 70)
	)
	(segment
		(start 191 142)
		(end 191.5 142.5)
		(width 0.15)
		(layer "In4.Cu")
		(net 70)
	)
	(segment
		(start 194.349795 126.949164)
		(end 194.213524 126.812893)
		(width 0.15)
		(layer "In4.Cu")
		(net 70)
	)
	(segment
		(start 195.551877 125.747082)
		(end 195.415606 125.610811)
		(width 0.15)
		(layer "In4.Cu")
		(net 70)
	)
	(segment
		(start 191.94563 129.353328)
		(end 191.945631 129.353328)
		(width 0.15)
		(layer "In4.Cu")
		(net 70)
	)
	(segment
		(start 193.748754 128.151243)
		(end 193.748754 128.151246)
		(width 0.15)
		(layer "In4.Cu")
		(net 70)
	)
	(segment
		(start 194.349794 126.949164)
		(end 194.349795 126.949164)
		(width 0.15)
		(layer "In4.Cu")
		(net 70)
	)
	(segment
		(start 192.546671 129.353326)
		(end 192.546672 129.353328)
		(width 0.15)
		(layer "In4.Cu")
		(net 70)
	)
	(segment
		(start 209.5 110.5)
		(end 209.5 112.31)
		(width 0.15)
		(layer "In4.Cu")
		(net 70)
	)
	(segment
		(start 195.551876 125.747082)
		(end 195.551877 125.747082)
		(width 0.15)
		(layer "In4.Cu")
		(net 70)
	)
	(segment
		(start 208.9 109.9)
		(end 209.5 110.5)
		(width 0.15)
		(layer "In4.Cu")
		(net 70)
	)
	(segment
		(start 191.945631 129.353328)
		(end 191.809399 129.217096)
		(width 0.15)
		(layer "In4.Cu")
		(net 70)
	)
	(segment
		(start 208.37 116.63)
		(end 205.97 116.63)
		(width 0.15)
		(layer "In4.Cu")
		(net 70)
	)
	(arc
		(start 193.011486 128.015019)
		(mid 192.710966 127.890539)
		(end 192.410445 128.015018)
		(width 0.15)
		(layer "In4.Cu")
		(net 70)
	)
	(arc
		(start 196.152917 125.146039)
		(mid 196.277396 125.446559)
		(end 196.152917 125.747079)
		(width 0.15)
		(layer "In4.Cu")
		(net 70)
	)
	(arc
		(start 192.546671 128.752285)
		(mid 192.671151 129.052805)
		(end 192.546672 129.353326)
		(width 0.15)
		(layer "In4.Cu")
		(net 70)
	)
	(arc
		(start 193.748754 128.151246)
		(mid 193.448233 128.275726)
		(end 193.147712 128.151246)
		(width 0.15)
		(layer "In4.Cu")
		(net 70)
	)
	(arc
		(start 194.950836 126.348121)
		(mid 195.075315 126.648642)
		(end 194.950835 126.949162)
		(width 0.15)
		(layer "In4.Cu")
		(net 70)
	)
	(arc
		(start 196.01668 124.408762)
		(mid 195.892201 124.709282)
		(end 196.01668 125.009802)
		(width 0.15)
		(layer "In4.Cu")
		(net 70)
	)
	(arc
		(start 193.612484 126.812893)
		(mid 193.488005 127.113413)
		(end 193.612484 127.413933)
		(width 0.15)
		(layer "In4.Cu")
		(net 70)
	)
	(arc
		(start 191.208358 129.217096)
		(mid 191.083879 129.517616)
		(end 191.208358 129.818136)
		(width 0.15)
		(layer "In4.Cu")
		(net 70)
	)
	(arc
		(start 191.344589 129.954367)
		(mid 191.469069 130.254887)
		(end 191.34459 130.555408)
		(width 0.15)
		(layer "In4.Cu")
		(net 70)
	)
	(arc
		(start 195.415606 125.610811)
		(mid 195.115085 125.486332)
		(end 194.814565 125.610812)
		(width 0.15)
		(layer "In4.Cu")
		(net 70)
	)
	(arc
		(start 192.546672 129.353328)
		(mid 192.246151 129.477808)
		(end 191.94563 129.353328)
		(width 0.15)
		(layer "In4.Cu")
		(net 70)
	)
	(arc
		(start 196.152918 125.747082)
		(mid 195.852397 125.871562)
		(end 195.551876 125.747082)
		(width 0.15)
		(layer "In4.Cu")
		(net 70)
	)
	(arc
		(start 192.410445 128.015019)
		(mid 192.285966 128.315539)
		(end 192.410445 128.616059)
		(width 0.15)
		(layer "In4.Cu")
		(net 70)
	)
	(arc
		(start 194.213524 126.812893)
		(mid 193.913003 126.688414)
		(end 193.612483 126.812894)
		(width 0.15)
		(layer "In4.Cu")
		(net 70)
	)
	(arc
		(start 191.809399 129.217096)
		(mid 191.508879 129.092616)
		(end 191.208358 129.217095)
		(width 0.15)
		(layer "In4.Cu")
		(net 70)
	)
	(arc
		(start 193.748754 127.550203)
		(mid 193.873233 127.850724)
		(end 193.748753 128.151244)
		(width 0.15)
		(layer "In4.Cu")
		(net 70)
	)
	(arc
		(start 197.355 124.545)
		(mid 197.054479 124.66948)
		(end 196.753958 124.545)
		(width 0.15)
		(layer "In4.Cu")
		(net 70)
	)
	(arc
		(start 196.617721 124.408762)
		(mid 196.317201 124.284283)
		(end 196.016681 124.408762)
		(width 0.15)
		(layer "In4.Cu")
		(net 70)
	)
	(arc
		(start 194.814566 125.610811)
		(mid 194.690087 125.911331)
		(end 194.814566 126.211851)
		(width 0.15)
		(layer "In4.Cu")
		(net 70)
	)
	(arc
		(start 194.950836 126.949164)
		(mid 194.650315 127.073644)
		(end 194.349794 126.949164)
		(width 0.15)
		(layer "In4.Cu")
		(net 70)
	)
	(segment
		(start 201.5 106)
		(end 201.5 107.152)
		(width 0.38)
		(layer "F.Cu")
		(net 71)
	)
	(segment
		(start 194.0005 145.9995)
		(end 194.5 145.5)
		(width 0.256)
		(layer "F.Cu")
		(net 71)
	)
	(via
		(at 194.5 145.5)
		(size 0.45)
		(drill 0.1)
		(layers "F.Cu" "B.Cu")
		(remove_unused_layers yes)
		(keep_end_layers yes)
		(zone_layer_connections)
		(net 71)
	)
	(via
		(at 201.5 107.152)
		(size 0.45)
		(drill 0.1)
		(layers "F.Cu" "B.Cu")
		(remove_unused_layers yes)
		(keep_end_layers yes)
		(zone_layer_connections)
		(net 71)
	)
	(segment
		(start 187.75 121.44)
		(end 192.51 116.68)
		(width 0.148)
		(layer "In4.Cu")
		(net 71)
	)
	(segment
		(start 189.95 145.385728)
		(end 189.95 145.85)
		(width 0.148)
		(layer "In4.Cu")
		(net 71)
	)
	(segment
		(start 188 143.3)
		(end 188 143.6485)
		(width 0.148)
		(layer "In4.Cu")
		(net 71)
	)
	(segment
		(start 200.1 114.19)
		(end 201.6 112.69)
		(width 0.148)
		(layer "In4.Cu")
		(net 71)
	)
	(segment
		(start 200.95 110.25)
		(end 200.95 107.702)
		(width 0.148)
		(layer "In4.Cu")
		(net 71)
	)
	(segment
		(start 192 146.8)
		(end 192 146.2)
		(width 0.15)
		(layer "In4.Cu")
		(net 71)
	)
	(segment
		(start 192.51 116.68)
		(end 192.66 116.68)
		(width 0.148)
		(layer "In4.Cu")
		(net 71)
	)
	(segment
		(start 190.7 146.05)
		(end 190.95 146.3)
		(width 0.148)
		(layer "In4.Cu")
		(net 71)
	)
	(segment
		(start 194.535 116.305)
		(end 194.535 115.36805)
		(width 0.148)
		(layer "In4.Cu")
		(net 71)
	)
	(segment
		(start 193 145.632843)
		(end 193 145.2)
		(width 0.15)
		(layer "In4.Cu")
		(net 71)
	)
	(segment
		(start 188 143.3)
		(end 188 139.05)
		(width 0.15)
		(layer "In4.Cu")
		(net 71)
	)
	(segment
		(start 188 143.6485)
		(end 188.3515 144)
		(width 0.148)
		(layer "In4.Cu")
		(net 71)
	)
	(segment
		(start 192 146.2)
		(end 192.2 146)
		(width 0.15)
		(layer "In4.Cu")
		(net 71)
	)
	(segment
		(start 195.285 115.36805)
		(end 195.285 116.305)
		(width 0.148)
		(layer "In4.Cu")
		(net 71)
	)
	(segment
		(start 189.95 145.85)
		(end 190.15 146.05)
		(width 0.148)
		(layer "In4.Cu")
		(net 71)
	)
	(segment
		(start 195.66 116.68)
		(end 195.88 116.68)
		(width 0.148)
		(layer "In4.Cu")
		(net 71)
	)
	(segment
		(start 193.035 116.305)
		(end 193.035 115.368045)
		(width 0.148)
		(layer "In4.Cu")
		(net 71)
	)
	(segment
		(start 191.175 147)
		(end 191.8 147)
		(width 0.148)
		(layer "In4.Cu")
		(net 71)
	)
	(segment
		(start 188.3515 144)
		(end 188.7 144)
		(width 0.148)
		(layer "In4.Cu")
		(net 71)
	)
	(segment
		(start 188.7 144)
		(end 189 144.3)
		(width 0.148)
		(layer "In4.Cu")
		(net 71)
	)
	(segment
		(start 189 144.8)
		(end 189.2 145)
		(width 0.148)
		(layer "In4.Cu")
		(net 71)
	)
	(segment
		(start 201.6 112.69)
		(end 201.6 110.9)
		(width 0.148)
		(layer "In4.Cu")
		(net 71)
	)
	(segment
		(start 193.2 145)
		(end 194 145)
		(width 0.15)
		(layer "In4.Cu")
		(net 71)
	)
	(segment
		(start 194 145)
		(end 194.5 145.5)
		(width 0.15)
		(layer "In4.Cu")
		(net 71)
	)
	(segment
		(start 189.2 145)
		(end 189.564272 145)
		(width 0.148)
		(layer "In4.Cu")
		(net 71)
	)
	(segment
		(start 190.15 146.05)
		(end 190.7 146.05)
		(width 0.148)
		(layer "In4.Cu")
		(net 71)
	)
	(segment
		(start 198.37 114.19)
		(end 200.1 114.19)
		(width 0.148)
		(layer "In4.Cu")
		(net 71)
	)
	(segment
		(start 192.632843 146)
		(end 193 145.632843)
		(width 0.15)
		(layer "In4.Cu")
		(net 71)
	)
	(segment
		(start 192.2 146)
		(end 192.632843 146)
		(width 0.15)
		(layer "In4.Cu")
		(net 71)
	)
	(segment
		(start 191.8 147)
		(end 192 146.8)
		(width 0.15)
		(layer "In4.Cu")
		(net 71)
	)
	(segment
		(start 200.95 107.702)
		(end 201.5 107.152)
		(width 0.148)
		(layer "In4.Cu")
		(net 71)
	)
	(segment
		(start 201.6 110.9)
		(end 200.95 110.25)
		(width 0.148)
		(layer "In4.Cu")
		(net 71)
	)
	(segment
		(start 190.95 146.775)
		(end 191.175 147)
		(width 0.148)
		(layer "In4.Cu")
		(net 71)
	)
	(segment
		(start 193.785 115.368045)
		(end 193.785 116.305)
		(width 0.148)
		(layer "In4.Cu")
		(net 71)
	)
	(segment
		(start 193 145.2)
		(end 193.2 145)
		(width 0.15)
		(layer "In4.Cu")
		(net 71)
	)
	(segment
		(start 188 139.05)
		(end 187.75 138.8)
		(width 0.15)
		(layer "In4.Cu")
		(net 71)
	)
	(segment
		(start 187.75 131.25)
		(end 187.75 121.44)
		(width 0.148)
		(layer "In4.Cu")
		(net 71)
	)
	(segment
		(start 189 144.3)
		(end 189 144.8)
		(width 0.148)
		(layer "In4.Cu")
		(net 71)
	)
	(segment
		(start 190.95 146.3)
		(end 190.95 146.775)
		(width 0.148)
		(layer "In4.Cu")
		(net 71)
	)
	(segment
		(start 187.75 138.8)
		(end 187.75 131.25)
		(width 0.15)
		(layer "In4.Cu")
		(net 71)
	)
	(segment
		(start 189.564272 145)
		(end 189.95 145.385728)
		(width 0.148)
		(layer "In4.Cu")
		(net 71)
	)
	(segment
		(start 195.88 116.68)
		(end 198.37 114.19)
		(width 0.148)
		(layer "In4.Cu")
		(net 71)
	)
	(arc
		(start 194.91 114.99305)
		(mid 195.175165 115.102885)
		(end 195.285 115.36805)
		(width 0.148)
		(layer "In4.Cu")
		(net 71)
	)
	(arc
		(start 192.66 116.68)
		(mid 192.925165 116.570165)
		(end 193.035 116.305)
		(width 0.148)
		(layer "In4.Cu")
		(net 71)
	)
	(arc
		(start 194.16 116.68)
		(mid 194.425165 116.570165)
		(end 194.535 116.305)
		(width 0.148)
		(layer "In4.Cu")
		(net 71)
	)
	(arc
		(start 194.535 115.36805)
		(mid 194.644835 115.102885)
		(end 194.91 114.99305)
		(width 0.148)
		(layer "In4.Cu")
		(net 71)
	)
	(arc
		(start 193.41 114.993045)
		(mid 193.675165 115.10288)
		(end 193.785 115.368045)
		(width 0.148)
		(layer "In4.Cu")
		(net 71)
	)
	(arc
		(start 195.285 116.305)
		(mid 195.394835 116.570165)
		(end 195.66 116.68)
		(width 0.148)
		(layer "In4.Cu")
		(net 71)
	)
	(arc
		(start 193.035 115.368045)
		(mid 193.144835 115.10288)
		(end 193.41 114.993045)
		(width 0.148)
		(layer "In4.Cu")
		(net 71)
	)
	(arc
		(start 193.785 116.305)
		(mid 193.894835 116.570165)
		(end 194.16 116.68)
		(width 0.148)
		(layer "In4.Cu")
		(net 71)
	)
	(segment
		(start 199.8 106)
		(end 199.8 107.152)
		(width 0.38)
		(layer "F.Cu")
		(net 72)
	)
	(segment
		(start 196.0005 142.9995)
		(end 196.5 142.5)
		(width 0.256)
		(layer "F.Cu")
		(net 72)
	)
	(via
		(at 199.8 107.152)
		(size 0.45)
		(drill 0.1)
		(layers "F.Cu" "B.Cu")
		(remove_unused_layers yes)
		(keep_end_layers yes)
		(zone_layer_connections)
		(net 72)
	)
	(via
		(at 196.5 142.5)
		(size 0.45)
		(drill 0.1)
		(layers "F.Cu" "B.Cu")
		(remove_unused_layers yes)
		(keep_end_layers yes)
		(zone_layer_connections)
		(net 72)
	)
	(segment
		(start 195.25 112.45)
		(end 195.860742 112.45)
		(width 0.1)
		(layer "In9.Cu")
		(net 72)
	)
	(segment
		(start 195.860742 112.95)
		(end 195.25 112.95)
		(width 0.1)
		(layer "In9.Cu")
		(net 72)
	)
	(segment
		(start 198.01 141.29)
		(end 198.01 141.74)
		(width 0.1)
		(layer "In9.Cu")
		(net 72)
	)
	(segment
		(start 198.01 141.74)
		(end 197.75 142)
		(width 0.1)
		(layer "In9.Cu")
		(net 72)
	)
	(segment
		(start 194 120.1)
		(end 194.35 120.45)
		(width 0.1)
		(layer "In9.Cu")
		(net 72)
	)
	(segment
		(start 195.9 120.45)
		(end 200.3 124.85)
		(width 0.1)
		(layer "In9.Cu")
		(net 72)
	)
	(segment
		(start 195.860742 113.95)
		(end 195.25 113.95)
		(width 0.1)
		(layer "In9.Cu")
		(net 72)
	)
	(segment
		(start 198.36 140.94)
		(end 198.01 141.29)
		(width 0.1)
		(layer "In9.Cu")
		(net 72)
	)
	(segment
		(start 197.75 142)
		(end 197.3 142)
		(width 0.1)
		(layer "In9.Cu")
		(net 72)
	)
	(segment
		(start 197.3 142)
		(end 196.8 142.5)
		(width 0.1)
		(layer "In9.Cu")
		(net 72)
	)
	(segment
		(start 195.25 114.45)
		(end 195.860742 114.45)
		(width 0.1)
		(layer "In9.Cu")
		(net 72)
	)
	(segment
		(start 195.25 113.45)
		(end 195.860742 113.45)
		(width 0.1)
		(layer "In9.Cu")
		(net 72)
	)
	(segment
		(start 195.25 106.75)
		(end 195.25 110.75)
		(width 0.1)
		(layer "In9.Cu")
		(net 72)
	)
	(segment
		(start 199.979371 106.341422)
		(end 199.97937 106.341423)
		(width 0.1)
		(layer "In9.Cu")
		(net 72)
	)
	(segment
		(start 196.925 105.875)
		(end 196.925 105.525)
		(width 0.1)
		(layer "In9.Cu")
		(net 72)
	)
	(segment
		(start 199.696527 106.624263)
		(end 199.979371 106.341422)
		(width 0.1)
		(layer "In9.Cu")
		(net 72)
	)
	(segment
		(start 197.575 105.525)
		(end 197.575 105.875)
		(width 0.1)
		(layer "In9.Cu")
		(net 72)
	)
	(segment
		(start 195.25 116.45)
		(end 195.860749 116.45)
		(width 0.1)
		(layer "In9.Cu")
		(net 72)
	)
	(segment
		(start 196.8 142.5)
		(end 196.5 142.5)
		(width 0.1)
		(layer "In9.Cu")
		(net 72)
	)
	(segment
		(start 199.01 140.75)
		(end 198.82 140.94)
		(width 0.1)
		(layer "In9.Cu")
		(net 72)
	)
	(segment
		(start 199.8 107.152)
		(end 199.696527 107.048527)
		(width 0.1)
		(layer "In9.Cu")
		(net 72)
	)
	(segment
		(start 195.8 106.2)
		(end 195.25 106.75)
		(width 0.1)
		(layer "In9.Cu")
		(net 72)
	)
	(segment
		(start 200.3 124.85)
		(end 200.3 137.375)
		(width 0.1)
		(layer "In9.Cu")
		(net 72)
	)
	(segment
		(start 195.25 110.75)
		(end 195 111)
		(width 0.1)
		(layer "In9.Cu")
		(net 72)
	)
	(segment
		(start 199.555107 105.917158)
		(end 199.272265 106.199999)
		(width 0.1)
		(layer "In9.Cu")
		(net 72)
	)
	(segment
		(start 198.82 140.94)
		(end 198.36 140.94)
		(width 0.1)
		(layer "In9.Cu")
		(net 72)
	)
	(segment
		(start 198.225 105.875)
		(end 198.225 105.525)
		(width 0.1)
		(layer "In9.Cu")
		(net 72)
	)
	(segment
		(start 196.275 105.525)
		(end 196.275 105.875)
		(width 0.1)
		(layer "In9.Cu")
		(net 72)
	)
	(segment
		(start 195.95 106.2)
		(end 195.8 106.2)
		(width 0.1)
		(layer "In9.Cu")
		(net 72)
	)
	(segment
		(start 195 117.2)
		(end 195 117.9)
		(width 0.1)
		(layer "In9.Cu")
		(net 72)
	)
	(segment
		(start 199.01 138.665)
		(end 199.01 140.75)
		(width 0.1)
		(layer "In9.Cu")
		(net 72)
	)
	(segment
		(start 194.35 120.45)
		(end 195.9 120.45)
		(width 0.1)
		(layer "In9.Cu")
		(net 72)
	)
	(segment
		(start 195.25 115.45)
		(end 195.860742 115.45)
		(width 0.1)
		(layer "In9.Cu")
		(net 72)
	)
	(segment
		(start 195.860749 116.95)
		(end 195.25 116.95)
		(width 0.1)
		(layer "In9.Cu")
		(net 72)
	)
	(segment
		(start 195 117.9)
		(end 194 118.9)
		(width 0.1)
		(layer "In9.Cu")
		(net 72)
	)
	(segment
		(start 195.860742 115.95)
		(end 195.25 115.95)
		(width 0.1)
		(layer "In9.Cu")
		(net 72)
	)
	(segment
		(start 194 118.9)
		(end 194 120.1)
		(width 0.1)
		(layer "In9.Cu")
		(net 72)
	)
	(segment
		(start 200.3 137.375)
		(end 199.01 138.665)
		(width 0.1)
		(layer "In9.Cu")
		(net 72)
	)
	(segment
		(start 195 111)
		(end 195 112.2)
		(width 0.1)
		(layer "In9.Cu")
		(net 72)
	)
	(segment
		(start 195.860742 114.95)
		(end 195.25 114.95)
		(width 0.1)
		(layer "In9.Cu")
		(net 72)
	)
	(segment
		(start 198.848 106.2)
		(end 198.55 106.2)
		(width 0.1)
		(layer "In9.Cu")
		(net 72)
	)
	(arc
		(start 198.55 106.2)
		(mid 198.32019 106.10481)
		(end 198.225 105.875)
		(width 0.1)
		(layer "In9.Cu")
		(net 72)
	)
	(arc
		(start 195 113.2)
		(mid 195.073223 113.376777)
		(end 195.25 113.45)
		(width 0.1)
		(layer "In9.Cu")
		(net 72)
	)
	(arc
		(start 196.925 105.525)
		(mid 196.82981 105.29519)
		(end 196.6 105.2)
		(width 0.1)
		(layer "In9.Cu")
		(net 72)
	)
	(arc
		(start 198.225 105.525)
		(mid 198.12981 105.29519)
		(end 197.9 105.2)
		(width 0.1)
		(layer "In9.Cu")
		(net 72)
	)
	(arc
		(start 197.25 106.2)
		(mid 197.02019 106.10481)
		(end 196.925 105.875)
		(width 0.1)
		(layer "In9.Cu")
		(net 72)
	)
	(arc
		(start 196.275 105.875)
		(mid 196.17981 106.10481)
		(end 195.95 106.2)
		(width 0.1)
		(layer "In9.Cu")
		(net 72)
	)
	(arc
		(start 199.97937 106.341423)
		(mid 200.067238 106.12929)
		(end 199.979371 105.917158)
		(width 0.1)
		(layer "In9.Cu")
		(net 72)
	)
	(arc
		(start 195.860742 115.45)
		(mid 196.037519 115.523223)
		(end 196.110742 115.7)
		(width 0.1)
		(layer "In9.Cu")
		(net 72)
	)
	(arc
		(start 196.110749 116.7)
		(mid 196.037526 116.876777)
		(end 195.860749 116.95)
		(width 0.1)
		(layer "In9.Cu")
		(net 72)
	)
	(arc
		(start 196.110742 114.7)
		(mid 196.037519 114.876777)
		(end 195.860742 114.95)
		(width 0.1)
		(layer "In9.Cu")
		(net 72)
	)
	(arc
		(start 195 112.2)
		(mid 195.073223 112.376777)
		(end 195.25 112.45)
		(width 0.1)
		(layer "In9.Cu")
		(net 72)
	)
	(arc
		(start 195.25 115.95)
		(mid 195.073223 116.023223)
		(end 195 116.2)
		(width 0.1)
		(layer "In9.Cu")
		(net 72)
	)
	(arc
		(start 199.272265 106.199999)
		(mid 199.060134 106.287869)
		(end 198.848 106.2)
		(width 0.1)
		(layer "In9.Cu")
		(net 72)
	)
	(arc
		(start 195 115.2)
		(mid 195.073223 115.376777)
		(end 195.25 115.45)
		(width 0.1)
		(layer "In9.Cu")
		(net 72)
	)
	(arc
		(start 196.110742 115.7)
		(mid 196.037519 115.876777)
		(end 195.860742 115.95)
		(width 0.1)
		(layer "In9.Cu")
		(net 72)
	)
	(arc
		(start 197.575 105.875)
		(mid 197.47981 106.10481)
		(end 197.25 106.2)
		(width 0.1)
		(layer "In9.Cu")
		(net 72)
	)
	(arc
		(start 196.110742 112.7)
		(mid 196.037519 112.876777)
		(end 195.860742 112.95)
		(width 0.1)
		(layer "In9.Cu")
		(net 72)
	)
	(arc
		(start 195.860742 112.45)
		(mid 196.037519 112.523223)
		(end 196.110742 112.7)
		(width 0.1)
		(layer "In9.Cu")
		(net 72)
	)
	(arc
		(start 195 116.2)
		(mid 195.073223 116.376777)
		(end 195.25 116.45)
		(width 0.1)
		(layer "In9.Cu")
		(net 72)
	)
	(arc
		(start 195.860742 113.45)
		(mid 196.037519 113.523223)
		(end 196.110742 113.7)
		(width 0.1)
		(layer "In9.Cu")
		(net 72)
	)
	(arc
		(start 197.9 105.2)
		(mid 197.67019 105.29519)
		(end 197.575 105.525)
		(width 0.1)
		(layer "In9.Cu")
		(net 72)
	)
	(arc
		(start 195.860749 116.45)
		(mid 196.037526 116.523223)
		(end 196.110749 116.7)
		(width 0.1)
		(layer "In9.Cu")
		(net 72)
	)
	(arc
		(start 196.110742 113.7)
		(mid 196.037519 113.876777)
		(end 195.860742 113.95)
		(width 0.1)
		(layer "In9.Cu")
		(net 72)
	)
	(arc
		(start 195.25 116.95)
		(mid 195.073223 117.023223)
		(end 195 117.2)
		(width 0.1)
		(layer "In9.Cu")
		(net 72)
	)
	(arc
		(start 195 114.2)
		(mid 195.073223 114.376777)
		(end 195.25 114.45)
		(width 0.1)
		(layer "In9.Cu")
		(net 72)
	)
	(arc
		(start 199.696527 107.048527)
		(mid 199.608659 106.836395)
		(end 199.696527 106.624263)
		(width 0.1)
		(layer "In9.Cu")
		(net 72)
	)
	(arc
		(start 195.860742 114.45)
		(mid 196.037519 114.523223)
		(end 196.110742 114.7)
		(width 0.1)
		(layer "In9.Cu")
		(net 72)
	)
	(arc
		(start 196.6 105.2)
		(mid 196.37019 105.29519)
		(end 196.275 105.525)
		(width 0.1)
		(layer "In9.Cu")
		(net 72)
	)
	(arc
		(start 195.25 114.95)
		(mid 195.073223 115.023223)
		(end 195 115.2)
		(width 0.1)
		(layer "In9.Cu")
		(net 72)
	)
	(arc
		(start 195.25 113.95)
		(mid 195.073223 114.023223)
		(end 195 114.2)
		(width 0.1)
		(layer "In9.Cu")
		(net 72)
	)
	(arc
		(start 199.979371 105.917158)
		(mid 199.767239 105.82929)
		(end 199.555107 105.917158)
		(width 0.1)
		(layer "In9.Cu")
		(net 72)
	)
	(arc
		(start 195.25 112.95)
		(mid 195.073223 113.023223)
		(end 195 113.2)
		(width 0.1)
		(layer "In9.Cu")
		(net 72)
	)
	(segment
		(start 195.0005 143.9995)
		(end 195.5 143.5)
		(width 0.256)
		(layer "F.Cu")
		(net 73)
	)
	(segment
		(start 198.1 106)
		(end 198.1 107.152)
		(width 0.38)
		(layer "F.Cu")
		(net 73)
	)
	(via
		(at 198.1 107.152)
		(size 0.45)
		(drill 0.1)
		(layers "F.Cu" "B.Cu")
		(remove_unused_layers yes)
		(keep_end_layers yes)
		(zone_layer_connections)
		(net 73)
	)
	(via
		(at 195.5 143.5)
		(size 0.45)
		(drill 0.1)
		(layers "F.Cu" "B.Cu")
		(remove_unused_layers yes)
		(keep_end_layers yes)
		(zone_layer_connections)
		(net 73)
	)
	(segment
		(start 198.81 144)
		(end 198.31 144)
		(width 0.1)
		(layer "In9.Cu")
		(net 73)
	)
	(segment
		(start 196.01 144.7)
		(end 196.01 144.35)
		(width 0.1)
		(layer "In9.Cu")
		(net 73)
	)
	(segment
		(start 202.267338 118.823039)
		(end 202.81538 118.275)
		(width 0.1)
		(layer "In9.Cu")
		(net 73)
	)
	(segment
		(start 204 124.080826)
		(end 204 137.25)
		(width 0.1)
		(layer "In9.Cu")
		(net 73)
	)
	(segment
		(start 197.726 112.726)
		(end 201.436521 116.436521)
		(width 0.1)
		(layer "In9.Cu")
		(net 73)
	)
	(segment
		(start 200.88844 117.903839)
		(end 200.888441 117.90384)
		(width 0.1)
		(layer "In9.Cu")
		(net 73)
	)
	(segment
		(start 202.09 140.69)
		(end 201.8 140.98)
		(width 0.1)
		(layer "In9.Cu")
		(net 73)
	)
	(segment
		(start 197.99 144.32)
		(end 197.99 144.69)
		(width 0.1)
		(layer "In9.Cu")
		(net 73)
	)
	(segment
		(start 204 137.25)
		(end 202.09 139.16)
		(width 0.1)
		(layer "In9.Cu")
		(net 73)
	)
	(segment
		(start 201.775 120.675)
		(end 203.525 120.675)
		(width 0.1)
		(layer "In9.Cu")
		(net 73)
	)
	(segment
		(start 199.72 143.02)
		(end 199.35 143.02)
		(width 0.1)
		(layer "In9.Cu")
		(net 73)
	)
	(segment
		(start 200 142.74)
		(end 199.72 143.02)
		(width 0.1)
		(layer "In9.Cu")
		(net 73)
	)
	(segment
		(start 201.05 141.29)
		(end 201.05 141.725)
		(width 0.1)
		(layer "In9.Cu")
		(net 73)
	)
	(segment
		(start 203.525 119.725)
		(end 201.775 119.725)
		(width 0.1)
		(layer "In9.Cu")
		(net 73)
	)
	(segment
		(start 199.35 143.02)
		(end 199.02 143.35)
		(width 0.1)
		(layer "In9.Cu")
		(net 73)
	)
	(segment
		(start 201.896141 117.355761)
		(end 201.896142 117.35576)
		(width 0.1)
		(layer "In9.Cu")
		(net 73)
	)
	(segment
		(start 200 142.34)
		(end 200 142.74)
		(width 0.1)
		(layer "In9.Cu")
		(net 73)
	)
	(segment
		(start 202.355759 117.815378)
		(end 201.80772 118.36342)
		(width 0.1)
		(layer "In9.Cu")
		(net 73)
	)
	(segment
		(start 203.041342 122.25)
		(end 203.7 122.25)
		(width 0.1)
		(layer "In9.Cu")
		(net 73)
	)
	(segment
		(start 199.02 143.79)
		(end 198.81 144)
		(width 0.1)
		(layer "In9.Cu")
		(net 73)
	)
	(segment
		(start 201.8 140.98)
		(end 201.36 140.98)
		(width 0.1)
		(layer "In9.Cu")
		(net 73)
	)
	(segment
		(start 201.80772 118.82304)
		(end 201.807719 118.823038)
		(width 0.1)
		(layer "In9.Cu")
		(net 73)
	)
	(segment
		(start 197.99 144.69)
		(end 197.68 145)
		(width 0.1)
		(layer "In9.Cu")
		(net 73)
	)
	(segment
		(start 203.7 122.85)
		(end 203.041347 122.85)
		(width 0.1)
		(layer "In9.Cu")
		(net 73)
	)
	(segment
		(start 204 121.15)
		(end 204 121.35)
		(width 0.1)
		(layer "In9.Cu")
		(net 73)
	)
	(segment
		(start 201.34806 117.903839)
		(end 201.896141 117.355761)
		(width 0.1)
		(layer "In9.Cu")
		(net 73)
	)
	(segment
		(start 200.38 141.96)
		(end 200 142.34)
		(width 0.1)
		(layer "In9.Cu")
		(net 73)
	)
	(segment
		(start 202.355761 117.355761)
		(end 202.355758 117.355759)
		(width 0.1)
		(layer "In9.Cu")
		(net 73)
	)
	(segment
		(start 199.02 143.35)
		(end 199.02 143.79)
		(width 0.1)
		(layer "In9.Cu")
		(net 73)
	)
	(segment
		(start 202.09 139.16)
		(end 202.09 140.69)
		(width 0.1)
		(layer "In9.Cu")
		(net 73)
	)
	(segment
		(start 204 123.75)
		(end 204 124.080826)
		(width 0.1)
		(layer "In9.Cu")
		(net 73)
	)
	(segment
		(start 201.05 141.725)
		(end 200.815 141.96)
		(width 0.1)
		(layer "In9.Cu")
		(net 73)
	)
	(segment
		(start 201.43652 116.89614)
		(end 200.888439 117.44422)
		(width 0.1)
		(layer "In9.Cu")
		(net 73)
	)
	(segment
		(start 197.68 145)
		(end 196.31 145)
		(width 0.1)
		(layer "In9.Cu")
		(net 73)
	)
	(segment
		(start 203.275 118.275)
		(end 204 119)
		(width 0.1)
		(layer "In9.Cu")
		(net 73)
	)
	(segment
		(start 201.80772 118.36342)
		(end 201.807719 118.363421)
		(width 0.1)
		(layer "In9.Cu")
		(net 73)
	)
	(segment
		(start 200.815 141.96)
		(end 200.38 141.96)
		(width 0.1)
		(layer "In9.Cu")
		(net 73)
	)
	(segment
		(start 204 119)
		(end 204 119.25)
		(width 0.1)
		(layer "In9.Cu")
		(net 73)
	)
	(segment
		(start 201.36 140.98)
		(end 201.05 141.29)
		(width 0.1)
		(layer "In9.Cu")
		(net 73)
	)
	(segment
		(start 202.81538 118.275)
		(end 202.815381 118.274999)
		(width 0.1)
		(layer "In9.Cu")
		(net 73)
	)
	(segment
		(start 198.1 107.152)
		(end 197.726 107.526)
		(width 0.1)
		(layer "In9.Cu")
		(net 73)
	)
	(segment
		(start 196.01 144.35)
		(end 195.5 143.84)
		(width 0.1)
		(layer "In9.Cu")
		(net 73)
	)
	(segment
		(start 203.7 121.65)
		(end 203.041342 121.65)
		(width 0.1)
		(layer "In9.Cu")
		(net 73)
	)
	(segment
		(start 197.726 107.526)
		(end 197.726 112.726)
		(width 0.1)
		(layer "In9.Cu")
		(net 73)
	)
	(segment
		(start 195.5 143.84)
		(end 195.5 143.5)
		(width 0.1)
		(layer "In9.Cu")
		(net 73)
	)
	(segment
		(start 198.31 144)
		(end 197.99 144.32)
		(width 0.1)
		(layer "In9.Cu")
		(net 73)
	)
	(segment
		(start 196.31 145)
		(end 196.01 144.7)
		(width 0.1)
		(layer "In9.Cu")
		(net 73)
	)
	(segment
		(start 203.041347 123.45)
		(end 203.7 123.45)
		(width 0.1)
		(layer "In9.Cu")
		(net 73)
	)
	(arc
		(start 201.436521 116.436521)
		(mid 201.531711 116.666331)
		(end 201.43652 116.89614)
		(width 0.1)
		(layer "In9.Cu")
		(net 73)
	)
	(arc
		(start 204 121.35)
		(mid 203.912132 121.562132)
		(end 203.7 121.65)
		(width 0.1)
		(layer "In9.Cu")
		(net 73)
	)
	(arc
		(start 201.807719 118.363421)
		(mid 201.712529 118.593231)
		(end 201.80772 118.82304)
		(width 0.1)
		(layer "In9.Cu")
		(net 73)
	)
	(arc
		(start 201.3 120.2)
		(mid 201.439124 120.535876)
		(end 201.775 120.675)
		(width 0.1)
		(layer "In9.Cu")
		(net 73)
	)
	(arc
		(start 201.896142 117.35576)
		(mid 202.125952 117.26057)
		(end 202.355761 117.355761)
		(width 0.1)
		(layer "In9.Cu")
		(net 73)
	)
	(arc
		(start 201.775 119.725)
		(mid 201.439124 119.864124)
		(end 201.3 120.2)
		(width 0.1)
		(layer "In9.Cu")
		(net 73)
	)
	(arc
		(start 201.807719 118.823038)
		(mid 202.037528 118.918229)
		(end 202.267338 118.823039)
		(width 0.1)
		(layer "In9.Cu")
		(net 73)
	)
	(arc
		(start 203.041347 122.85)
		(mid 202.829215 122.937868)
		(end 202.741347 123.15)
		(width 0.1)
		(layer "In9.Cu")
		(net 73)
	)
	(arc
		(start 202.741347 123.15)
		(mid 202.829215 123.362132)
		(end 203.041347 123.45)
		(width 0.1)
		(layer "In9.Cu")
		(net 73)
	)
	(arc
		(start 200.888439 117.44422)
		(mid 200.793249 117.67403)
		(end 200.88844 117.903839)
		(width 0.1)
		(layer "In9.Cu")
		(net 73)
	)
	(arc
		(start 204 122.55)
		(mid 203.912132 122.762132)
		(end 203.7 122.85)
		(width 0.1)
		(layer "In9.Cu")
		(net 73)
	)
	(arc
		(start 203.7 123.45)
		(mid 203.912132 123.537868)
		(end 204 123.75)
		(width 0.1)
		(layer "In9.Cu")
		(net 73)
	)
	(arc
		(start 202.355758 117.355759)
		(mid 202.450949 117.585568)
		(end 202.355759 117.815378)
		(width 0.1)
		(layer "In9.Cu")
		(net 73)
	)
	(arc
		(start 204 119.25)
		(mid 203.860876 119.585876)
		(end 203.525 119.725)
		(width 0.1)
		(layer "In9.Cu")
		(net 73)
	)
	(arc
		(start 203.7 122.25)
		(mid 203.912132 122.337868)
		(end 204 122.55)
		(width 0.1)
		(layer "In9.Cu")
		(net 73)
	)
	(arc
		(start 202.741342 121.95)
		(mid 202.82921 122.162132)
		(end 203.041342 122.25)
		(width 0.1)
		(layer "In9.Cu")
		(net 73)
	)
	(arc
		(start 202.815381 118.274999)
		(mid 203.045191 118.179809)
		(end 203.275 118.275)
		(width 0.1)
		(layer "In9.Cu")
		(net 73)
	)
	(arc
		(start 200.888441 117.90384)
		(mid 201.118251 117.99903)
		(end 201.34806 117.903839)
		(width 0.1)
		(layer "In9.Cu")
		(net 73)
	)
	(arc
		(start 203.525 120.675)
		(mid 203.860876 120.814124)
		(end 204 121.15)
		(width 0.1)
		(layer "In9.Cu")
		(net 73)
	)
	(arc
		(start 203.041342 121.65)
		(mid 202.82921 121.737868)
		(end 202.741342 121.95)
		(width 0.1)
		(layer "In9.Cu")
		(net 73)
	)
	(segment
		(start 196.4 106)
		(end 196.4 107.152)
		(width 0.38)
		(layer "F.Cu")
		(net 74)
	)
	(segment
		(start 194.0005 142.999499)
		(end 194.499999 142.5)
		(width 0.256)
		(layer "F.Cu")
		(net 74)
	)
	(via
		(at 194.499999 142.5)
		(size 0.45)
		(drill 0.1)
		(layers "F.Cu" "B.Cu")
		(remove_unused_layers yes)
		(keep_end_layers yes)
		(zone_layer_connections)
		(net 74)
	)
	(via
		(at 196.4 107.152)
		(size 0.45)
		(drill 0.1)
		(layers "F.Cu" "B.Cu")
		(remove_unused_layers yes)
		(keep_end_layers yes)
		(zone_layer_connections)
		(net 74)
	)
	(segment
		(start 201.05 137.95)
		(end 201.05 137.65)
		(width 0.1)
		(layer "In9.Cu")
		(net 74)
	)
	(segment
		(start 196.8 120.3)
		(end 196.8 119.95)
		(width 0.1)
		(layer "In9.Cu")
		(net 74)
	)
	(segment
		(start 199.31 140.99)
		(end 199.79 140.99)
		(width 0.1)
		(layer "In9.Cu")
		(net 74)
	)
	(segment
		(start 201.689452 129.025)
		(end 201.425 129.025)
		(width 0.1)
		(layer "In9.Cu")
		(net 74)
	)
	(segment
		(start 200.03 138.97)
		(end 201.05 137.95)
		(width 0.1)
		(layer "In9.Cu")
		(net 74)
	)
	(segment
		(start 201.05 124.55)
		(end 196.8 120.3)
		(width 0.1)
		(layer "In9.Cu")
		(net 74)
	)
	(segment
		(start 201.425 135.775)
		(end 201.68945 135.775)
		(width 0.1)
		(layer "In9.Cu")
		(net 74)
	)
	(segment
		(start 201.425 128.275)
		(end 201.68945 128.275)
		(width 0.1)
		(layer "In9.Cu")
		(net 74)
	)
	(segment
		(start 201.68945 130.525)
		(end 201.425 130.525)
		(width 0.1)
		(layer "In9.Cu")
		(net 74)
	)
	(segment
		(start 201.425 131.275)
		(end 201.68945 131.275)
		(width 0.1)
		(layer "In9.Cu")
		(net 74)
	)
	(segment
		(start 195.75 142.05)
		(end 196 142.3)
		(width 0.1)
		(layer "In9.Cu")
		(net 74)
	)
	(segment
		(start 199 141.77)
		(end 199 141.3)
		(width 0.1)
		(layer "In9.Cu")
		(net 74)
	)
	(segment
		(start 196.8 118.85)
		(end 196.8 118.7)
		(width 0.1)
		(layer "In9.Cu")
		(net 74)
	)
	(segment
		(start 196 142.7)
		(end 196.29 142.99)
		(width 0.1)
		(layer "In9.Cu")
		(net 74)
	)
	(segment
		(start 196.8 107.552)
		(end 196.4 107.152)
		(width 0.1)
		(layer "In9.Cu")
		(net 74)
	)
	(segment
		(start 196.8 117.2)
		(end 196.8 107.552)
		(width 0.1)
		(layer "In9.Cu")
		(net 74)
	)
	(segment
		(start 201.05 125.65)
		(end 201.05 124.85)
		(width 0.1)
		(layer "In9.Cu")
		(net 74)
	)
	(segment
		(start 198.01 142.67)
		(end 198.01 142.25)
		(width 0.1)
		(layer "In9.Cu")
		(net 74)
	)
	(segment
		(start 201.05 124.85)
		(end 201.05 124.55)
		(width 0.1)
		(layer "In9.Cu")
		(net 74)
	)
	(segment
		(start 199.79 140.99)
		(end 200.03 140.75)
		(width 0.1)
		(layer "In9.Cu")
		(net 74)
	)
	(segment
		(start 200.03 140.75)
		(end 200.03 138.97)
		(width 0.1)
		(layer "In9.Cu")
		(net 74)
	)
	(segment
		(start 201.425 134.275)
		(end 201.68945 134.275)
		(width 0.1)
		(layer "In9.Cu")
		(net 74)
	)
	(segment
		(start 201.425 129.775)
		(end 201.689452 129.775)
		(width 0.1)
		(layer "In9.Cu")
		(net 74)
	)
	(segment
		(start 194.8 142.5)
		(end 195.25 142.05)
		(width 0.1)
		(layer "In9.Cu")
		(net 74)
	)
	(segment
		(start 198.24 142.02)
		(end 198.75 142.02)
		(width 0.1)
		(layer "In9.Cu")
		(net 74)
	)
	(segment
		(start 198.75 142.02)
		(end 199 141.77)
		(width 0.1)
		(layer "In9.Cu")
		(net 74)
	)
	(segment
		(start 199 141.3)
		(end 199.31 140.99)
		(width 0.1)
		(layer "In9.Cu")
		(net 74)
	)
	(segment
		(start 196.425 118.325)
		(end 195.825 118.325)
		(width 0.1)
		(layer "In9.Cu")
		(net 74)
	)
	(segment
		(start 194.499999 142.5)
		(end 194.8 142.5)
		(width 0.1)
		(layer "In9.Cu")
		(net 74)
	)
	(segment
		(start 198.01 142.25)
		(end 198.24 142.02)
		(width 0.1)
		(layer "In9.Cu")
		(net 74)
	)
	(segment
		(start 196.29 142.99)
		(end 197.69 142.99)
		(width 0.1)
		(layer "In9.Cu")
		(net 74)
	)
	(segment
		(start 195.825 117.575)
		(end 196.425 117.575)
		(width 0.1)
		(layer "In9.Cu")
		(net 74)
	)
	(segment
		(start 201.689454 126.025)
		(end 201.425 126.025)
		(width 0.1)
		(layer "In9.Cu")
		(net 74)
	)
	(segment
		(start 201.68945 127.525)
		(end 201.425 127.525)
		(width 0.1)
		(layer "In9.Cu")
		(net 74)
	)
	(segment
		(start 201.68945 133.525)
		(end 201.425 133.525)
		(width 0.1)
		(layer "In9.Cu")
		(net 74)
	)
	(segment
		(start 201.689451 132.025)
		(end 201.425 132.025)
		(width 0.1)
		(layer "In9.Cu")
		(net 74)
	)
	(segment
		(start 196.525 119.675)
		(end 194.675 119.675)
		(width 0.1)
		(layer "In9.Cu")
		(net 74)
	)
	(segment
		(start 197.69 142.99)
		(end 198.01 142.67)
		(width 0.1)
		(layer "In9.Cu")
		(net 74)
	)
	(segment
		(start 201.425 126.775)
		(end 201.689454 126.775)
		(width 0.1)
		(layer "In9.Cu")
		(net 74)
	)
	(segment
		(start 195.25 142.05)
		(end 195.75 142.05)
		(width 0.1)
		(layer "In9.Cu")
		(net 74)
	)
	(segment
		(start 201.425 132.775)
		(end 201.689451 132.775)
		(width 0.1)
		(layer "In9.Cu")
		(net 74)
	)
	(segment
		(start 201.68945 136.525)
		(end 201.425 136.525)
		(width 0.1)
		(layer "In9.Cu")
		(net 74)
	)
	(segment
		(start 201.425 137.275)
		(end 201.68945 137.275)
		(width 0.1)
		(layer "In9.Cu")
		(net 74)
	)
	(segment
		(start 194.675 119.125)
		(end 196.525 119.125)
		(width 0.1)
		(layer "In9.Cu")
		(net 74)
	)
	(segment
		(start 196 142.3)
		(end 196 142.7)
		(width 0.1)
		(layer "In9.Cu")
		(net 74)
	)
	(segment
		(start 201.68945 135.025)
		(end 201.425 135.025)
		(width 0.1)
		(layer "In9.Cu")
		(net 74)
	)
	(arc
		(start 201.689454 126.775)
		(mid 201.954619 126.665165)
		(end 202.064454 126.4)
		(width 0.1)
		(layer "In9.Cu")
		(net 74)
	)
	(arc
		(start 201.05 136.15)
		(mid 201.159835 135.884835)
		(end 201.425 135.775)
		(width 0.1)
		(layer "In9.Cu")
		(net 74)
	)
	(arc
		(start 201.05 133.15)
		(mid 201.159835 132.884835)
		(end 201.425 132.775)
		(width 0.1)
		(layer "In9.Cu")
		(net 74)
	)
	(arc
		(start 201.05 131.65)
		(mid 201.159835 131.384835)
		(end 201.425 131.275)
		(width 0.1)
		(layer "In9.Cu")
		(net 74)
	)
	(arc
		(start 201.68945 131.275)
		(mid 201.954615 131.165165)
		(end 202.06445 130.9)
		(width 0.1)
		(layer "In9.Cu")
		(net 74)
	)
	(arc
		(start 202.06445 135.4)
		(mid 201.954615 135.134835)
		(end 201.68945 135.025)
		(width 0.1)
		(layer "In9.Cu")
		(net 74)
	)
	(arc
		(start 201.689451 132.775)
		(mid 201.954616 132.665165)
		(end 202.064451 132.4)
		(width 0.1)
		(layer "In9.Cu")
		(net 74)
	)
	(arc
		(start 194.4 119.4)
		(mid 194.480546 119.205546)
		(end 194.675 119.125)
		(width 0.1)
		(layer "In9.Cu")
		(net 74)
	)
	(arc
		(start 201.68945 134.275)
		(mid 201.954615 134.165165)
		(end 202.06445 133.9)
		(width 0.1)
		(layer "In9.Cu")
		(net 74)
	)
	(arc
		(start 201.05 128.65)
		(mid 201.159835 128.384835)
		(end 201.425 128.275)
		(width 0.1)
		(layer "In9.Cu")
		(net 74)
	)
	(arc
		(start 195.825 118.325)
		(mid 195.559835 118.215165)
		(end 195.45 117.95)
		(width 0.1)
		(layer "In9.Cu")
		(net 74)
	)
	(arc
		(start 196.8 118.7)
		(mid 196.690165 118.434835)
		(end 196.425 118.325)
		(width 0.1)
		(layer "In9.Cu")
		(net 74)
	)
	(arc
		(start 201.425 130.525)
		(mid 201.159835 130.415165)
		(end 201.05 130.15)
		(width 0.1)
		(layer "In9.Cu")
		(net 74)
	)
	(arc
		(start 202.06445 136.9)
		(mid 201.954615 136.634835)
		(end 201.68945 136.525)
		(width 0.1)
		(layer "In9.Cu")
		(net 74)
	)
	(arc
		(start 201.68945 137.275)
		(mid 201.954615 137.165165)
		(end 202.06445 136.9)
		(width 0.1)
		(layer "In9.Cu")
		(net 74)
	)
	(arc
		(start 201.425 126.025)
		(mid 201.159835 125.915165)
		(end 201.05 125.65)
		(width 0.1)
		(layer "In9.Cu")
		(net 74)
	)
	(arc
		(start 201.425 127.525)
		(mid 201.159835 127.415165)
		(end 201.05 127.15)
		(width 0.1)
		(layer "In9.Cu")
		(net 74)
	)
	(arc
		(start 196.525 119.125)
		(mid 196.719454 119.044454)
		(end 196.8 118.85)
		(width 0.1)
		(layer "In9.Cu")
		(net 74)
	)
	(arc
		(start 201.425 135.025)
		(mid 201.159835 134.915165)
		(end 201.05 134.65)
		(width 0.1)
		(layer "In9.Cu")
		(net 74)
	)
	(arc
		(start 202.06445 127.9)
		(mid 201.954615 127.634835)
		(end 201.68945 127.525)
		(width 0.1)
		(layer "In9.Cu")
		(net 74)
	)
	(arc
		(start 194.675 119.675)
		(mid 194.480546 119.594454)
		(end 194.4 119.4)
		(width 0.1)
		(layer "In9.Cu")
		(net 74)
	)
	(arc
		(start 201.689452 129.775)
		(mid 201.954617 129.665165)
		(end 202.064452 129.4)
		(width 0.1)
		(layer "In9.Cu")
		(net 74)
	)
	(arc
		(start 196.425 117.575)
		(mid 196.690165 117.465165)
		(end 196.8 117.2)
		(width 0.1)
		(layer "In9.Cu")
		(net 74)
	)
	(arc
		(start 201.68945 128.275)
		(mid 201.954615 128.165165)
		(end 202.06445 127.9)
		(width 0.1)
		(layer "In9.Cu")
		(net 74)
	)
	(arc
		(start 196.8 119.95)
		(mid 196.719454 119.755546)
		(end 196.525 119.675)
		(width 0.1)
		(layer "In9.Cu")
		(net 74)
	)
	(arc
		(start 202.064451 132.4)
		(mid 201.954616 132.134835)
		(end 201.689451 132.025)
		(width 0.1)
		(layer "In9.Cu")
		(net 74)
	)
	(arc
		(start 201.425 132.025)
		(mid 201.159835 131.915165)
		(end 201.05 131.65)
		(width 0.1)
		(layer "In9.Cu")
		(net 74)
	)
	(arc
		(start 201.425 129.025)
		(mid 201.159835 128.915165)
		(end 201.05 128.65)
		(width 0.1)
		(layer "In9.Cu")
		(net 74)
	)
	(arc
		(start 195.45 117.95)
		(mid 195.559835 117.684835)
		(end 195.825 117.575)
		(width 0.1)
		(layer "In9.Cu")
		(net 74)
	)
	(arc
		(start 202.064454 126.4)
		(mid 201.954619 126.134835)
		(end 201.689454 126.025)
		(width 0.1)
		(layer "In9.Cu")
		(net 74)
	)
	(arc
		(start 202.06445 130.9)
		(mid 201.954615 130.634835)
		(end 201.68945 130.525)
		(width 0.1)
		(layer "In9.Cu")
		(net 74)
	)
	(arc
		(start 202.06445 133.9)
		(mid 201.954615 133.634835)
		(end 201.68945 133.525)
		(width 0.1)
		(layer "In9.Cu")
		(net 74)
	)
	(arc
		(start 202.064452 129.4)
		(mid 201.954617 129.134835)
		(end 201.689452 129.025)
		(width 0.1)
		(layer "In9.Cu")
		(net 74)
	)
	(arc
		(start 201.425 136.525)
		(mid 201.159835 136.415165)
		(end 201.05 136.15)
		(width 0.1)
		(layer "In9.Cu")
		(net 74)
	)
	(arc
		(start 201.68945 135.775)
		(mid 201.954615 135.665165)
		(end 202.06445 135.4)
		(width 0.1)
		(layer "In9.Cu")
		(net 74)
	)
	(arc
		(start 201.05 130.15)
		(mid 201.159835 129.884835)
		(end 201.425 129.775)
		(width 0.1)
		(layer "In9.Cu")
		(net 74)
	)
	(arc
		(start 201.05 134.65)
		(mid 201.159835 134.384835)
		(end 201.425 134.275)
		(width 0.1)
		(layer "In9.Cu")
		(net 74)
	)
	(arc
		(start 201.425 133.525)
		(mid 201.159835 133.415165)
		(end 201.05 133.15)
		(width 0.1)
		(layer "In9.Cu")
		(net 74)
	)
	(arc
		(start 201.05 137.65)
		(mid 201.159835 137.384835)
		(end 201.425 137.275)
		(width 0.1)
		(layer "In9.Cu")
		(net 74)
	)
	(arc
		(start 201.05 127.15)
		(mid 201.159835 126.884835)
		(end 201.425 126.775)
		(width 0.1)
		(layer "In9.Cu")
		(net 74)
	)
	(segment
		(start 194.7 106)
		(end 194.7 107.152)
		(width 0.38)
		(layer "F.Cu")
		(net 75)
	)
	(segment
		(start 196.0005 141.9995)
		(end 196.5 141.5)
		(width 0.256)
		(layer "F.Cu")
		(net 75)
	)
	(via
		(at 194.7 107.152)
		(size 0.45)
		(drill 0.1)
		(layers "F.Cu" "B.Cu")
		(remove_unused_layers yes)
		(keep_end_layers yes)
		(zone_layer_connections)
		(net 75)
	)
	(via
		(at 196.5 141.5)
		(size 0.45)
		(drill 0.1)
		(layers "F.Cu" "B.Cu")
		(remove_unused_layers yes)
		(keep_end_layers yes)
		(zone_layer_connections)
		(net 75)
	)
	(segment
		(start 194.7 105.7)
		(end 194.5 105.5)
		(width 0.1)
		(layer "In9.Cu")
		(net 75)
	)
	(segment
		(start 199.075 129.25)
		(end 199.404454 129.25)
		(width 0.1)
		(layer "In9.Cu")
		(net 75)
	)
	(segment
		(start 199.075 127.95)
		(end 199.404454 127.95)
		(width 0.1)
		(layer "In9.Cu")
		(net 75)
	)
	(segment
		(start 199.075 134.45)
		(end 199.404481 134.45)
		(width 0.1)
		(layer "In9.Cu")
		(net 75)
	)
	(segment
		(start 193.85 105.5)
		(end 193.65 105.7)
		(width 0.1)
		(layer "In9.Cu")
		(net 75)
	)
	(segment
		(start 193.65 107.02225)
		(end 193.65 107.55)
		(width 0.1)
		(layer "In9.Cu")
		(net 75)
	)
	(segment
		(start 194.1 117.85)
		(end 193.65 117.85)
		(width 0.1)
		(layer "In9.Cu")
		(net 75)
	)
	(segment
		(start 199.075 131.85)
		(end 199.404481 131.85)
		(width 0.1)
		(layer "In9.Cu")
		(net 75)
	)
	(segment
		(start 199.075 133.15)
		(end 199.404454 133.15)
		(width 0.1)
		(layer "In9.Cu")
		(net 75)
	)
	(segment
		(start 199.075 125.35)
		(end 199.404454 125.35)
		(width 0.1)
		(layer "In9.Cu")
		(net 75)
	)
	(segment
		(start 198 138.4)
		(end 198 140.8)
		(width 0.1)
		(layer "In9.Cu")
		(net 75)
	)
	(segment
		(start 198 140.8)
		(end 197.8 141)
		(width 0.1)
		(layer "In9.Cu")
		(net 75)
	)
	(segment
		(start 194.375 108.675)
		(end 194.025 108.675)
		(width 0.1)
		(layer "In9.Cu")
		(net 75)
	)
	(segment
		(start 194.45 117.5)
		(end 194.1 117.85)
		(width 0.1)
		(layer "In9.Cu")
		(net 75)
	)
	(segment
		(start 199.404467 131.2)
		(end 199.075 131.2)
		(width 0.1)
		(layer "In9.Cu")
		(net 75)
	)
	(segment
		(start 194.072251 106.37225)
		(end 194.072251 106.6)
		(width 0.1)
		(layer "In9.Cu")
		(net 75)
	)
	(segment
		(start 199.404454 129.9)
		(end 199.075 129.9)
		(width 0.1)
		(layer "In9.Cu")
		(net 75)
	)
	(segment
		(start 199.404454 126)
		(end 199.075 126)
		(width 0.1)
		(layer "In9.Cu")
		(net 75)
	)
	(segment
		(start 198.75 137.65)
		(end 198 138.4)
		(width 0.1)
		(layer "In9.Cu")
		(net 75)
	)
	(segment
		(start 193.861125 106.161125)
		(end 193.861126 106.161125)
		(width 0.1)
		(layer "In9.Cu")
		(net 75)
	)
	(segment
		(start 199.075 126.65)
		(end 199.404454 126.65)
		(width 0.1)
		(layer "In9.Cu")
		(net 75)
	)
	(segment
		(start 193.45 118.05)
		(end 193.45 120.6)
		(width 0.1)
		(layer "In9.Cu")
		(net 75)
	)
	(segment
		(start 199.404454 128.6)
		(end 199.075 128.6)
		(width 0.1)
		(layer "In9.Cu")
		(net 75)
	)
	(segment
		(start 194.5 105.5)
		(end 193.85 105.5)
		(width 0.1)
		(layer "In9.Cu")
		(net 75)
	)
	(segment
		(start 193.45 120.6)
		(end 193.85 121)
		(width 0.1)
		(layer "In9.Cu")
		(net 75)
	)
	(segment
		(start 193.65 110)
		(end 194.45 110.8)
		(width 0.1)
		(layer "In9.Cu")
		(net 75)
	)
	(segment
		(start 193.65 117.85)
		(end 193.45 118.05)
		(width 0.1)
		(layer "In9.Cu")
		(net 75)
	)
	(segment
		(start 193.861126 106.811125)
		(end 193.861125 106.811125)
		(width 0.1)
		(layer "In9.Cu")
		(net 75)
	)
	(segment
		(start 199.404454 133.8)
		(end 199.075 133.8)
		(width 0.1)
		(layer "In9.Cu")
		(net 75)
	)
	(segment
		(start 198.75 136.725)
		(end 198.75 137.65)
		(width 0.1)
		(layer "In9.Cu")
		(net 75)
	)
	(segment
		(start 194.025 107.925)
		(end 194.375 107.925)
		(width 0.1)
		(layer "In9.Cu")
		(net 75)
	)
	(segment
		(start 199.075 135.75)
		(end 199.404454 135.75)
		(width 0.1)
		(layer "In9.Cu")
		(net 75)
	)
	(segment
		(start 199.404454 136.4)
		(end 199.075 136.4)
		(width 0.1)
		(layer "In9.Cu")
		(net 75)
	)
	(segment
		(start 194.45 110.8)
		(end 194.45 114.7)
		(width 0.1)
		(layer "In9.Cu")
		(net 75)
	)
	(segment
		(start 194.45 116.1)
		(end 194.45 117.5)
		(width 0.1)
		(layer "In9.Cu")
		(net 75)
	)
	(segment
		(start 197 141)
		(end 196.5 141.5)
		(width 0.1)
		(layer "In9.Cu")
		(net 75)
	)
	(segment
		(start 195.35 121)
		(end 198.75 124.4)
		(width 0.1)
		(layer "In9.Cu")
		(net 75)
	)
	(segment
		(start 193.8 115.35)
		(end 193.8 115.45)
		(width 0.1)
		(layer "In9.Cu")
		(net 75)
	)
	(segment
		(start 193.65 105.7)
		(end 193.65 105.95)
		(width 0.1)
		(layer "In9.Cu")
		(net 75)
	)
	(segment
		(start 199.075 130.55)
		(end 199.404467 130.55)
		(width 0.1)
		(layer "In9.Cu")
		(net 75)
	)
	(segment
		(start 198.75 124.4)
		(end 198.75 125.025)
		(width 0.1)
		(layer "In9.Cu")
		(net 75)
	)
	(segment
		(start 197.8 141)
		(end 197 141)
		(width 0.1)
		(layer "In9.Cu")
		(net 75)
	)
	(segment
		(start 199.404481 135.1)
		(end 199.075 135.1)
		(width 0.1)
		(layer "In9.Cu")
		(net 75)
	)
	(segment
		(start 199.404454 127.3)
		(end 199.075 127.3)
		(width 0.1)
		(layer "In9.Cu")
		(net 75)
	)
	(segment
		(start 193.85 121)
		(end 195.35 121)
		(width 0.1)
		(layer "In9.Cu")
		(net 75)
	)
	(segment
		(start 199.404481 132.5)
		(end 199.075 132.5)
		(width 0.1)
		(layer "In9.Cu")
		(net 75)
	)
	(segment
		(start 194.7 107.152)
		(end 194.7 105.7)
		(width 0.1)
		(layer "In9.Cu")
		(net 75)
	)
	(segment
		(start 193.65 109.05)
		(end 193.65 110)
		(width 0.1)
		(layer "In9.Cu")
		(net 75)
	)
	(arc
		(start 198.75 132.825)
		(mid 198.84519 133.05481)
		(end 199.075 133.15)
		(width 0.1)
		(layer "In9.Cu")
		(net 75)
	)
	(arc
		(start 193.861125 106.811125)
		(mid 193.711837 106.872962)
		(end 193.65 107.02225)
		(width 0.1)
		(layer "In9.Cu")
		(net 75)
	)
	(arc
		(start 199.404454 133.15)
		(mid 199.634264 133.24519)
		(end 199.729454 133.475)
		(width 0.1)
		(layer "In9.Cu")
		(net 75)
	)
	(arc
		(start 199.075 132.5)
		(mid 198.84519 132.59519)
		(end 198.75 132.825)
		(width 0.1)
		(layer "In9.Cu")
		(net 75)
	)
	(arc
		(start 198.75 131.525)
		(mid 198.84519 131.75481)
		(end 199.075 131.85)
		(width 0.1)
		(layer "In9.Cu")
		(net 75)
	)
	(arc
		(start 199.075 133.8)
		(mid 198.84519 133.89519)
		(end 198.75 134.125)
		(width 0.1)
		(layer "In9.Cu")
		(net 75)
	)
	(arc
		(start 199.075 127.3)
		(mid 198.84519 127.39519)
		(end 198.75 127.625)
		(width 0.1)
		(layer "In9.Cu")
		(net 75)
	)
	(arc
		(start 199.729454 136.075)
		(mid 199.634264 136.30481)
		(end 199.404454 136.4)
		(width 0.1)
		(layer "In9.Cu")
		(net 75)
	)
	(arc
		(start 199.729454 126.975)
		(mid 199.634264 127.20481)
		(end 199.404454 127.3)
		(width 0.1)
		(layer "In9.Cu")
		(net 75)
	)
	(arc
		(start 194.75 108.3)
		(mid 194.640165 108.565165)
		(end 194.375 108.675)
		(width 0.1)
		(layer "In9.Cu")
		(net 75)
	)
	(arc
		(start 194.072251 106.6)
		(mid 194.010414 106.749288)
		(end 193.861126 106.811125)
		(width 0.1)
		(layer "In9.Cu")
		(net 75)
	)
	(arc
		(start 193.65 105.95)
		(mid 193.711837 106.099288)
		(end 193.861125 106.161125)
		(width 0.1)
		(layer "In9.Cu")
		(net 75)
	)
	(arc
		(start 199.075 128.6)
		(mid 198.84519 128.69519)
		(end 198.75 128.925)
		(width 0.1)
		(layer "In9.Cu")
		(net 75)
	)
	(arc
		(start 199.075 136.4)
		(mid 198.84519 136.49519)
		(end 198.75 136.725)
		(width 0.1)
		(layer "In9.Cu")
		(net 75)
	)
	(arc
		(start 194.125 115.775)
		(mid 194.35481 115.87019)
		(end 194.45 116.1)
		(width 0.1)
		(layer "In9.Cu")
		(net 75)
	)
	(arc
		(start 199.404481 131.85)
		(mid 199.634291 131.94519)
		(end 199.729481 132.175)
		(width 0.1)
		(layer "In9.Cu")
		(net 75)
	)
	(arc
		(start 199.729454 128.275)
		(mid 199.634264 128.50481)
		(end 199.404454 128.6)
		(width 0.1)
		(layer "In9.Cu")
		(net 75)
	)
	(arc
		(start 198.75 135.425)
		(mid 198.84519 135.65481)
		(end 199.075 135.75)
		(width 0.1)
		(layer "In9.Cu")
		(net 75)
	)
	(arc
		(start 193.861126 106.161125)
		(mid 194.010414 106.222962)
		(end 194.072251 106.37225)
		(width 0.1)
		(layer "In9.Cu")
		(net 75)
	)
	(arc
		(start 199.075 131.2)
		(mid 198.84519 131.29519)
		(end 198.75 131.525)
		(width 0.1)
		(layer "In9.Cu")
		(net 75)
	)
	(arc
		(start 199.729481 134.775)
		(mid 199.634291 135.00481)
		(end 199.404481 135.1)
		(width 0.1)
		(layer "In9.Cu")
		(net 75)
	)
	(arc
		(start 199.729467 130.875)
		(mid 199.634277 131.10481)
		(end 199.404467 131.2)
		(width 0.1)
		(layer "In9.Cu")
		(net 75)
	)
	(arc
		(start 199.729454 125.675)
		(mid 199.634264 125.90481)
		(end 199.404454 126)
		(width 0.1)
		(layer "In9.Cu")
		(net 75)
	)
	(arc
		(start 199.404454 127.95)
		(mid 199.634264 128.04519)
		(end 199.729454 128.275)
		(width 0.1)
		(layer "In9.Cu")
		(net 75)
	)
	(arc
		(start 199.729454 133.475)
		(mid 199.634264 133.70481)
		(end 199.404454 133.8)
		(width 0.1)
		(layer "In9.Cu")
		(net 75)
	)
	(arc
		(start 198.75 125.025)
		(mid 198.84519 125.25481)
		(end 199.075 125.35)
		(width 0.1)
		(layer "In9.Cu")
		(net 75)
	)
	(arc
		(start 194.45 114.7)
		(mid 194.35481 114.92981)
		(end 194.125 115.025)
		(width 0.1)
		(layer "In9.Cu")
		(net 75)
	)
	(arc
		(start 199.075 129.9)
		(mid 198.84519 129.99519)
		(end 198.75 130.225)
		(width 0.1)
		(layer "In9.Cu")
		(net 75)
	)
	(arc
		(start 198.75 134.125)
		(mid 198.84519 134.35481)
		(end 199.075 134.45)
		(width 0.1)
		(layer "In9.Cu")
		(net 75)
	)
	(arc
		(start 193.8 115.45)
		(mid 193.89519 115.67981)
		(end 194.125 115.775)
		(width 0.1)
		(layer "In9.Cu")
		(net 75)
	)
	(arc
		(start 193.65 107.55)
		(mid 193.759835 107.815165)
		(end 194.025 107.925)
		(width 0.1)
		(layer "In9.Cu")
		(net 75)
	)
	(arc
		(start 198.75 130.225)
		(mid 198.84519 130.45481)
		(end 199.075 130.55)
		(width 0.1)
		(layer "In9.Cu")
		(net 75)
	)
	(arc
		(start 199.729454 129.575)
		(mid 199.634264 129.80481)
		(end 199.404454 129.9)
		(width 0.1)
		(layer "In9.Cu")
		(net 75)
	)
	(arc
		(start 199.075 126)
		(mid 198.84519 126.09519)
		(end 198.75 126.325)
		(width 0.1)
		(layer "In9.Cu")
		(net 75)
	)
	(arc
		(start 199.729481 132.175)
		(mid 199.634291 132.40481)
		(end 199.404481 132.5)
		(width 0.1)
		(layer "In9.Cu")
		(net 75)
	)
	(arc
		(start 198.75 127.625)
		(mid 198.84519 127.85481)
		(end 199.075 127.95)
		(width 0.1)
		(layer "In9.Cu")
		(net 75)
	)
	(arc
		(start 198.75 128.925)
		(mid 198.84519 129.15481)
		(end 199.075 129.25)
		(width 0.1)
		(layer "In9.Cu")
		(net 75)
	)
	(arc
		(start 199.404454 125.35)
		(mid 199.634264 125.44519)
		(end 199.729454 125.675)
		(width 0.1)
		(layer "In9.Cu")
		(net 75)
	)
	(arc
		(start 199.404454 129.25)
		(mid 199.634264 129.34519)
		(end 199.729454 129.575)
		(width 0.1)
		(layer "In9.Cu")
		(net 75)
	)
	(arc
		(start 199.404454 135.75)
		(mid 199.634264 135.84519)
		(end 199.729454 136.075)
		(width 0.1)
		(layer "In9.Cu")
		(net 75)
	)
	(arc
		(start 194.025 108.675)
		(mid 193.759835 108.784835)
		(end 193.65 109.05)
		(width 0.1)
		(layer "In9.Cu")
		(net 75)
	)
	(arc
		(start 199.404481 134.45)
		(mid 199.634291 134.54519)
		(end 199.729481 134.775)
		(width 0.1)
		(layer "In9.Cu")
		(net 75)
	)
	(arc
		(start 199.404467 130.55)
		(mid 199.634277 130.64519)
		(end 199.729467 130.875)
		(width 0.1)
		(layer "In9.Cu")
		(net 75)
	)
	(arc
		(start 199.404454 126.65)
		(mid 199.634264 126.74519)
		(end 199.729454 126.975)
		(width 0.1)
		(layer "In9.Cu")
		(net 75)
	)
	(arc
		(start 194.125 115.025)
		(mid 193.89519 115.12019)
		(end 193.8 115.35)
		(width 0.1)
		(layer "In9.Cu")
		(net 75)
	)
	(arc
		(start 198.75 126.325)
		(mid 198.84519 126.55481)
		(end 199.075 126.65)
		(width 0.1)
		(layer "In9.Cu")
		(net 75)
	)
	(arc
		(start 199.075 135.1)
		(mid 198.84519 135.19519)
		(end 198.75 135.425)
		(width 0.1)
		(layer "In9.Cu")
		(net 75)
	)
	(arc
		(start 194.375 107.925)
		(mid 194.640165 108.034835)
		(end 194.75 108.3)
		(width 0.1)
		(layer "In9.Cu")
		(net 75)
	)
	(segment
		(start 193 106)
		(end 193 107.152)
		(width 0.38)
		(layer "F.Cu")
		(net 76)
	)
	(segment
		(start 195.0005 140.9995)
		(end 195.5 140.5)
		(width 0.256)
		(layer "F.Cu")
		(net 76)
	)
	(via
		(at 195.5 140.5)
		(size 0.45)
		(drill 0.1)
		(layers "F.Cu" "B.Cu")
		(remove_unused_layers yes)
		(keep_end_layers yes)
		(zone_layer_connections)
		(net 76)
	)
	(via
		(at 193 107.152)
		(size 0.45)
		(drill 0.1)
		(layers "F.Cu" "B.Cu")
		(remove_unused_layers yes)
		(keep_end_layers yes)
		(zone_layer_connections)
		(net 76)
	)
	(segment
		(start 191.05 121.75)
		(end 191.05 120.6)
		(width 0.1)
		(layer "In9.Cu")
		(net 76)
	)
	(segment
		(start 193 113.15)
		(end 193 110.65)
		(width 0.1)
		(layer "In9.Cu")
		(net 76)
	)
	(segment
		(start 197.278464 134.025)
		(end 196.9 134.025)
		(width 0.1)
		(layer "In9.Cu")
		(net 76)
	)
	(segment
		(start 191.05 120.6)
		(end 190.45 120)
		(width 0.1)
		(layer "In9.Cu")
		(net 76)
	)
	(segment
		(start 196.9 136.775)
		(end 197.278464 136.775)
		(width 0.1)
		(layer "In9.Cu")
		(net 76)
	)
	(segment
		(start 197 125.4)
		(end 197 124.75)
		(width 0.1)
		(layer "In9.Cu")
		(net 76)
	)
	(segment
		(start 196.9 133.475)
		(end 197.278464 133.475)
		(width 0.1)
		(layer "In9.Cu")
		(net 76)
	)
	(segment
		(start 196.9 131.275)
		(end 197.278464 131.275)
		(width 0.1)
		(layer "In9.Cu")
		(net 76)
	)
	(segment
		(start 197.278464 130.725)
		(end 196.9 130.725)
		(width 0.1)
		(layer "In9.Cu")
		(net 76)
	)
	(segment
		(start 192.05 107.6)
		(end 192.05 105.65)
		(width 0.1)
		(layer "In9.Cu")
		(net 76)
	)
	(segment
		(start 196.625 125.775)
		(end 197 125.4)
		(width 0.1)
		(layer "In9.Cu")
		(net 76)
	)
	(segment
		(start 197.278453 127.425)
		(end 196.9 127.425)
		(width 0.1)
		(layer "In9.Cu")
		(net 76)
	)
	(segment
		(start 193 110.65)
		(end 192.05 109.7)
		(width 0.1)
		(layer "In9.Cu")
		(net 76)
	)
	(segment
		(start 192.7 107.95)
		(end 192.4 107.95)
		(width 0.1)
		(layer "In9.Cu")
		(net 76)
	)
	(segment
		(start 196.625 126.05)
		(end 196.625 125.775)
		(width 0.1)
		(layer "In9.Cu")
		(net 76)
	)
	(segment
		(start 192.05 109.7)
		(end 192.05 109)
		(width 0.1)
		(layer "In9.Cu")
		(net 76)
	)
	(segment
		(start 196.625 137.375)
		(end 196.625 137.05)
		(width 0.1)
		(layer "In9.Cu")
		(net 76)
	)
	(segment
		(start 191.55 122.25)
		(end 191.05 121.75)
		(width 0.1)
		(layer "In9.Cu")
		(net 76)
	)
	(segment
		(start 196.9 132.375)
		(end 197.278464 132.375)
		(width 0.1)
		(layer "In9.Cu")
		(net 76)
	)
	(segment
		(start 197.278457 128.525)
		(end 196.9 128.525)
		(width 0.1)
		(layer "In9.Cu")
		(net 76)
	)
	(segment
		(start 197.278464 131.825)
		(end 196.9 131.825)
		(width 0.1)
		(layer "In9.Cu")
		(net 76)
	)
	(segment
		(start 196.9 127.975)
		(end 197.278453 127.975)
		(width 0.1)
		(layer "In9.Cu")
		(net 76)
	)
	(segment
		(start 197 124.75)
		(end 194.5 122.25)
		(width 0.1)
		(layer "In9.Cu")
		(net 76)
	)
	(segment
		(start 192.2 105.5)
		(end 192.85 105.5)
		(width 0.1)
		(layer "In9.Cu")
		(net 76)
	)
	(segment
		(start 196.9 130.175)
		(end 197.278457 130.175)
		(width 0.1)
		(layer "In9.Cu")
		(net 76)
	)
	(segment
		(start 192.4 108.65)
		(end 192.7 108.65)
		(width 0.1)
		(layer "In9.Cu")
		(net 76)
	)
	(segment
		(start 195.5 140.5)
		(end 196 140)
		(width 0.1)
		(layer "In9.Cu")
		(net 76)
	)
	(segment
		(start 197.278464 132.925)
		(end 196.9 132.925)
		(width 0.1)
		(layer "In9.Cu")
		(net 76)
	)
	(segment
		(start 197.27845 126.325)
		(end 196.9 126.325)
		(width 0.1)
		(layer "In9.Cu")
		(net 76)
	)
	(segment
		(start 197.278457 129.625)
		(end 196.9 129.625)
		(width 0.1)
		(layer "In9.Cu")
		(net 76)
	)
	(segment
		(start 196 138)
		(end 196.625 137.375)
		(width 0.1)
		(layer "In9.Cu")
		(net 76)
	)
	(segment
		(start 196.9 135.675)
		(end 197.278464 135.675)
		(width 0.1)
		(layer "In9.Cu")
		(net 76)
	)
	(segment
		(start 197.278464 135.125)
		(end 196.9 135.125)
		(width 0.1)
		(layer "In9.Cu")
		(net 76)
	)
	(segment
		(start 190.95 115.2)
		(end 193 113.15)
		(width 0.1)
		(layer "In9.Cu")
		(net 76)
	)
	(segment
		(start 196.9 129.075)
		(end 197.278457 129.075)
		(width 0.1)
		(layer "In9.Cu")
		(net 76)
	)
	(segment
		(start 190.45 118.85)
		(end 189.5 117.9)
		(width 0.1)
		(layer "In9.Cu")
		(net 76)
	)
	(segment
		(start 189.8 115.2)
		(end 190.95 115.2)
		(width 0.1)
		(layer "In9.Cu")
		(net 76)
	)
	(segment
		(start 189.5 115.5)
		(end 189.8 115.2)
		(width 0.1)
		(layer "In9.Cu")
		(net 76)
	)
	(segment
		(start 194.5 122.25)
		(end 191.55 122.25)
		(width 0.1)
		(layer "In9.Cu")
		(net 76)
	)
	(segment
		(start 196 140)
		(end 196 138)
		(width 0.1)
		(layer "In9.Cu")
		(net 76)
	)
	(segment
		(start 196.9 126.875)
		(end 197.27845 126.875)
		(width 0.1)
		(layer "In9.Cu")
		(net 76)
	)
	(segment
		(start 192.85 105.5)
		(end 193 105.65)
		(width 0.1)
		(layer "In9.Cu")
		(net 76)
	)
	(segment
		(start 190.45 120)
		(end 190.45 118.85)
		(width 0.1)
		(layer "In9.Cu")
		(net 76)
	)
	(segment
		(start 196.9 134.575)
		(end 197.278464 134.575)
		(width 0.1)
		(layer "In9.Cu")
		(net 76)
	)
	(segment
		(start 192.05 105.65)
		(end 192.2 105.5)
		(width 0.1)
		(layer "In9.Cu")
		(net 76)
	)
	(segment
		(start 193 105.65)
		(end 193 107.152)
		(width 0.1)
		(layer "In9.Cu")
		(net 76)
	)
	(segment
		(start 189.5 117.9)
		(end 189.5 115.5)
		(width 0.1)
		(layer "In9.Cu")
		(net 76)
	)
	(segment
		(start 197.278464 136.225)
		(end 196.9 136.225)
		(width 0.1)
		(layer "In9.Cu")
		(net 76)
	)
	(arc
		(start 196.625 127.15)
		(mid 196.705546 126.955546)
		(end 196.9 126.875)
		(width 0.1)
		(layer "In9.Cu")
		(net 76)
	)
	(arc
		(start 197.553464 134.3)
		(mid 197.472918 134.105546)
		(end 197.278464 134.025)
		(width 0.1)
		(layer "In9.Cu")
		(net 76)
	)
	(arc
		(start 196.625 131.55)
		(mid 196.705546 131.355546)
		(end 196.9 131.275)
		(width 0.1)
		(layer "In9.Cu")
		(net 76)
	)
	(arc
		(start 196.9 126.325)
		(mid 196.705546 126.244454)
		(end 196.625 126.05)
		(width 0.1)
		(layer "In9.Cu")
		(net 76)
	)
	(arc
		(start 196.625 129.35)
		(mid 196.705546 129.155546)
		(end 196.9 129.075)
		(width 0.1)
		(layer "In9.Cu")
		(net 76)
	)
	(arc
		(start 197.27845 126.875)
		(mid 197.472904 126.794454)
		(end 197.55345 126.6)
		(width 0.1)
		(layer "In9.Cu")
		(net 76)
	)
	(arc
		(start 196.9 128.525)
		(mid 196.705546 128.444454)
		(end 196.625 128.25)
		(width 0.1)
		(layer "In9.Cu")
		(net 76)
	)
	(arc
		(start 197.278464 132.375)
		(mid 197.472918 132.294454)
		(end 197.553464 132.1)
		(width 0.1)
		(layer "In9.Cu")
		(net 76)
	)
	(arc
		(start 197.553464 136.5)
		(mid 197.472918 136.305546)
		(end 197.278464 136.225)
		(width 0.1)
		(layer "In9.Cu")
		(net 76)
	)
	(arc
		(start 197.278464 134.575)
		(mid 197.472918 134.494454)
		(end 197.553464 134.3)
		(width 0.1)
		(layer "In9.Cu")
		(net 76)
	)
	(arc
		(start 196.9 129.625)
		(mid 196.705546 129.544454)
		(end 196.625 129.35)
		(width 0.1)
		(layer "In9.Cu")
		(net 76)
	)
	(arc
		(start 196.625 132.65)
		(mid 196.705546 132.455546)
		(end 196.9 132.375)
		(width 0.1)
		(layer "In9.Cu")
		(net 76)
	)
	(arc
		(start 197.553464 132.1)
		(mid 197.472918 131.905546)
		(end 197.278464 131.825)
		(width 0.1)
		(layer "In9.Cu")
		(net 76)
	)
	(arc
		(start 192.4 107.95)
		(mid 192.152513 107.847487)
		(end 192.05 107.6)
		(width 0.1)
		(layer "In9.Cu")
		(net 76)
	)
	(arc
		(start 197.553453 127.7)
		(mid 197.472907 127.505546)
		(end 197.278453 127.425)
		(width 0.1)
		(layer "In9.Cu")
		(net 76)
	)
	(arc
		(start 197.278464 136.775)
		(mid 197.472918 136.694454)
		(end 197.553464 136.5)
		(width 0.1)
		(layer "In9.Cu")
		(net 76)
	)
	(arc
		(start 197.55345 126.6)
		(mid 197.472904 126.405546)
		(end 197.27845 126.325)
		(width 0.1)
		(layer "In9.Cu")
		(net 76)
	)
	(arc
		(start 197.278457 130.175)
		(mid 197.472911 130.094454)
		(end 197.553457 129.9)
		(width 0.1)
		(layer "In9.Cu")
		(net 76)
	)
	(arc
		(start 193.05 108.3)
		(mid 192.947487 108.052513)
		(end 192.7 107.95)
		(width 0.1)
		(layer "In9.Cu")
		(net 76)
	)
	(arc
		(start 197.278464 135.675)
		(mid 197.472918 135.594454)
		(end 197.553464 135.4)
		(width 0.1)
		(layer "In9.Cu")
		(net 76)
	)
	(arc
		(start 197.278464 133.475)
		(mid 197.472918 133.394454)
		(end 197.553464 133.2)
		(width 0.1)
		(layer "In9.Cu")
		(net 76)
	)
	(arc
		(start 196.625 134.85)
		(mid 196.705546 134.655546)
		(end 196.9 134.575)
		(width 0.1)
		(layer "In9.Cu")
		(net 76)
	)
	(arc
		(start 196.625 135.95)
		(mid 196.705546 135.755546)
		(end 196.9 135.675)
		(width 0.1)
		(layer "In9.Cu")
		(net 76)
	)
	(arc
		(start 196.9 132.925)
		(mid 196.705546 132.844454)
		(end 196.625 132.65)
		(width 0.1)
		(layer "In9.Cu")
		(net 76)
	)
	(arc
		(start 196.625 130.45)
		(mid 196.705546 130.255546)
		(end 196.9 130.175)
		(width 0.1)
		(layer "In9.Cu")
		(net 76)
	)
	(arc
		(start 196.9 135.125)
		(mid 196.705546 135.044454)
		(end 196.625 134.85)
		(width 0.1)
		(layer "In9.Cu")
		(net 76)
	)
	(arc
		(start 197.553464 131)
		(mid 197.472918 130.805546)
		(end 197.278464 130.725)
		(width 0.1)
		(layer "In9.Cu")
		(net 76)
	)
	(arc
		(start 196.625 137.05)
		(mid 196.705546 136.855546)
		(end 196.9 136.775)
		(width 0.1)
		(layer "In9.Cu")
		(net 76)
	)
	(arc
		(start 196.9 127.425)
		(mid 196.705546 127.344454)
		(end 196.625 127.15)
		(width 0.1)
		(layer "In9.Cu")
		(net 76)
	)
	(arc
		(start 197.278457 129.075)
		(mid 197.472911 128.994454)
		(end 197.553457 128.8)
		(width 0.1)
		(layer "In9.Cu")
		(net 76)
	)
	(arc
		(start 197.553464 135.4)
		(mid 197.472918 135.205546)
		(end 197.278464 135.125)
		(width 0.1)
		(layer "In9.Cu")
		(net 76)
	)
	(arc
		(start 196.625 133.75)
		(mid 196.705546 133.555546)
		(end 196.9 133.475)
		(width 0.1)
		(layer "In9.Cu")
		(net 76)
	)
	(arc
		(start 197.553457 128.8)
		(mid 197.472911 128.605546)
		(end 197.278457 128.525)
		(width 0.1)
		(layer "In9.Cu")
		(net 76)
	)
	(arc
		(start 196.625 128.25)
		(mid 196.705546 128.055546)
		(end 196.9 127.975)
		(width 0.1)
		(layer "In9.Cu")
		(net 76)
	)
	(arc
		(start 197.553457 129.9)
		(mid 197.472911 129.705546)
		(end 197.278457 129.625)
		(width 0.1)
		(layer "In9.Cu")
		(net 76)
	)
	(arc
		(start 197.553464 133.2)
		(mid 197.472918 133.005546)
		(end 197.278464 132.925)
		(width 0.1)
		(layer "In9.Cu")
		(net 76)
	)
	(arc
		(start 197.278464 131.275)
		(mid 197.472918 131.194454)
		(end 197.553464 131)
		(width 0.1)
		(layer "In9.Cu")
		(net 76)
	)
	(arc
		(start 196.9 130.725)
		(mid 196.705546 130.644454)
		(end 196.625 130.45)
		(width 0.1)
		(layer "In9.Cu")
		(net 76)
	)
	(arc
		(start 196.9 136.225)
		(mid 196.705546 136.144454)
		(end 196.625 135.95)
		(width 0.1)
		(layer "In9.Cu")
		(net 76)
	)
	(arc
		(start 192.7 108.65)
		(mid 192.947487 108.547487)
		(end 193.05 108.3)
		(width 0.1)
		(layer "In9.Cu")
		(net 76)
	)
	(arc
		(start 197.278453 127.975)
		(mid 197.472907 127.894454)
		(end 197.553453 127.7)
		(width 0.1)
		(layer "In9.Cu")
		(net 76)
	)
	(arc
		(start 196.9 134.025)
		(mid 196.705546 133.944454)
		(end 196.625 133.75)
		(width 0.1)
		(layer "In9.Cu")
		(net 76)
	)
	(arc
		(start 196.9 131.825)
		(mid 196.705546 131.744454)
		(end 196.625 131.55)
		(width 0.1)
		(layer "In9.Cu")
		(net 76)
	)
	(arc
		(start 192.05 109)
		(mid 192.152513 108.752513)
		(end 192.4 108.65)
		(width 0.1)
		(layer "In9.Cu")
		(net 76)
	)
	(segment
		(start 193.0005 141.9995)
		(end 193.5 141.5)
		(width 0.256)
		(layer "F.Cu")
		(net 77)
	)
	(segment
		(start 191.3 106)
		(end 191.3 107.152)
		(width 0.38)
		(layer "F.Cu")
		(net 77)
	)
	(via
		(at 193.5 141.5)
		(size 0.45)
		(drill 0.1)
		(layers "F.Cu" "B.Cu")
		(remove_unused_layers yes)
		(keep_end_layers yes)
		(zone_layer_connections)
		(net 77)
	)
	(via
		(at 191.3 107.152)
		(size 0.45)
		(drill 0.1)
		(layers "F.Cu" "B.Cu")
		(remove_unused_layers yes)
		(keep_end_layers yes)
		(zone_layer_connections)
		(net 77)
	)
	(segment
		(start 189.925 113.225)
		(end 189.925 113.075)
		(width 0.1)
		(layer "In9.Cu")
		(net 77)
	)
	(segment
		(start 190.775 106.025)
		(end 190.775 105.725)
		(width 0.1)
		(layer "In9.Cu")
		(net 77)
	)
	(segment
		(start 191.036813 110.031813)
		(end 190.35 109.345)
		(width 0.1)
		(layer "In9.Cu")
		(net 77)
	)
	(segment
		(start 191.611868 110.022444)
		(end 191.611869 110.022445)
		(width 0.1)
		(layer "In9.Cu")
		(net 77)
	)
	(segment
		(start 191.6025 110.314657)
		(end 191.611869 110.305287)
		(width 0.1)
		(layer "In9.Cu")
		(net 77)
	)
	(segment
		(start 190.85 113.475)
		(end 190.975 113.35)
		(width 0.1)
		(layer "In9.Cu")
		(net 77)
	)
	(segment
		(start 190.975 113.102514)
		(end 190.975001 113.102512)
		(width 0.1)
		(layer "In9.Cu")
		(net 77)
	)
	(segment
		(start 193.5 141.5)
		(end 194.02 142.02)
		(width 0.1)
		(layer "In9.Cu")
		(net 77)
	)
	(segment
		(start 195.4 126.7)
		(end 193.125 124.425)
		(width 0.1)
		(layer "In9.Cu")
		(net 77)
	)
	(segment
		(start 190.975 112.855026)
		(end 191.045712 112.784315)
		(width 0.1)
		(layer "In9.Cu")
		(net 77)
	)
	(segment
		(start 191.540688 112.784315)
		(end 191.67 112.655)
		(width 0.1)
		(layer "In9.Cu")
		(net 77)
	)
	(segment
		(start 188.075 106.7)
		(end 187.9 106.525)
		(width 0.1)
		(layer "In9.Cu")
		(net 77)
	)
	(segment
		(start 189 120.8)
		(end 187.25 119.05)
		(width 0.1)
		(layer "In9.Cu")
		(net 77)
	)
	(segment
		(start 191 105.5)
		(end 191.15 105.5)
		(width 0.1)
		(layer "In9.Cu")
		(net 77)
	)
	(segment
		(start 190.975002 112.855025)
		(end 190.975 112.855026)
		(width 0.1)
		(layer "In9.Cu")
		(net 77)
	)
	(segment
		(start 191.15 105.5)
		(end 191.3 105.65)
		(width 0.1)
		(layer "In9.Cu")
		(net 77)
	)
	(segment
		(start 190.35 106.975)
		(end 190.075 106.7)
		(width 0.1)
		(layer "In9.Cu")
		(net 77)
	)
	(segment
		(start 190.675 108.575)
		(end 191.275 108.575)
		(width 0.1)
		(layer "In9.Cu")
		(net 77)
	)
	(segment
		(start 188.075 105.5)
		(end 188.3 105.5)
		(width 0.1)
		(layer "In9.Cu")
		(net 77)
	)
	(segment
		(start 191.3 105.65)
		(end 191.3 107.152)
		(width 0.1)
		(layer "In9.Cu")
		(net 77)
	)
	(segment
		(start 191.275 107.925)
		(end 190.675 107.925)
		(width 0.1)
		(layer "In9.Cu")
		(net 77)
	)
	(segment
		(start 195.11 136.89)
		(end 195.4 136.6)
		(width 0.1)
		(layer "In9.Cu")
		(net 77)
	)
	(segment
		(start 190.075 106.7)
		(end 188.075 106.7)
		(width 0.1)
		(layer "In9.Cu")
		(net 77)
	)
	(segment
		(start 189.425 113.075)
		(end 189.425 113.225)
		(width 0.1)
		(layer "In9.Cu")
		(net 77)
	)
	(segment
		(start 188.575 113.475)
		(end 188.675 113.475)
		(width 0.1)
		(layer "In9.Cu")
		(net 77)
	)
	(segment
		(start 190.325 105.725)
		(end 190.325 106.025)
		(width 0.1)
		(layer "In9.Cu")
		(net 77)
	)
	(segment
		(start 191.329026 110.022445)
		(end 191.319656 110.031814)
		(width 0.1)
		(layer "In9.Cu")
		(net 77)
	)
	(segment
		(start 190.675 113.475)
		(end 190.85 113.475)
		(width 0.1)
		(layer "In9.Cu")
		(net 77)
	)
	(segment
		(start 188.975 106.025)
		(end 188.975 105.725)
		(width 0.1)
		(layer "In9.Cu")
		(net 77)
	)
	(segment
		(start 187.9 105.675)
		(end 188.075 105.5)
		(width 0.1)
		(layer "In9.Cu")
		(net 77)
	)
	(segment
		(start 194.82 142.02)
		(end 195.11 141.73)
		(width 0.1)
		(layer "In9.Cu")
		(net 77)
	)
	(segment
		(start 191.67 112.655)
		(end 191.67 110.665)
		(width 0.1)
		(layer "In9.Cu")
		(net 77)
	)
	(segment
		(start 188.925 113.225)
		(end 188.925 113.075)
		(width 0.1)
		(layer "In9.Cu")
		(net 77)
	)
	(segment
		(start 195.11 141.73)
		(end 195.11 136.89)
		(width 0.1)
		(layer "In9.Cu")
		(net 77)
	)
	(segment
		(start 190.35 107.6)
		(end 190.35 106.975)
		(width 0.1)
		(layer "In9.Cu")
		(net 77)
	)
	(segment
		(start 189 123.975)
		(end 189 120.8)
		(width 0.1)
		(layer "In9.Cu")
		(net 77)
	)
	(segment
		(start 191.329026 110.022444)
		(end 191.329026 110.022445)
		(width 0.1)
		(layer "In9.Cu")
		(net 77)
	)
	(segment
		(start 189.425 105.725)
		(end 189.425 106.025)
		(width 0.1)
		(layer "In9.Cu")
		(net 77)
	)
	(segment
		(start 189.45 124.425)
		(end 189 123.975)
		(width 0.1)
		(layer "In9.Cu")
		(net 77)
	)
	(segment
		(start 189.875 106.025)
		(end 189.875 105.725)
		(width 0.1)
		(layer "In9.Cu")
		(net 77)
	)
	(segment
		(start 187.9 106.525)
		(end 187.9 105.675)
		(width 0.1)
		(layer "In9.Cu")
		(net 77)
	)
	(segment
		(start 194.02 142.02)
		(end 194.82 142.02)
		(width 0.1)
		(layer "In9.Cu")
		(net 77)
	)
	(segment
		(start 187.25 119.05)
		(end 187.25 114.8)
		(width 0.1)
		(layer "In9.Cu")
		(net 77)
	)
	(segment
		(start 193.125 124.425)
		(end 189.45 124.425)
		(width 0.1)
		(layer "In9.Cu")
		(net 77)
	)
	(segment
		(start 191.67 110.665)
		(end 191.6025 110.5975)
		(width 0.1)
		(layer "In9.Cu")
		(net 77)
	)
	(segment
		(start 195.4 136.6)
		(end 195.4 126.7)
		(width 0.1)
		(layer "In9.Cu")
		(net 77)
	)
	(segment
		(start 191.602499 110.314657)
		(end 191.6025 110.314657)
		(width 0.1)
		(layer "In9.Cu")
		(net 77)
	)
	(segment
		(start 187.25 114.8)
		(end 188.575 113.475)
		(width 0.1)
		(layer "In9.Cu")
		(net 77)
	)
	(segment
		(start 191.540687 112.784316)
		(end 191.540688 112.784315)
		(width 0.1)
		(layer "In9.Cu")
		(net 77)
	)
	(segment
		(start 188.525 105.725)
		(end 188.525 106.025)
		(width 0.1)
		(layer "In9.Cu")
		(net 77)
	)
	(segment
		(start 190.425 113.075)
		(end 190.425 113.225)
		(width 0.1)
		(layer "In9.Cu")
		(net 77)
	)
	(segment
		(start 190.35 109.345)
		(end 190.35 108.9)
		(width 0.1)
		(layer "In9.Cu")
		(net 77)
	)
	(arc
		(start 190.55 106.25)
		(mid 190.709099 106.184099)
		(end 190.775 106.025)
		(width 0.1)
		(layer "In9.Cu")
		(net 77)
	)
	(arc
		(start 188.925 113.075)
		(mid 188.998223 112.898223)
		(end 189.175 112.825)
		(width 0.1)
		(layer "In9.Cu")
		(net 77)
	)
	(arc
		(start 189.425 106.025)
		(mid 189.490901 106.184099)
		(end 189.65 106.25)
		(width 0.1)
		(layer "In9.Cu")
		(net 77)
	)
	(arc
		(start 188.75 106.25)
		(mid 188.909099 106.184099)
		(end 188.975 106.025)
		(width 0.1)
		(layer "In9.Cu")
		(net 77)
	)
	(arc
		(start 189.875 105.725)
		(mid 189.940901 105.565901)
		(end 190.1 105.5)
		(width 0.1)
		(layer "In9.Cu")
		(net 77)
	)
	(arc
		(start 191.6025 110.5975)
		(mid 191.543921 110.456079)
		(end 191.602499 110.314657)
		(width 0.1)
		(layer "In9.Cu")
		(net 77)
	)
	(arc
		(start 190.425 113.225)
		(mid 190.498223 113.401777)
		(end 190.675 113.475)
		(width 0.1)
		(layer "In9.Cu")
		(net 77)
	)
	(arc
		(start 188.675 113.475)
		(mid 188.851777 113.401777)
		(end 188.925 113.225)
		(width 0.1)
		(layer "In9.Cu")
		(net 77)
	)
	(arc
		(start 190.975001 113.102512)
		(mid 190.923745 112.978768)
		(end 190.975002 112.855025)
		(width 0.1)
		(layer "In9.Cu")
		(net 77)
	)
	(arc
		(start 190.35 108.9)
		(mid 190.44519 108.67019)
		(end 190.675 108.575)
		(width 0.1)
		(layer "In9.Cu")
		(net 77)
	)
	(arc
		(start 191.611869 110.305287)
		(mid 191.670447 110.163865)
		(end 191.611868 110.022444)
		(width 0.1)
		(layer "In9.Cu")
		(net 77)
	)
	(arc
		(start 189.925 113.075)
		(mid 189.998223 112.898223)
		(end 190.175 112.825)
		(width 0.1)
		(layer "In9.Cu")
		(net 77)
	)
	(arc
		(start 191.2932 112.784315)
		(mid 191.416943 112.835572)
		(end 191.540687 112.784316)
		(width 0.1)
		(layer "In9.Cu")
		(net 77)
	)
	(arc
		(start 189.425 113.225)
		(mid 189.498223 113.401777)
		(end 189.675 113.475)
		(width 0.1)
		(layer "In9.Cu")
		(net 77)
	)
	(arc
		(start 188.525 106.025)
		(mid 188.590901 106.184099)
		(end 188.75 106.25)
		(width 0.1)
		(layer "In9.Cu")
		(net 77)
	)
	(arc
		(start 191.045712 112.784315)
		(mid 191.169456 112.733059)
		(end 191.2932 112.784315)
		(width 0.1)
		(layer "In9.Cu")
		(net 77)
	)
	(arc
		(start 191.611869 110.022445)
		(mid 191.470448 109.963866)
		(end 191.329026 110.022444)
		(width 0.1)
		(layer "In9.Cu")
		(net 77)
	)
	(arc
		(start 189.2 105.5)
		(mid 189.359099 105.565901)
		(end 189.425 105.725)
		(width 0.1)
		(layer "In9.Cu")
		(net 77)
	)
	(arc
		(start 190.675 107.925)
		(mid 190.44519 107.82981)
		(end 190.35 107.6)
		(width 0.1)
		(layer "In9.Cu")
		(net 77)
	)
	(arc
		(start 190.1 105.5)
		(mid 190.259099 105.565901)
		(end 190.325 105.725)
		(width 0.1)
		(layer "In9.Cu")
		(net 77)
	)
	(arc
		(start 188.3 105.5)
		(mid 188.459099 105.565901)
		(end 188.525 105.725)
		(width 0.1)
		(layer "In9.Cu")
		(net 77)
	)
	(arc
		(start 190.175 112.825)
		(mid 190.351777 112.898223)
		(end 190.425 113.075)
		(width 0.1)
		(layer "In9.Cu")
		(net 77)
	)
	(arc
		(start 189.675 113.475)
		(mid 189.851777 113.401777)
		(end 189.925 113.225)
		(width 0.1)
		(layer "In9.Cu")
		(net 77)
	)
	(arc
		(start 189.175 112.825)
		(mid 189.351777 112.898223)
		(end 189.425 113.075)
		(width 0.1)
		(layer "In9.Cu")
		(net 77)
	)
	(arc
		(start 189.65 106.25)
		(mid 189.809099 106.184099)
		(end 189.875 106.025)
		(width 0.1)
		(layer "In9.Cu")
		(net 77)
	)
	(arc
		(start 190.325 106.025)
		(mid 190.390901 106.184099)
		(end 190.55 106.25)
		(width 0.1)
		(layer "In9.Cu")
		(net 77)
	)
	(arc
		(start 191.6 108.25)
		(mid 191.50481 108.02019)
		(end 191.275 107.925)
		(width 0.1)
		(layer "In9.Cu")
		(net 77)
	)
	(arc
		(start 191.275 108.575)
		(mid 191.50481 108.47981)
		(end 191.6 108.25)
		(width 0.1)
		(layer "In9.Cu")
		(net 77)
	)
	(arc
		(start 191.319656 110.031814)
		(mid 191.178234 110.090392)
		(end 191.036813 110.031813)
		(width 0.1)
		(layer "In9.Cu")
		(net 77)
	)
	(arc
		(start 190.775 105.725)
		(mid 190.840901 105.565901)
		(end 191 105.5)
		(width 0.1)
		(layer "In9.Cu")
		(net 77)
	)
	(arc
		(start 190.975 113.35)
		(mid 191.026257 113.226256)
		(end 190.975 113.102514)
		(width 0.1)
		(layer "In9.Cu")
		(net 77)
	)
	(arc
		(start 188.975 105.725)
		(mid 189.040901 105.565901)
		(end 189.2 105.5)
		(width 0.1)
		(layer "In9.Cu")
		(net 77)
	)
	(segment
		(start 189.6 106)
		(end 189.6 107.152)
		(width 0.38)
		(layer "F.Cu")
		(net 78)
	)
	(segment
		(start 194.0005 141.999501)
		(end 194.5 141.5)
		(width 0.256)
		(layer "F.Cu")
		(net 78)
	)
	(via
		(at 189.6 107.152)
		(size 0.45)
		(drill 0.1)
		(layers "F.Cu" "B.Cu")
		(remove_unused_layers yes)
		(keep_end_layers yes)
		(zone_layer_connections)
		(net 78)
	)
	(via
		(at 194.5 141.5)
		(size 0.45)
		(drill 0.1)
		(layers "F.Cu" "B.Cu")
		(remove_unused_layers yes)
		(keep_end_layers yes)
		(zone_layer_connections)
		(net 78)
	)
	(segment
		(start 194.242157 126.774999)
		(end 194.242156 126.774999)
		(width 0.1)
		(layer "In9.Cu")
		(net 78)
	)
	(segment
		(start 191.1 125.1)
		(end 191.1 125.5)
		(width 0.1)
		(layer "In9.Cu")
		(net 78)
	)
	(segment
		(start 187.852079 120.976343)
		(end 187.180329 121.648094)
		(width 0.1)
		(layer "In9.Cu")
		(net 78)
	)
	(segment
		(start 188.35 108.5)
		(end 189.4 108.5)
		(width 0.1)
		(layer "In9.Cu")
		(net 78)
	)
	(segment
		(start 186.013603 120.764212)
		(end 186.013604 120.764213)
		(width 0.1)
		(layer "In9.Cu")
		(net 78)
	)
	(segment
		(start 192.82794 125.077941)
		(end 192.827941 125.077941)
		(width 0.1)
		(layer "In9.Cu")
		(net 78)
	)
	(segment
		(start 188.575 112.425)
		(end 190.735 112.425)
		(width 0.1)
		(layer "In9.Cu")
		(net 78)
	)
	(segment
		(start 193.745829 126.988483)
		(end 193.74583 126.988484)
		(width 0.1)
		(layer "In9.Cu")
		(net 78)
	)
	(segment
		(start 186.756064 121.223831)
		(end 187.427815 120.552081)
		(width 0.1)
		(layer "In9.Cu")
		(net 78)
	)
	(segment
		(start 193.110784 125.643627)
		(end 192.897285 125.857127)
		(width 0.1)
		(layer "In9.Cu")
		(net 78)
	)
	(segment
		(start 194.91 140.79)
		(end 194.91 139.16)
		(width 0.1)
		(layer "In9.Cu")
		(net 78)
	)
	(segment
		(start 192.65 124.9)
		(end 192.1 124.9)
		(width 0.1)
		(layer "In9.Cu")
		(net 78)
	)
	(segment
		(start 191.11 111.02)
		(end 190.19 110.1)
		(width 0.1)
		(layer "In9.Cu")
		(net 78)
	)
	(segment
		(start 191.11 112.05)
		(end 191.11 111.02)
		(width 0.1)
		(layer "In9.Cu")
		(net 78)
	)
	(segment
		(start 193.745829 126.70564)
		(end 193.959314 126.492156)
		(width 0.1)
		(layer "In9.Cu")
		(net 78)
	)
	(segment
		(start 189.825 109.875)
		(end 189.825 109.375)
		(width 0.1)
		(layer "In9.Cu")
		(net 78)
	)
	(segment
		(start 188.4 121.1)
		(end 188.276343 120.976343)
		(width 0.1)
		(layer "In9.Cu")
		(net 78)
	)
	(segment
		(start 190.7 125.5)
		(end 190.7 125.1)
		(width 0.1)
		(layer "In9.Cu")
		(net 78)
	)
	(segment
		(start 194.65 126.9)
		(end 194.525 126.775)
		(width 0.1)
		(layer "In9.Cu")
		(net 78)
	)
	(segment
		(start 188.65 125.45)
		(end 188.4 125.2)
		(width 0.1)
		(layer "In9.Cu")
		(net 78)
	)
	(segment
		(start 191.9 125.1)
		(end 191.9 125.5)
		(width 0.1)
		(layer "In9.Cu")
		(net 78)
	)
	(segment
		(start 188.4 121.2)
		(end 188.4 121.1)
		(width 0.1)
		(layer "In9.Cu")
		(net 78)
	)
	(segment
		(start 188.4 125.2)
		(end 188.4 124.1)
		(width 0.1)
		(layer "In9.Cu")
		(net 78)
	)
	(segment
		(start 190.19 110.1)
		(end 190.05 110.1)
		(width 0.1)
		(layer "In9.Cu")
		(net 78)
	)
	(segment
		(start 189.7 124.9)
		(end 189.65 124.9)
		(width 0.1)
		(layer "In9.Cu")
		(net 78)
	)
	(segment
		(start 189.6 108.3)
		(end 189.6 107.152)
		(width 0.1)
		(layer "In9.Cu")
		(net 78)
	)
	(segment
		(start 187.95 108.9)
		(end 188.35 108.5)
		(width 0.1)
		(layer "In9.Cu")
		(net 78)
	)
	(segment
		(start 193.676471 126.209313)
		(end 193.67647 126.209313)
		(width 0.1)
		(layer "In9.Cu")
		(net 78)
	)
	(segment
		(start 194.5 141.5)
		(end 194.5 141.2)
		(width 0.1)
		(layer "In9.Cu")
		(net 78)
	)
	(segment
		(start 193.18013 126.139968)
		(end 193.393626 125.926469)
		(width 0.1)
		(layer "In9.Cu")
		(net 78)
	)
	(segment
		(start 186.65 119.35)
		(end 186.55 119.25)
		(width 0.1)
		(layer "In9.Cu")
		(net 78)
	)
	(segment
		(start 187.038907 120.127815)
		(end 186.402512 120.764211)
		(width 0.1)
		(layer "In9.Cu")
		(net 78)
	)
	(segment
		(start 194.5 141.2)
		(end 194.91 140.79)
		(width 0.1)
		(layer "In9.Cu")
		(net 78)
	)
	(segment
		(start 186.55 114.45)
		(end 188.575 112.425)
		(width 0.1)
		(layer "In9.Cu")
		(net 78)
	)
	(segment
		(start 189.4 108.5)
		(end 189.6 108.3)
		(width 0.1)
		(layer "In9.Cu")
		(net 78)
	)
	(segment
		(start 193.180131 126.422811)
		(end 193.180129 126.42281)
		(width 0.1)
		(layer "In9.Cu")
		(net 78)
	)
	(segment
		(start 189.9 125.5)
		(end 189.9 125.1)
		(width 0.1)
		(layer "In9.Cu")
		(net 78)
	)
	(segment
		(start 193.180128 126.139967)
		(end 193.18013 126.139968)
		(width 0.1)
		(layer "In9.Cu")
		(net 78)
	)
	(segment
		(start 189.65 124.9)
		(end 189.1 125.45)
		(width 0.1)
		(layer "In9.Cu")
		(net 78)
	)
	(segment
		(start 188.4 123.2)
		(end 188.4 122.35)
		(width 0.1)
		(layer "In9.Cu")
		(net 78)
	)
	(segment
		(start 194.91 139.16)
		(end 194.65 138.9)
		(width 0.1)
		(layer "In9.Cu")
		(net 78)
	)
	(segment
		(start 193.959313 126.209313)
		(end 193.959314 126.209314)
		(width 0.1)
		(layer "In9.Cu")
		(net 78)
	)
	(segment
		(start 193.67647 126.209313)
		(end 193.462973 126.422811)
		(width 0.1)
		(layer "In9.Cu")
		(net 78)
	)
	(segment
		(start 192.614442 125.574284)
		(end 192.82794 125.360783)
		(width 0.1)
		(layer "In9.Cu")
		(net 78)
	)
	(segment
		(start 189.375 109.375)
		(end 189.375 109.875)
		(width 0.1)
		(layer "In9.Cu")
		(net 78)
	)
	(segment
		(start 193.110785 125.643627)
		(end 193.110784 125.643627)
		(width 0.1)
		(layer "In9.Cu")
		(net 78)
	)
	(segment
		(start 194.242156 126.774999)
		(end 194.028672 126.988484)
		(width 0.1)
		(layer "In9.Cu")
		(net 78)
	)
	(segment
		(start 193.745829 126.705641)
		(end 193.745829 126.70564)
		(width 0.1)
		(layer "In9.Cu")
		(net 78)
	)
	(segment
		(start 192.827941 125.077941)
		(end 192.65 124.9)
		(width 0.1)
		(layer "In9.Cu")
		(net 78)
	)
	(segment
		(start 186.55 119.25)
		(end 186.55 114.45)
		(width 0.1)
		(layer "In9.Cu")
		(net 78)
	)
	(segment
		(start 186.013603 120.375304)
		(end 186.649999 119.738909)
		(width 0.1)
		(layer "In9.Cu")
		(net 78)
	)
	(segment
		(start 190.3 125.1)
		(end 190.3 125.5)
		(width 0.1)
		(layer "In9.Cu")
		(net 78)
	)
	(segment
		(start 194.65 138.9)
		(end 194.65 126.9)
		(width 0.1)
		(layer "In9.Cu")
		(net 78)
	)
	(segment
		(start 188.3 110.1)
		(end 187.95 109.75)
		(width 0.1)
		(layer "In9.Cu")
		(net 78)
	)
	(segment
		(start 192.61444 125.574283)
		(end 192.614442 125.574284)
		(width 0.1)
		(layer "In9.Cu")
		(net 78)
	)
	(segment
		(start 189.1 125.45)
		(end 188.65 125.45)
		(width 0.1)
		(layer "In9.Cu")
		(net 78)
	)
	(segment
		(start 189.15 110.1)
		(end 188.3 110.1)
		(width 0.1)
		(layer "In9.Cu")
		(net 78)
	)
	(segment
		(start 192.614443 125.857127)
		(end 192.614441 125.857126)
		(width 0.1)
		(layer "In9.Cu")
		(net 78)
	)
	(segment
		(start 193.393626 125.643627)
		(end 193.393628 125.643628)
		(width 0.1)
		(layer "In9.Cu")
		(net 78)
	)
	(segment
		(start 187.95 109.75)
		(end 187.95 108.9)
		(width 0.1)
		(layer "In9.Cu")
		(net 78)
	)
	(segment
		(start 187.85 121.8)
		(end 187.85 121.75)
		(width 0.1)
		(layer "In9.Cu")
		(net 78)
	)
	(segment
		(start 191.5 125.5)
		(end 191.5 125.1)
		(width 0.1)
		(layer "In9.Cu")
		(net 78)
	)
	(segment
		(start 190.735 112.425)
		(end 191.11 112.05)
		(width 0.1)
		(layer "In9.Cu")
		(net 78)
	)
	(arc
		(start 193.462973 126.422811)
		(mid 193.321551 126.481388)
		(end 193.180131 126.422811)
		(width 0.1)
		(layer "In9.Cu")
		(net 78)
	)
	(arc
		(start 186.649999 119.738909)
		(mid 186.730545 119.544455)
		(end 186.65 119.35)
		(width 0.1)
		(layer "In9.Cu")
		(net 78)
	)
	(arc
		(start 186.013604 120.764213)
		(mid 185.933058 120.569759)
		(end 186.013603 120.375304)
		(width 0.1)
		(layer "In9.Cu")
		(net 78)
	)
	(arc
		(start 191.9 125.5)
		(mid 191.841421 125.641421)
		(end 191.7 125.7)
		(width 0.1)
		(layer "In9.Cu")
		(net 78)
	)
	(arc
		(start 189.6 109.15)
		(mid 189.440901 109.215901)
		(end 189.375 109.375)
		(width 0.1)
		(layer "In9.Cu")
		(net 78)
	)
	(arc
		(start 191.1 125.5)
		(mid 191.041421 125.641421)
		(end 190.9 125.7)
		(width 0.1)
		(layer "In9.Cu")
		(net 78)
	)
	(arc
		(start 188.175 123.875)
		(mid 188.015901 123.809099)
		(end 187.95 123.65)
		(width 0.1)
		(layer "In9.Cu")
		(net 78)
	)
	(arc
		(start 189.375 109.875)
		(mid 189.309099 110.034099)
		(end 189.15 110.1)
		(width 0.1)
		(layer "In9.Cu")
		(net 78)
	)
	(arc
		(start 190.3 125.5)
		(mid 190.241421 125.641421)
		(end 190.1 125.7)
		(width 0.1)
		(layer "In9.Cu")
		(net 78)
	)
	(arc
		(start 193.393626 125.926469)
		(mid 193.452205 125.785049)
		(end 193.393626 125.643627)
		(width 0.1)
		(layer "In9.Cu")
		(net 78)
	)
	(arc
		(start 191.3 124.9)
		(mid 191.158579 124.958579)
		(end 191.1 125.1)
		(width 0.1)
		(layer "In9.Cu")
		(net 78)
	)
	(arc
		(start 192.897285 125.857127)
		(mid 192.755863 125.915704)
		(end 192.614443 125.857127)
		(width 0.1)
		(layer "In9.Cu")
		(net 78)
	)
	(arc
		(start 192.614441 125.857126)
		(mid 192.555862 125.715705)
		(end 192.61444 125.574283)
		(width 0.1)
		(layer "In9.Cu")
		(net 78)
	)
	(arc
		(start 193.393628 125.643628)
		(mid 193.252207 125.585049)
		(end 193.110785 125.643627)
		(width 0.1)
		(layer "In9.Cu")
		(net 78)
	)
	(arc
		(start 191.7 125.7)
		(mid 191.558579 125.641421)
		(end 191.5 125.5)
		(width 0.1)
		(layer "In9.Cu")
		(net 78)
	)
	(arc
		(start 188.4 124.1)
		(mid 188.334099 123.940901)
		(end 188.175 123.875)
		(width 0.1)
		(layer "In9.Cu")
		(net 78)
	)
	(arc
		(start 193.959314 126.492156)
		(mid 194.017892 126.350734)
		(end 193.959313 126.209313)
		(width 0.1)
		(layer "In9.Cu")
		(net 78)
	)
	(arc
		(start 190.1 125.7)
		(mid 189.958579 125.641421)
		(end 189.9 125.5)
		(width 0.1)
		(layer "In9.Cu")
		(net 78)
	)
	(arc
		(start 188.125 121.475)
		(mid 188.319454 121.394454)
		(end 188.4 121.2)
		(width 0.1)
		(layer "In9.Cu")
		(net 78)
	)
	(arc
		(start 186.756064 121.648095)
		(mid 186.668196 121.435963)
		(end 186.756064 121.223831)
		(width 0.1)
		(layer "In9.Cu")
		(net 78)
	)
	(arc
		(start 190.9 125.7)
		(mid 190.758579 125.641421)
		(end 190.7 125.5)
		(width 0.1)
		(layer "In9.Cu")
		(net 78)
	)
	(arc
		(start 187.427816 120.127816)
		(mid 187.233362 120.04727)
		(end 187.038907 120.127815)
		(width 0.1)
		(layer "In9.Cu")
		(net 78)
	)
	(arc
		(start 189.9 125.1)
		(mid 189.841421 124.958579)
		(end 189.7 124.9)
		(width 0.1)
		(layer "In9.Cu")
		(net 78)
	)
	(arc
		(start 193.180129 126.42281)
		(mid 193.12155 126.281389)
		(end 193.180128 126.139967)
		(width 0.1)
		(layer "In9.Cu")
		(net 78)
	)
	(arc
		(start 193.74583 126.988484)
		(mid 193.687251 126.847063)
		(end 193.745829 126.705641)
		(width 0.1)
		(layer "In9.Cu")
		(net 78)
	)
	(arc
		(start 190.05 110.1)
		(mid 189.890901 110.034099)
		(end 189.825 109.875)
		(width 0.1)
		(layer "In9.Cu")
		(net 78)
	)
	(arc
		(start 193.959314 126.209314)
		(mid 193.817893 126.150735)
		(end 193.676471 126.209313)
		(width 0.1)
		(layer "In9.Cu")
		(net 78)
	)
	(arc
		(start 188.276343 120.976343)
		(mid 188.064211 120.888475)
		(end 187.852079 120.976343)
		(width 0.1)
		(layer "In9.Cu")
		(net 78)
	)
	(arc
		(start 194.028672 126.988484)
		(mid 193.88725 127.047062)
		(end 193.745829 126.988483)
		(width 0.1)
		(layer "In9.Cu")
		(net 78)
	)
	(arc
		(start 192.82794 125.360783)
		(mid 192.886519 125.219363)
		(end 192.82794 125.077941)
		(width 0.1)
		(layer "In9.Cu")
		(net 78)
	)
	(arc
		(start 188.4 122.35)
		(mid 188.319454 122.155546)
		(end 188.125 122.075)
		(width 0.1)
		(layer "In9.Cu")
		(net 78)
	)
	(arc
		(start 190.5 124.9)
		(mid 190.358579 124.958579)
		(end 190.3 125.1)
		(width 0.1)
		(layer "In9.Cu")
		(net 78)
	)
	(arc
		(start 186.402512 120.764211)
		(mid 186.208058 120.844757)
		(end 186.013603 120.764212)
		(width 0.1)
		(layer "In9.Cu")
		(net 78)
	)
	(arc
		(start 187.427815 120.552081)
		(mid 187.515684 120.339949)
		(end 187.427816 120.127816)
		(width 0.1)
		(layer "In9.Cu")
		(net 78)
	)
	(arc
		(start 190.7 125.1)
		(mid 190.641421 124.958579)
		(end 190.5 124.9)
		(width 0.1)
		(layer "In9.Cu")
		(net 78)
	)
	(arc
		(start 189.825 109.375)
		(mid 189.759099 109.215901)
		(end 189.6 109.15)
		(width 0.1)
		(layer "In9.Cu")
		(net 78)
	)
	(arc
		(start 187.95 123.65)
		(mid 188.015901 123.490901)
		(end 188.175 123.425)
		(width 0.1)
		(layer "In9.Cu")
		(net 78)
	)
	(arc
		(start 187.180329 121.648094)
		(mid 186.968197 121.735963)
		(end 186.756064 121.648095)
		(width 0.1)
		(layer "In9.Cu")
		(net 78)
	)
	(arc
		(start 194.525 126.775)
		(mid 194.383579 126.716421)
		(end 194.242157 126.774999)
		(width 0.1)
		(layer "In9.Cu")
		(net 78)
	)
	(arc
		(start 191.5 125.1)
		(mid 191.441421 124.958579)
		(end 191.3 124.9)
		(width 0.1)
		(layer "In9.Cu")
		(net 78)
	)
	(arc
		(start 187.85 121.75)
		(mid 187.930546 121.555546)
		(end 188.125 121.475)
		(width 0.1)
		(layer "In9.Cu")
		(net 78)
	)
	(arc
		(start 188.125 122.075)
		(mid 187.930546 121.994454)
		(end 187.85 121.8)
		(width 0.1)
		(layer "In9.Cu")
		(net 78)
	)
	(arc
		(start 188.175 123.425)
		(mid 188.334099 123.359099)
		(end 188.4 123.2)
		(width 0.1)
		(layer "In9.Cu")
		(net 78)
	)
	(arc
		(start 192.1 124.9)
		(mid 191.958579 124.958579)
		(end 191.9 125.1)
		(width 0.1)
		(layer "In9.Cu")
		(net 78)
	)
	(segment
		(start 182.8 106)
		(end 182.8 107.152)
		(width 0.38)
		(layer "F.Cu")
		(net 79)
	)
	(segment
		(start 192.0005 140.9995)
		(end 192.5 140.5)
		(width 0.256)
		(layer "F.Cu")
		(net 79)
	)
	(via
		(at 192.5 140.5)
		(size 0.45)
		(drill 0.1)
		(layers "F.Cu" "B.Cu")
		(remove_unused_layers yes)
		(keep_end_layers yes)
		(zone_layer_connections)
		(net 79)
	)
	(via
		(at 182.8 107.152)
		(size 0.45)
		(drill 0.1)
		(layers "F.Cu" "B.Cu")
		(remove_unused_layers yes)
		(keep_end_layers yes)
		(zone_layer_connections)
		(net 79)
	)
	(segment
		(start 177.25 123.25)
		(end 177.15 123.15)
		(width 0.1)
		(layer "In9.Cu")
		(net 79)
	)
	(segment
		(start 179.815179 123.022106)
		(end 179.65416 122.861087)
		(width 0.1)
		(layer "In9.Cu")
		(net 79)
	)
	(segment
		(start 179.300608 121.340811)
		(end 178.911699 120.951902)
		(width 0.1)
		(layer "In9.Cu")
		(net 79)
	)
	(segment
		(start 178.85 127.3)
		(end 178.85 124.85)
		(width 0.1)
		(layer "In9.Cu")
		(net 79)
	)
	(segment
		(start 180.35 119.95)
		(end 182.8 117.5)
		(width 0.1)
		(layer "In9.Cu")
		(net 79)
	)
	(segment
		(start 178.85 124.85)
		(end 178.38137 124.381371)
		(width 0.1)
		(layer "In9.Cu")
		(net 79)
	)
	(segment
		(start 191.75 138.85)
		(end 191.75 130.55)
		(width 0.1)
		(layer "In9.Cu")
		(net 79)
	)
	(segment
		(start 177.15 121.85)
		(end 177.627206 121.372791)
		(width 0.1)
		(layer "In9.Cu")
		(net 79)
	)
	(segment
		(start 179.178778 123.658498)
		(end 179.017764 123.497484)
		(width 0.1)
		(layer "In9.Cu")
		(net 79)
	)
	(segment
		(start 192.5 140.35)
		(end 192 139.85)
		(width 0.1)
		(layer "In9.Cu")
		(net 79)
	)
	(segment
		(start 178.876343 122.189338)
		(end 178.876344 122.189339)
		(width 0.1)
		(layer "In9.Cu")
		(net 79)
	)
	(segment
		(start 179.81518 123.340306)
		(end 179.81518 123.340305)
		(width 0.1)
		(layer "In9.Cu")
		(net 79)
	)
	(segment
		(start 177.982843 122.658578)
		(end 177.982844 122.65858)
		(width 0.1)
		(layer "In9.Cu")
		(net 79)
	)
	(segment
		(start 192 139.85)
		(end 192 139.1)
		(width 0.1)
		(layer "In9.Cu")
		(net 79)
	)
	(segment
		(start 177.627206 120.736395)
		(end 177.556496 120.665685)
		(width 0.1)
		(layer "In9.Cu")
		(net 79)
	)
	(segment
		(start 180.85 129.3)
		(end 178.85 127.3)
		(width 0.1)
		(layer "In9.Cu")
		(net 79)
	)
	(segment
		(start 177.815686 123.250001)
		(end 177.815685 123.249999)
		(width 0.1)
		(layer "In9.Cu")
		(net 79)
	)
	(segment
		(start 178.699568 123.815684)
		(end 178.860581 123.976697)
		(width 0.1)
		(layer "In9.Cu")
		(net 79)
	)
	(segment
		(start 190.5 129.3)
		(end 180.85 129.3)
		(width 0.1)
		(layer "In9.Cu")
		(net 79)
	)
	(segment
		(start 179.05 119.95)
		(end 179.2 119.95)
		(width 0.1)
		(layer "In9.Cu")
		(net 79)
	)
	(segment
		(start 178.876344 122.189339)
		(end 178.83137 122.234314)
		(width 0.1)
		(layer "In9.Cu")
		(net 79)
	)
	(segment
		(start 179.017765 123.179288)
		(end 179.017766 123.179289)
		(width 0.1)
		(layer "In9.Cu")
		(net 79)
	)
	(segment
		(start 178.487435 121.376166)
		(end 178.876343 121.765074)
		(width 0.1)
		(layer "In9.Cu")
		(net 79)
	)
	(segment
		(start 192 139.1)
		(end 191.75 138.85)
		(width 0.1)
		(layer "In9.Cu")
		(net 79)
	)
	(segment
		(start 191.75 130.55)
		(end 190.5 129.3)
		(width 0.1)
		(layer "In9.Cu")
		(net 79)
	)
	(segment
		(start 177.770713 122.446447)
		(end 177.982843 122.658578)
		(width 0.1)
		(layer "In9.Cu")
		(net 79)
	)
	(segment
		(start 179.335963 123.179288)
		(end 179.335964 123.179288)
		(width 0.1)
		(layer "In9.Cu")
		(net 79)
	)
	(segment
		(start 178.407109 122.234316)
		(end 178.194976 122.022184)
		(width 0.1)
		(layer "In9.Cu")
		(net 79)
	)
	(segment
		(start 178.263603 120.1)
		(end 178.263602 120.1)
		(width 0.1)
		(layer "In9.Cu")
		(net 79)
	)
	(segment
		(start 178.699567 123.815684)
		(end 178.699568 123.815684)
		(width 0.1)
		(layer "In9.Cu")
		(net 79)
	)
	(segment
		(start 179.300607 121.340811)
		(end 179.300608 121.340811)
		(width 0.1)
		(layer "In9.Cu")
		(net 79)
	)
	(segment
		(start 179.45 120.2)
		(end 179.45 120.5)
		(width 0.1)
		(layer "In9.Cu")
		(net 79)
	)
	(segment
		(start 179.654161 122.542892)
		(end 180.290558 121.906497)
		(width 0.1)
		(layer "In9.Cu")
		(net 79)
	)
	(segment
		(start 180.290559 121.340812)
		(end 180.290559 121.340811)
		(width 0.1)
		(layer "In9.Cu")
		(net 79)
	)
	(segment
		(start 178.192892 120.029289)
		(end 178.263603 120.1)
		(width 0.1)
		(layer "In9.Cu")
		(net 79)
	)
	(segment
		(start 177.15 123.15)
		(end 177.15 121.85)
		(width 0.1)
		(layer "In9.Cu")
		(net 79)
	)
	(segment
		(start 178.83137 122.234314)
		(end 178.831374 122.234317)
		(width 0.1)
		(layer "In9.Cu")
		(net 79)
	)
	(segment
		(start 179.95 120.5)
		(end 179.95 120.2)
		(width 0.1)
		(layer "In9.Cu")
		(net 79)
	)
	(segment
		(start 192.5 140.5)
		(end 192.5 140.35)
		(width 0.1)
		(layer "In9.Cu")
		(net 79)
	)
	(segment
		(start 179.65416 122.542889)
		(end 179.654161 122.542892)
		(width 0.1)
		(layer "In9.Cu")
		(net 79)
	)
	(segment
		(start 179.335964 123.179288)
		(end 179.496982 123.340306)
		(width 0.1)
		(layer "In9.Cu")
		(net 79)
	)
	(segment
		(start 178.9 120.1)
		(end 179.05 119.95)
		(width 0.1)
		(layer "In9.Cu")
		(net 79)
	)
	(segment
		(start 179.017764 123.179286)
		(end 179.017765 123.179288)
		(width 0.1)
		(layer "In9.Cu")
		(net 79)
	)
	(segment
		(start 177.982843 123.082843)
		(end 177.815686 123.250001)
		(width 0.1)
		(layer "In9.Cu")
		(net 79)
	)
	(segment
		(start 180.2 119.95)
		(end 180.35 119.95)
		(width 0.1)
		(layer "In9.Cu")
		(net 79)
	)
	(segment
		(start 182.8 117.5)
		(end 182.8 107.152)
		(width 0.1)
		(layer "In9.Cu")
		(net 79)
	)
	(arc
		(start 179.2 119.95)
		(mid 179.376777 120.023223)
		(end 179.45 120.2)
		(width 0.1)
		(layer "In9.Cu")
		(net 79)
	)
	(arc
		(start 178.876343 121.765074)
		(mid 178.964211 121.977206)
		(end 178.876343 122.189338)
		(width 0.1)
		(layer "In9.Cu")
		(net 79)
	)
	(arc
		(start 178.487435 120.951902)
		(mid 178.399567 121.164034)
		(end 178.487435 121.376166)
		(width 0.1)
		(layer "In9.Cu")
		(net 79)
	)
	(arc
		(start 180.290559 121.340811)
		(mid 180.007716 121.223654)
		(end 179.724873 121.340811)
		(width 0.1)
		(layer "In9.Cu")
		(net 79)
	)
	(arc
		(start 177.815685 123.249999)
		(mid 177.532843 123.367157)
		(end 177.25 123.25)
		(width 0.1)
		(layer "In9.Cu")
		(net 79)
	)
	(arc
		(start 178.38137 123.815685)
		(mid 178.540468 123.749784)
		(end 178.699567 123.815684)
		(width 0.1)
		(layer "In9.Cu")
		(net 79)
	)
	(arc
		(start 179.178779 123.976697)
		(mid 179.24468 123.817597)
		(end 179.178778 123.658498)
		(width 0.1)
		(layer "In9.Cu")
		(net 79)
	)
	(arc
		(start 177.627206 121.372791)
		(mid 177.759008 121.054593)
		(end 177.627206 120.736395)
		(width 0.1)
		(layer "In9.Cu")
		(net 79)
	)
	(arc
		(start 177.556496 120.665685)
		(mid 177.424694 120.347487)
		(end 177.556496 120.029289)
		(width 0.1)
		(layer "In9.Cu")
		(net 79)
	)
	(arc
		(start 179.496982 123.340306)
		(mid 179.656081 123.406207)
		(end 179.81518 123.340306)
		(width 0.1)
		(layer "In9.Cu")
		(net 79)
	)
	(arc
		(start 178.911699 120.951902)
		(mid 178.699567 120.864034)
		(end 178.487435 120.951902)
		(width 0.1)
		(layer "In9.Cu")
		(net 79)
	)
	(arc
		(start 179.017764 123.497484)
		(mid 178.951863 123.338385)
		(end 179.017764 123.179286)
		(width 0.1)
		(layer "In9.Cu")
		(net 79)
	)
	(arc
		(start 177.982844 122.65858)
		(mid 178.07071 122.870711)
		(end 177.982843 123.082843)
		(width 0.1)
		(layer "In9.Cu")
		(net 79)
	)
	(arc
		(start 179.017766 123.179289)
		(mid 179.176864 123.113388)
		(end 179.335963 123.179288)
		(width 0.1)
		(layer "In9.Cu")
		(net 79)
	)
	(arc
		(start 177.556496 120.029289)
		(mid 177.874694 119.897487)
		(end 178.192892 120.029289)
		(width 0.1)
		(layer "In9.Cu")
		(net 79)
	)
	(arc
		(start 179.7 120.75)
		(mid 179.876777 120.676777)
		(end 179.95 120.5)
		(width 0.1)
		(layer "In9.Cu")
		(net 79)
	)
	(arc
		(start 178.831374 122.234317)
		(mid 178.61924 122.322186)
		(end 178.407109 122.234316)
		(width 0.1)
		(layer "In9.Cu")
		(net 79)
	)
	(arc
		(start 178.263602 120.1)
		(mid 178.581801 120.231802)
		(end 178.9 120.1)
		(width 0.1)
		(layer "In9.Cu")
		(net 79)
	)
	(arc
		(start 179.81518 123.340305)
		(mid 179.881081 123.181205)
		(end 179.815179 123.022106)
		(width 0.1)
		(layer "In9.Cu")
		(net 79)
	)
	(arc
		(start 179.45 120.5)
		(mid 179.523223 120.676777)
		(end 179.7 120.75)
		(width 0.1)
		(layer "In9.Cu")
		(net 79)
	)
	(arc
		(start 179.724873 121.340811)
		(mid 179.51274 121.428679)
		(end 179.300607 121.340811)
		(width 0.1)
		(layer "In9.Cu")
		(net 79)
	)
	(arc
		(start 178.860581 123.976697)
		(mid 179.01968 124.042598)
		(end 179.178779 123.976697)
		(width 0.1)
		(layer "In9.Cu")
		(net 79)
	)
	(arc
		(start 179.65416 122.861087)
		(mid 179.588259 122.701988)
		(end 179.65416 122.542889)
		(width 0.1)
		(layer "In9.Cu")
		(net 79)
	)
	(arc
		(start 179.95 120.2)
		(mid 180.023223 120.023223)
		(end 180.2 119.95)
		(width 0.1)
		(layer "In9.Cu")
		(net 79)
	)
	(arc
		(start 180.290558 121.906497)
		(mid 180.407716 121.623655)
		(end 180.290559 121.340812)
		(width 0.1)
		(layer "In9.Cu")
		(net 79)
	)
	(arc
		(start 178.194976 122.022184)
		(mid 177.982845 121.934314)
		(end 177.770711 122.022183)
		(width 0.1)
		(layer "In9.Cu")
		(net 79)
	)
	(arc
		(start 177.770711 122.022183)
		(mid 177.682843 122.234315)
		(end 177.770713 122.446447)
		(width 0.1)
		(layer "In9.Cu")
		(net 79)
	)
	(arc
		(start 178.38137 124.381371)
		(mid 178.264213 124.098528)
		(end 178.38137 123.815685)
		(width 0.1)
		(layer "In9.Cu")
		(net 79)
	)
	(segment
		(start 190.0005 140.9995)
		(end 190.5 140.5)
		(width 0.256)
		(layer "F.Cu")
		(net 80)
	)
	(segment
		(start 181.1 106)
		(end 181.1 107.152)
		(width 0.38)
		(layer "F.Cu")
		(net 80)
	)
	(via
		(at 190.5 140.5)
		(size 0.45)
		(drill 0.1)
		(layers "F.Cu" "B.Cu")
		(remove_unused_layers yes)
		(keep_end_layers yes)
		(zone_layer_connections)
		(net 80)
	)
	(via
		(at 181.1 107.152)
		(size 0.45)
		(drill 0.1)
		(layers "F.Cu" "B.Cu")
		(remove_unused_layers yes)
		(keep_end_layers yes)
		(zone_layer_connections)
		(net 80)
	)
	(segment
		(start 180.65 131.4)
		(end 189.2 131.4)
		(width 0.1)
		(layer "In9.Cu")
		(net 80)
	)
	(segment
		(start 178.275 129.696751)
		(end 177.956801 130.014949)
		(width 0.1)
		(layer "In9.Cu")
		(net 80)
	)
	(segment
		(start 178.628552 130.6867)
		(end 178.94675 130.368501)
		(width 0.1)
		(layer "In9.Cu")
		(net 80)
	)
	(segment
		(start 181.1 111.55)
		(end 181.1 116.9)
		(width 0.1)
		(layer "In9.Cu")
		(net 80)
	)
	(segment
		(start 179.45 118.55)
		(end 177.85 118.55)
		(width 0.1)
		(layer "In9.Cu")
		(net 80)
	)
	(segment
		(start 178.628552 130.686699)
		(end 178.628552 130.6867)
		(width 0.1)
		(layer "In9.Cu")
		(net 80)
	)
	(segment
		(start 177.3 125.35)
		(end 177.3 128.05)
		(width 0.1)
		(layer "In9.Cu")
		(net 80)
	)
	(segment
		(start 172.15 118.95)
		(end 172.15 120.2)
		(width 0.1)
		(layer "In9.Cu")
		(net 80)
	)
	(segment
		(start 180.625 109.05)
		(end 180.625 109.8)
		(width 0.1)
		(layer "In9.Cu")
		(net 80)
	)
	(segment
		(start 178.274999 129.696751)
		(end 178.275 129.696751)
		(width 0.1)
		(layer "In9.Cu")
		(net 80)
	)
	(segment
		(start 180.625 111.075)
		(end 181.1 111.55)
		(width 0.1)
		(layer "In9.Cu")
		(net 80)
	)
	(segment
		(start 179.618501 130.368502)
		(end 180.65 131.4)
		(width 0.1)
		(layer "In9.Cu")
		(net 80)
	)
	(segment
		(start 181.1 116.9)
		(end 179.45 118.55)
		(width 0.1)
		(layer "In9.Cu")
		(net 80)
	)
	(segment
		(start 172.15 120.2)
		(end 177.3 125.35)
		(width 0.1)
		(layer "In9.Cu")
		(net 80)
	)
	(segment
		(start 190 139.2)
		(end 190 140)
		(width 0.1)
		(layer "In9.Cu")
		(net 80)
	)
	(segment
		(start 190.3 132.5)
		(end 190.3 138.9)
		(width 0.1)
		(layer "In9.Cu")
		(net 80)
	)
	(segment
		(start 177.956802 130.6867)
		(end 177.956801 130.6867)
		(width 0.1)
		(layer "In9.Cu")
		(net 80)
	)
	(segment
		(start 177.3 128.05)
		(end 178.275 129.025)
		(width 0.1)
		(layer "In9.Cu")
		(net 80)
	)
	(segment
		(start 172.95 118.15)
		(end 172.15 118.95)
		(width 0.1)
		(layer "In9.Cu")
		(net 80)
	)
	(segment
		(start 180.625 107.627)
		(end 180.625 107.85)
		(width 0.1)
		(layer "In9.Cu")
		(net 80)
	)
	(segment
		(start 190.3 138.9)
		(end 190 139.2)
		(width 0.1)
		(layer "In9.Cu")
		(net 80)
	)
	(segment
		(start 181.925 108.75)
		(end 180.925 108.75)
		(width 0.1)
		(layer "In9.Cu")
		(net 80)
	)
	(segment
		(start 177.45 118.15)
		(end 172.95 118.15)
		(width 0.1)
		(layer "In9.Cu")
		(net 80)
	)
	(segment
		(start 190 140)
		(end 190.5 140.5)
		(width 0.1)
		(layer "In9.Cu")
		(net 80)
	)
	(segment
		(start 180.925 110.1)
		(end 181.933205 110.1)
		(width 0.1)
		(layer "In9.Cu")
		(net 80)
	)
	(segment
		(start 189.2 131.4)
		(end 190.3 132.5)
		(width 0.1)
		(layer "In9.Cu")
		(net 80)
	)
	(segment
		(start 181.1 107.152)
		(end 180.625 107.627)
		(width 0.1)
		(layer "In9.Cu")
		(net 80)
	)
	(segment
		(start 181.933205 110.7)
		(end 180.925 110.7)
		(width 0.1)
		(layer "In9.Cu")
		(net 80)
	)
	(segment
		(start 180.925 108.15)
		(end 181.925 108.15)
		(width 0.1)
		(layer "In9.Cu")
		(net 80)
	)
	(segment
		(start 180.625 111)
		(end 180.625 111.075)
		(width 0.1)
		(layer "In9.Cu")
		(net 80)
	)
	(segment
		(start 177.85 118.55)
		(end 177.45 118.15)
		(width 0.1)
		(layer "In9.Cu")
		(net 80)
	)
	(arc
		(start 182.233205 110.4)
		(mid 182.145337 110.612132)
		(end 181.933205 110.7)
		(width 0.1)
		(layer "In9.Cu")
		(net 80)
	)
	(arc
		(start 178.94675 130.368501)
		(mid 179.282626 130.229377)
		(end 179.618501 130.368502)
		(width 0.1)
		(layer "In9.Cu")
		(net 80)
	)
	(arc
		(start 177.956801 130.014949)
		(mid 177.817677 130.350825)
		(end 177.956802 130.6867)
		(width 0.1)
		(layer "In9.Cu")
		(net 80)
	)
	(arc
		(start 180.925 110.7)
		(mid 180.712868 110.787868)
		(end 180.625 111)
		(width 0.1)
		(layer "In9.Cu")
		(net 80)
	)
	(arc
		(start 181.925 108.15)
		(mid 182.137132 108.237868)
		(end 182.225 108.45)
		(width 0.1)
		(layer "In9.Cu")
		(net 80)
	)
	(arc
		(start 180.925 108.75)
		(mid 180.712868 108.837868)
		(end 180.625 109.05)
		(width 0.1)
		(layer "In9.Cu")
		(net 80)
	)
	(arc
		(start 177.956801 130.6867)
		(mid 178.292677 130.825824)
		(end 178.628552 130.686699)
		(width 0.1)
		(layer "In9.Cu")
		(net 80)
	)
	(arc
		(start 178.275 129.025)
		(mid 178.414124 129.360876)
		(end 178.274999 129.696751)
		(width 0.1)
		(layer "In9.Cu")
		(net 80)
	)
	(arc
		(start 180.625 109.8)
		(mid 180.712868 110.012132)
		(end 180.925 110.1)
		(width 0.1)
		(layer "In9.Cu")
		(net 80)
	)
	(arc
		(start 182.225 108.45)
		(mid 182.137132 108.662132)
		(end 181.925 108.75)
		(width 0.1)
		(layer "In9.Cu")
		(net 80)
	)
	(arc
		(start 180.625 107.85)
		(mid 180.712868 108.062132)
		(end 180.925 108.15)
		(width 0.1)
		(layer "In9.Cu")
		(net 80)
	)
	(arc
		(start 181.933205 110.1)
		(mid 182.145337 110.187868)
		(end 182.233205 110.4)
		(width 0.1)
		(layer "In9.Cu")
		(net 80)
	)
	(segment
		(start 179.4 106)
		(end 179.4 107.152)
		(width 0.38)
		(layer "F.Cu")
		(net 81)
	)
	(segment
		(start 189.0005 140.9995)
		(end 189.5 140.5)
		(width 0.256)
		(layer "F.Cu")
		(net 81)
	)
	(via
		(at 189.5 140.5)
		(size 0.45)
		(drill 0.1)
		(layers "F.Cu" "B.Cu")
		(remove_unused_layers yes)
		(keep_end_layers yes)
		(zone_layer_connections)
		(net 81)
	)
	(via
		(at 179.4 107.152)
		(size 0.45)
		(drill 0.1)
		(layers "F.Cu" "B.Cu")
		(remove_unused_layers yes)
		(keep_end_layers yes)
		(zone_layer_connections)
		(net 81)
	)
	(segment
		(start 176.9 133.25)
		(end 187.55 133.25)
		(width 0.1)
		(layer "In9.Cu")
		(net 81)
	)
	(segment
		(start 178.875 111.0375)
		(end 179.4 111.5625)
		(width 0.1)
		(layer "In9.Cu")
		(net 81)
	)
	(segment
		(start 187.55 133.25)
		(end 189 134.7)
		(width 0.1)
		(layer "In9.Cu")
		(net 81)
	)
	(segment
		(start 178.875 107.677)
		(end 178.875 107.85)
		(width 0.1)
		(layer "In9.Cu")
		(net 81)
	)
	(segment
		(start 179.575 108.75)
		(end 179.175 108.75)
		(width 0.1)
		(layer "In9.Cu")
		(net 81)
	)
	(segment
		(start 178.875 109.05)
		(end 178.875 111.0375)
		(width 0.1)
		(layer "In9.Cu")
		(net 81)
	)
	(segment
		(start 169.9 120.35)
		(end 169.9 120.6)
		(width 0.1)
		(layer "In9.Cu")
		(net 81)
	)
	(segment
		(start 170.437297 120.849999)
		(end 170.437296 120.85)
		(width 0.1)
		(layer "In9.Cu")
		(net 81)
	)
	(segment
		(start 171.221016 117.680024)
		(end 171.079595 117.538603)
		(width 0.1)
		(layer "In9.Cu")
		(net 81)
	)
	(segment
		(start 170.125 118.175)
		(end 169.9 118.4)
		(width 0.1)
		(layer "In9.Cu")
		(net 81)
	)
	(segment
		(start 170.790849 121.490849)
		(end 175.4 126.1)
		(width 0.1)
		(layer "In9.Cu")
		(net 81)
	)
	(segment
		(start 170.902817 117.998222)
		(end 170.902817 117.998221)
		(width 0.1)
		(layer "In9.Cu")
		(net 81)
	)
	(segment
		(start 189 140)
		(end 189.5 140.5)
		(width 0.1)
		(layer "In9.Cu")
		(net 81)
	)
	(segment
		(start 171.539214 117.361825)
		(end 171.539214 117.361824)
		(width 0.1)
		(layer "In9.Cu")
		(net 81)
	)
	(segment
		(start 170.761395 117.8568)
		(end 170.902817 117.998222)
		(width 0.1)
		(layer "In9.Cu")
		(net 81)
	)
	(segment
		(start 170.125 119.675)
		(end 170.675 119.675)
		(width 0.1)
		(layer "In9.Cu")
		(net 81)
	)
	(segment
		(start 169.9 118.4)
		(end 169.9 118.55)
		(width 0.1)
		(layer "In9.Cu")
		(net 81)
	)
	(segment
		(start 169.9 120.6)
		(end 170.15 120.85)
		(width 0.1)
		(layer "In9.Cu")
		(net 81)
	)
	(segment
		(start 171.55 116.75)
		(end 171.397792 116.902205)
		(width 0.1)
		(layer "In9.Cu")
		(net 81)
	)
	(segment
		(start 170.584619 118.316421)
		(end 170.443198 118.175)
		(width 0.1)
		(layer "In9.Cu")
		(net 81)
	)
	(segment
		(start 179.4 107.152)
		(end 178.875 107.677)
		(width 0.1)
		(layer "In9.Cu")
		(net 81)
	)
	(segment
		(start 171.397792 117.220403)
		(end 171.539214 117.361825)
		(width 0.1)
		(layer "In9.Cu")
		(net 81)
	)
	(segment
		(start 189 134.7)
		(end 189 140)
		(width 0.1)
		(layer "In9.Cu")
		(net 81)
	)
	(segment
		(start 175.4 131.75)
		(end 176.9 133.25)
		(width 0.1)
		(layer "In9.Cu")
		(net 81)
	)
	(segment
		(start 170.761397 117.538603)
		(end 170.761395 117.538602)
		(width 0.1)
		(layer "In9.Cu")
		(net 81)
	)
	(segment
		(start 177.05 116.75)
		(end 171.55 116.75)
		(width 0.1)
		(layer "In9.Cu")
		(net 81)
	)
	(segment
		(start 170.125 118.775)
		(end 170.675 118.775)
		(width 0.1)
		(layer "In9.Cu")
		(net 81)
	)
	(segment
		(start 179.175 108.15)
		(end 179.575 108.15)
		(width 0.1)
		(layer "In9.Cu")
		(net 81)
	)
	(segment
		(start 175.4 126.1)
		(end 175.4 131.75)
		(width 0.1)
		(layer "In9.Cu")
		(net 81)
	)
	(segment
		(start 170.724592 120.85)
		(end 170.790849 120.916257)
		(width 0.1)
		(layer "In9.Cu")
		(net 81)
	)
	(segment
		(start 179.4 114.4)
		(end 177.05 116.75)
		(width 0.1)
		(layer "In9.Cu")
		(net 81)
	)
	(segment
		(start 170.675 119.225)
		(end 170.125 119.225)
		(width 0.1)
		(layer "In9.Cu")
		(net 81)
	)
	(segment
		(start 179.4 111.5625)
		(end 179.4 114.4)
		(width 0.1)
		(layer "In9.Cu")
		(net 81)
	)
	(segment
		(start 170.675 120.125)
		(end 170.125 120.125)
		(width 0.1)
		(layer "In9.Cu")
		(net 81)
	)
	(arc
		(start 171.539214 117.680024)
		(mid 171.380115 117.745925)
		(end 171.221016 117.680024)
		(width 0.1)
		(layer "In9.Cu")
		(net 81)
	)
	(arc
		(start 169.9 118.55)
		(mid 169.965901 118.709099)
		(end 170.125 118.775)
		(width 0.1)
		(layer "In9.Cu")
		(net 81)
	)
	(arc
		(start 179.175 108.75)
		(mid 178.962868 108.837868)
		(end 178.875 109.05)
		(width 0.1)
		(layer "In9.Cu")
		(net 81)
	)
	(arc
		(start 171.397792 116.902205)
		(mid 171.331891 117.061304)
		(end 171.397792 117.220403)
		(width 0.1)
		(layer "In9.Cu")
		(net 81)
	)
	(arc
		(start 170.790849 120.916257)
		(mid 170.850351 121.059906)
		(end 170.790849 121.203553)
		(width 0.1)
		(layer "In9.Cu")
		(net 81)
	)
	(arc
		(start 170.125 119.225)
		(mid 169.965901 119.290901)
		(end 169.9 119.45)
		(width 0.1)
		(layer "In9.Cu")
		(net 81)
	)
	(arc
		(start 171.539214 117.361824)
		(mid 171.605115 117.520924)
		(end 171.539214 117.680024)
		(width 0.1)
		(layer "In9.Cu")
		(net 81)
	)
	(arc
		(start 169.9 119.45)
		(mid 169.965901 119.609099)
		(end 170.125 119.675)
		(width 0.1)
		(layer "In9.Cu")
		(net 81)
	)
	(arc
		(start 170.15 120.85)
		(mid 170.293649 120.909501)
		(end 170.437297 120.849999)
		(width 0.1)
		(layer "In9.Cu")
		(net 81)
	)
	(arc
		(start 170.790849 121.203553)
		(mid 170.731349 121.347202)
		(end 170.790849 121.490849)
		(width 0.1)
		(layer "In9.Cu")
		(net 81)
	)
	(arc
		(start 170.437296 120.85)
		(mid 170.580945 120.7905)
		(end 170.724592 120.85)
		(width 0.1)
		(layer "In9.Cu")
		(net 81)
	)
	(arc
		(start 170.902817 117.998221)
		(mid 170.968718 118.157321)
		(end 170.902817 118.316421)
		(width 0.1)
		(layer "In9.Cu")
		(net 81)
	)
	(arc
		(start 170.902817 118.316421)
		(mid 170.743718 118.382322)
		(end 170.584619 118.316421)
		(width 0.1)
		(layer "In9.Cu")
		(net 81)
	)
	(arc
		(start 179.875 108.45)
		(mid 179.787132 108.662132)
		(end 179.575 108.75)
		(width 0.1)
		(layer "In9.Cu")
		(net 81)
	)
	(arc
		(start 170.125 120.125)
		(mid 169.965901 120.190901)
		(end 169.9 120.35)
		(width 0.1)
		(layer "In9.Cu")
		(net 81)
	)
	(arc
		(start 170.9 119.9)
		(mid 170.834099 120.059099)
		(end 170.675 120.125)
		(width 0.1)
		(layer "In9.Cu")
		(net 81)
	)
	(arc
		(start 170.675 118.775)
		(mid 170.834099 118.840901)
		(end 170.9 119)
		(width 0.1)
		(layer "In9.Cu")
		(net 81)
	)
	(arc
		(start 178.875 107.85)
		(mid 178.962868 108.062132)
		(end 179.175 108.15)
		(width 0.1)
		(layer "In9.Cu")
		(net 81)
	)
	(arc
		(start 179.575 108.15)
		(mid 179.787132 108.237868)
		(end 179.875 108.45)
		(width 0.1)
		(layer "In9.Cu")
		(net 81)
	)
	(arc
		(start 170.443198 118.175)
		(mid 170.284099 118.109099)
		(end 170.125 118.175)
		(width 0.1)
		(layer "In9.Cu")
		(net 81)
	)
	(arc
		(start 170.9 119)
		(mid 170.834099 119.159099)
		(end 170.675 119.225)
		(width 0.1)
		(layer "In9.Cu")
		(net 81)
	)
	(arc
		(start 170.761395 117.538602)
		(mid 170.695494 117.697701)
		(end 170.761395 117.8568)
		(width 0.1)
		(layer "In9.Cu")
		(net 81)
	)
	(arc
		(start 171.079595 117.538603)
		(mid 170.920496 117.472702)
		(end 170.761397 117.538603)
		(width 0.1)
		(layer "In9.Cu")
		(net 81)
	)
	(arc
		(start 170.675 119.675)
		(mid 170.834099 119.740901)
		(end 170.9 119.9)
		(width 0.1)
		(layer "In9.Cu")
		(net 81)
	)
	(segment
		(start 187.9995 141.9995)
		(end 187.5 141.5)
		(width 0.256)
		(layer "F.Cu")
		(net 82)
	)
	(segment
		(start 177.7 106)
		(end 177.7 107.152)
		(width 0.38)
		(layer "F.Cu")
		(net 82)
	)
	(via
		(at 187.5 141.5)
		(size 0.45)
		(drill 0.1)
		(layers "F.Cu" "B.Cu")
		(remove_unused_layers yes)
		(keep_end_layers yes)
		(zone_layer_connections)
		(net 82)
	)
	(via
		(at 177.7 107.152)
		(size 0.45)
		(drill 0.1)
		(layers "F.Cu" "B.Cu")
		(remove_unused_layers yes)
		(keep_end_layers yes)
		(zone_layer_connections)
		(net 82)
	)
	(segment
		(start 177.031372 113.218628)
		(end 177.03137 113.218627)
		(width 0.1)
		(layer "In9.Cu")
		(net 82)
	)
	(segment
		(start 177.225 110.275)
		(end 177.7 110.75)
		(width 0.1)
		(layer "In9.Cu")
		(net 82)
	)
	(segment
		(start 177.03137 113.218627)
		(end 177.03137 113.218628)
		(width 0.1)
		(layer "In9.Cu")
		(net 82)
	)
	(segment
		(start 177.513075 114.266018)
		(end 177.513074 114.266018)
		(width 0.1)
		(layer "In9.Cu")
		(net 82)
	)
	(segment
		(start 175.35 115.35)
		(end 170.5 115.35)
		(width 0.1)
		(layer "In9.Cu")
		(net 82)
	)
	(segment
		(start 176.465684 114.067156)
		(end 176.947372 114.548844)
		(width 0.1)
		(layer "In9.Cu")
		(net 82)
	)
	(segment
		(start 178.078771 113.700342)
		(end 178.07877 113.700342)
		(width 0.1)
		(layer "In9.Cu")
		(net 82)
	)
	(segment
		(start 176.947372 114.831687)
		(end 176.947371 114.831687)
		(width 0.1)
		(layer "In9.Cu")
		(net 82)
	)
	(segment
		(start 170.5 115.35)
		(end 168.25 117.6)
		(width 0.1)
		(layer "In9.Cu")
		(net 82)
	)
	(segment
		(start 176.465686 113.784314)
		(end 176.465684 113.784313)
		(width 0.1)
		(layer "In9.Cu")
		(net 82)
	)
	(segment
		(start 188 139.075)
		(end 188 141)
		(width 0.1)
		(layer "In9.Cu")
		(net 82)
	)
	(segment
		(start 176.664529 114.831687)
		(end 176.182842 114.35)
		(width 0.1)
		(layer "In9.Cu")
		(net 82)
	)
	(segment
		(start 173.5 132.65)
		(end 176.15 135.3)
		(width 0.1)
		(layer "In9.Cu")
		(net 82)
	)
	(segment
		(start 178.078771 113.417499)
		(end 178.078771 113.417498)
		(width 0.1)
		(layer "In9.Cu")
		(net 82)
	)
	(segment
		(start 177.513075 113.983175)
		(end 177.513075 113.983174)
		(width 0.1)
		(layer "In9.Cu")
		(net 82)
	)
	(segment
		(start 176.15 135.3)
		(end 186.1 135.3)
		(width 0.1)
		(layer "In9.Cu")
		(net 82)
	)
	(segment
		(start 177.03137 113.50147)
		(end 177.513075 113.983175)
		(width 0.1)
		(layer "In9.Cu")
		(net 82)
	)
	(segment
		(start 177.795928 113.700342)
		(end 177.314214 113.218628)
		(width 0.1)
		(layer "In9.Cu")
		(net 82)
	)
	(segment
		(start 188 141)
		(end 187.5 141.5)
		(width 0.1)
		(layer "In9.Cu")
		(net 82)
	)
	(segment
		(start 175.75 114.5)
		(end 175.75 114.95)
		(width 0.1)
		(layer "In9.Cu")
		(net 82)
	)
	(segment
		(start 177.597056 112.935784)
		(end 178.078771 113.417499)
		(width 0.1)
		(layer "In9.Cu")
		(net 82)
	)
	(segment
		(start 177.7 112.55)
		(end 177.597056 112.652942)
		(width 0.1)
		(layer "In9.Cu")
		(net 82)
	)
	(segment
		(start 177.7 107.152)
		(end 177.225 107.627)
		(width 0.1)
		(layer "In9.Cu")
		(net 82)
	)
	(segment
		(start 177.230232 114.266018)
		(end 176.748528 113.784314)
		(width 0.1)
		(layer "In9.Cu")
		(net 82)
	)
	(segment
		(start 186.1 135.3)
		(end 187.725 136.925)
		(width 0.1)
		(layer "In9.Cu")
		(net 82)
	)
	(segment
		(start 177.225 107.627)
		(end 177.225 110.275)
		(width 0.1)
		(layer "In9.Cu")
		(net 82)
	)
	(segment
		(start 173.5 126.9)
		(end 173.5 132.65)
		(width 0.1)
		(layer "In9.Cu")
		(net 82)
	)
	(segment
		(start 176.947372 114.548844)
		(end 176.947372 114.548843)
		(width 0.1)
		(layer "In9.Cu")
		(net 82)
	)
	(segment
		(start 187.725 138.8)
		(end 188 139.075)
		(width 0.1)
		(layer "In9.Cu")
		(net 82)
	)
	(segment
		(start 175.9 114.35)
		(end 175.75 114.5)
		(width 0.1)
		(layer "In9.Cu")
		(net 82)
	)
	(segment
		(start 168.25 121.65)
		(end 173.5 126.9)
		(width 0.1)
		(layer "In9.Cu")
		(net 82)
	)
	(segment
		(start 187.725 136.925)
		(end 187.725 138.8)
		(width 0.1)
		(layer "In9.Cu")
		(net 82)
	)
	(segment
		(start 177.7 110.75)
		(end 177.7 112.55)
		(width 0.1)
		(layer "In9.Cu")
		(net 82)
	)
	(segment
		(start 176.465684 113.784313)
		(end 176.465684 113.784314)
		(width 0.1)
		(layer "In9.Cu")
		(net 82)
	)
	(segment
		(start 175.75 114.95)
		(end 175.35 115.35)
		(width 0.1)
		(layer "In9.Cu")
		(net 82)
	)
	(segment
		(start 168.25 117.6)
		(end 168.25 121.65)
		(width 0.1)
		(layer "In9.Cu")
		(net 82)
	)
	(arc
		(start 177.513074 114.266018)
		(mid 177.371653 114.324596)
		(end 177.230232 114.266018)
		(width 0.1)
		(layer "In9.Cu")
		(net 82)
	)
	(arc
		(start 177.03137 113.218628)
		(mid 176.972792 113.360049)
		(end 177.03137 113.50147)
		(width 0.1)
		(layer "In9.Cu")
		(net 82)
	)
	(arc
		(start 176.748528 113.784314)
		(mid 176.607107 113.725736)
		(end 176.465686 113.784314)
		(width 0.1)
		(layer "In9.Cu")
		(net 82)
	)
	(arc
		(start 176.947371 114.831687)
		(mid 176.80595 114.890265)
		(end 176.664529 114.831687)
		(width 0.1)
		(layer "In9.Cu")
		(net 82)
	)
	(arc
		(start 177.513075 113.983174)
		(mid 177.571654 114.124596)
		(end 177.513075 114.266018)
		(width 0.1)
		(layer "In9.Cu")
		(net 82)
	)
	(arc
		(start 178.078771 113.417498)
		(mid 178.13735 113.55892)
		(end 178.078771 113.700342)
		(width 0.1)
		(layer "In9.Cu")
		(net 82)
	)
	(arc
		(start 176.465684 113.784314)
		(mid 176.407106 113.925735)
		(end 176.465684 114.067156)
		(width 0.1)
		(layer "In9.Cu")
		(net 82)
	)
	(arc
		(start 176.182842 114.35)
		(mid 176.041421 114.291422)
		(end 175.9 114.35)
		(width 0.1)
		(layer "In9.Cu")
		(net 82)
	)
	(arc
		(start 177.314214 113.218628)
		(mid 177.172793 113.16005)
		(end 177.031372 113.218628)
		(width 0.1)
		(layer "In9.Cu")
		(net 82)
	)
	(arc
		(start 176.947372 114.548843)
		(mid 177.005951 114.690265)
		(end 176.947372 114.831687)
		(width 0.1)
		(layer "In9.Cu")
		(net 82)
	)
	(arc
		(start 177.597056 112.652942)
		(mid 177.538478 112.794363)
		(end 177.597056 112.935784)
		(width 0.1)
		(layer "In9.Cu")
		(net 82)
	)
	(arc
		(start 178.07877 113.700342)
		(mid 177.937349 113.75892)
		(end 177.795928 113.700342)
		(width 0.1)
		(layer "In9.Cu")
		(net 82)
	)
	(segment
		(start 191.0005 141.9995)
		(end 191.5 141.5)
		(width 0.256)
		(layer "F.Cu")
		(net 83)
	)
	(segment
		(start 176 106)
		(end 176 107.152)
		(width 0.38)
		(layer "F.Cu")
		(net 83)
	)
	(via
		(at 191.5 141.5)
		(size 0.45)
		(drill 0.1)
		(layers "F.Cu" "B.Cu")
		(remove_unused_layers yes)
		(keep_end_layers yes)
		(zone_layer_connections)
		(net 83)
	)
	(via
		(at 176 107.152)
		(size 0.45)
		(drill 0.1)
		(layers "F.Cu" "B.Cu")
		(remove_unused_layers yes)
		(keep_end_layers yes)
		(zone_layer_connections)
		(net 83)
	)
	(segment
		(start 176 107.152)
		(end 175.998 107.152)
		(width 0.1)
		(layer "In9.Cu")
		(net 83)
	)
	(segment
		(start 176 112.25)
		(end 174.6 113.65)
		(width 0.1)
		(layer "In9.Cu")
		(net 83)
	)
	(segment
		(start 184.36 137.2)
		(end 186.01 138.85)
		(width 0.1)
		(layer "In9.Cu")
		(net 83)
	)
	(segment
		(start 175.998 107.152)
		(end 175.5 107.65)
		(width 0.1)
		(layer "In9.Cu")
		(net 83)
	)
	(segment
		(start 171.7 128.05)
		(end 171.7 134.4)
		(width 0.1)
		(layer "In9.Cu")
		(net 83)
	)
	(segment
		(start 189.33 143)
		(end 190.33 142)
		(width 0.1)
		(layer "In9.Cu")
		(net 83)
	)
	(segment
		(start 186.01 142.72)
		(end 186.29 143)
		(width 0.1)
		(layer "In9.Cu")
		(net 83)
	)
	(segment
		(start 191 142)
		(end 191.5 141.5)
		(width 0.1)
		(layer "In9.Cu")
		(net 83)
	)
	(segment
		(start 166.4 116.65)
		(end 166.4 122.75)
		(width 0.1)
		(layer "In9.Cu")
		(net 83)
	)
	(segment
		(start 166.4 122.75)
		(end 171.7 128.05)
		(width 0.1)
		(layer "In9.Cu")
		(net 83)
	)
	(segment
		(start 186.01 138.85)
		(end 186.01 142.72)
		(width 0.1)
		(layer "In9.Cu")
		(net 83)
	)
	(segment
		(start 190.33 142)
		(end 191 142)
		(width 0.1)
		(layer "In9.Cu")
		(net 83)
	)
	(segment
		(start 176 110.575)
		(end 176 112.25)
		(width 0.1)
		(layer "In9.Cu")
		(net 83)
	)
	(segment
		(start 174.5 137.2)
		(end 184.36 137.2)
		(width 0.1)
		(layer "In9.Cu")
		(net 83)
	)
	(segment
		(start 174.6 113.65)
		(end 169.4 113.65)
		(width 0.1)
		(layer "In9.Cu")
		(net 83)
	)
	(segment
		(start 175.5 107.65)
		(end 175.5 110.075)
		(width 0.1)
		(layer "In9.Cu")
		(net 83)
	)
	(segment
		(start 171.7 134.4)
		(end 174.5 137.2)
		(width 0.1)
		(layer "In9.Cu")
		(net 83)
	)
	(segment
		(start 169.4 113.65)
		(end 166.4 116.65)
		(width 0.1)
		(layer "In9.Cu")
		(net 83)
	)
	(segment
		(start 186.29 143)
		(end 189.33 143)
		(width 0.1)
		(layer "In9.Cu")
		(net 83)
	)
	(segment
		(start 175.5 110.075)
		(end 176 110.575)
		(width 0.1)
		(layer "In9.Cu")
		(net 83)
	)
	(segment
		(start 174.3 106)
		(end 174.3 107.152)
		(width 0.38)
		(layer "F.Cu")
		(net 84)
	)
	(segment
		(start 192.0005 139.999501)
		(end 192.5 139.5)
		(width 0.256)
		(layer "F.Cu")
		(net 84)
	)
	(via
		(at 174.3 107.152)
		(size 0.45)
		(drill 0.1)
		(layers "F.Cu" "B.Cu")
		(remove_unused_layers yes)
		(keep_end_layers yes)
		(zone_layer_connections)
		(net 84)
	)
	(via
		(at 192.5 139.5)
		(size 0.45)
		(drill 0.1)
		(layers "F.Cu" "B.Cu")
		(remove_unused_layers yes)
		(keep_end_layers yes)
		(zone_layer_connections)
		(net 84)
	)
	(segment
		(start 183.75 117.9)
		(end 183.75 112.7)
		(width 0.148)
		(layer "In9.Cu")
		(net 84)
	)
	(segment
		(start 183.480212 111.581684)
		(end 183.480214 111.581683)
		(width 0.148)
		(layer "In9.Cu")
		(net 84)
	)
	(segment
		(start 184.598531 111.851472)
		(end 184.59853 111.851471)
		(width 0.148)
		(layer "In9.Cu")
		(net 84)
	)
	(segment
		(start 175.402 106.05)
		(end 174.3 107.152)
		(width 0.148)
		(layer "In9.Cu")
		(net 84)
	)
	(segment
		(start 185.5 106.05)
		(end 175.402 106.05)
		(width 0.148)
		(layer "In9.Cu")
		(net 84)
	)
	(segment
		(start 185.44706 111.002941)
		(end 186 110.45)
		(width 0.148)
		(layer "In9.Cu")
		(net 84)
	)
	(segment
		(start 192.5 139.5)
		(end 192.5 129.55)
		(width 0.148)
		(layer "In9.Cu")
		(net 84)
	)
	(segment
		(start 184.752972 110.733117)
		(end 185.022797 111.002942)
		(width 0.148)
		(layer "In9.Cu")
		(net 84)
	)
	(segment
		(start 181.2 120.45)
		(end 183.75 117.9)
		(width 0.148)
		(layer "In9.Cu")
		(net 84)
	)
	(segment
		(start 192.5 129.55)
		(end 191.25 128.3)
		(width 0.148)
		(layer "In9.Cu")
		(net 84)
	)
	(segment
		(start 184.328706 110.733118)
		(end 184.328708 110.733117)
		(width 0.148)
		(layer "In9.Cu")
		(net 84)
	)
	(segment
		(start 186 110.45)
		(end 186 106.55)
		(width 0.148)
		(layer "In9.Cu")
		(net 84)
	)
	(segment
		(start 180 124.55)
		(end 181.2 123.35)
		(width 0.148)
		(layer "In9.Cu")
		(net 84)
	)
	(segment
		(start 183.904478 111.581683)
		(end 184.174267 111.851472)
		(width 0.148)
		(layer "In9.Cu")
		(net 84)
	)
	(segment
		(start 181.25 128.3)
		(end 180 127.05)
		(width 0.148)
		(layer "In9.Cu")
		(net 84)
	)
	(segment
		(start 186 106.55)
		(end 185.5 106.05)
		(width 0.148)
		(layer "In9.Cu")
		(net 84)
	)
	(segment
		(start 184.59853 111.427206)
		(end 184.328706 111.157382)
		(width 0.148)
		(layer "In9.Cu")
		(net 84)
	)
	(segment
		(start 184.59853 111.851471)
		(end 184.59853 111.85147)
		(width 0.148)
		(layer "In9.Cu")
		(net 84)
	)
	(segment
		(start 180 127.05)
		(end 180 124.55)
		(width 0.148)
		(layer "In9.Cu")
		(net 84)
	)
	(segment
		(start 181.2 123.35)
		(end 181.2 120.45)
		(width 0.148)
		(layer "In9.Cu")
		(net 84)
	)
	(segment
		(start 191.25 128.3)
		(end 181.25 128.3)
		(width 0.148)
		(layer "In9.Cu")
		(net 84)
	)
	(segment
		(start 185.447061 111.002942)
		(end 185.44706 111.002941)
		(width 0.148)
		(layer "In9.Cu")
		(net 84)
	)
	(segment
		(start 183.75 112.275736)
		(end 183.480212 112.005948)
		(width 0.148)
		(layer "In9.Cu")
		(net 84)
	)
	(arc
		(start 184.59853 111.85147)
		(mid 184.686398 111.639338)
		(end 184.59853 111.427206)
		(width 0.148)
		(layer "In9.Cu")
		(net 84)
	)
	(arc
		(start 184.328708 110.733117)
		(mid 184.54084 110.645249)
		(end 184.752972 110.733117)
		(width 0.148)
		(layer "In9.Cu")
		(net 84)
	)
	(arc
		(start 185.022797 111.002942)
		(mid 185.234929 111.09081)
		(end 185.447061 111.002942)
		(width 0.148)
		(layer "In9.Cu")
		(net 84)
	)
	(arc
		(start 183.480214 111.581683)
		(mid 183.692346 111.493815)
		(end 183.904478 111.581683)
		(width 0.148)
		(layer "In9.Cu")
		(net 84)
	)
	(arc
		(start 184.174267 111.851472)
		(mid 184.386399 111.93934)
		(end 184.598531 111.851472)
		(width 0.148)
		(layer "In9.Cu")
		(net 84)
	)
	(arc
		(start 184.328706 111.157382)
		(mid 184.240838 110.94525)
		(end 184.328706 110.733118)
		(width 0.148)
		(layer "In9.Cu")
		(net 84)
	)
	(arc
		(start 183.480212 112.005948)
		(mid 183.392344 111.793816)
		(end 183.480212 111.581684)
		(width 0.148)
		(layer "In9.Cu")
		(net 84)
	)
	(arc
		(start 183.75 112.7)
		(mid 183.837868 112.487868)
		(end 183.75 112.275736)
		(width 0.148)
		(layer "In9.Cu")
		(net 84)
	)
	(segment
		(start 173.45 106)
		(end 173.45 107.152)
		(width 0.38)
		(layer "F.Cu")
		(net 85)
	)
	(segment
		(start 193.0005 139.9995)
		(end 193.5 139.5)
		(width 0.256)
		(layer "F.Cu")
		(net 85)
	)
	(via
		(at 173.45 107.152)
		(size 0.45)
		(drill 0.1)
		(layers "F.Cu" "B.Cu")
		(remove_unused_layers yes)
		(keep_end_layers yes)
		(zone_layer_connections)
		(net 85)
	)
	(via
		(at 193.5 139.5)
		(size 0.45)
		(drill 0.1)
		(layers "F.Cu" "B.Cu")
		(remove_unused_layers yes)
		(keep_end_layers yes)
		(zone_layer_connections)
		(net 85)
	)
	(segment
		(start 191.65 127.3)
		(end 193.25 128.9)
		(width 0.148)
		(layer "In9.Cu")
		(net 85)
	)
	(segment
		(start 174.5 105.4)
		(end 186 105.4)
		(width 0.148)
		(layer "In9.Cu")
		(net 85)
	)
	(segment
		(start 184.65 118.4)
		(end 182.05 121)
		(width 0.148)
		(layer "In9.Cu")
		(net 85)
	)
	(segment
		(start 193.25 128.9)
		(end 193.25 139.25)
		(width 0.148)
		(layer "In9.Cu")
		(net 85)
	)
	(segment
		(start 186 105.4)
		(end 187.2 106.6)
		(width 0.148)
		(layer "In9.Cu")
		(net 85)
	)
	(segment
		(start 187.2 106.6)
		(end 187.2 110.55)
		(width 0.148)
		(layer "In9.Cu")
		(net 85)
	)
	(segment
		(start 184.65 113.1)
		(end 184.65 118.4)
		(width 0.148)
		(layer "In9.Cu")
		(net 85)
	)
	(segment
		(start 173.45 106.45)
		(end 174.5 105.4)
		(width 0.148)
		(layer "In9.Cu")
		(net 85)
	)
	(segment
		(start 182.05 121)
		(end 182.05 123.8)
		(width 0.148)
		(layer "In9.Cu")
		(net 85)
	)
	(segment
		(start 187.2 110.55)
		(end 184.65 113.1)
		(width 0.148)
		(layer "In9.Cu")
		(net 85)
	)
	(segment
		(start 173.45 107.152)
		(end 173.45 106.45)
		(width 0.148)
		(layer "In9.Cu")
		(net 85)
	)
	(segment
		(start 193.25 139.25)
		(end 193.5 139.5)
		(width 0.148)
		(layer "In9.Cu")
		(net 85)
	)
	(segment
		(start 181.8 127.3)
		(end 191.65 127.3)
		(width 0.148)
		(layer "In9.Cu")
		(net 85)
	)
	(segment
		(start 180.95 124.9)
		(end 180.95 126.45)
		(width 0.148)
		(layer "In9.Cu")
		(net 85)
	)
	(segment
		(start 182.05 123.8)
		(end 180.95 124.9)
		(width 0.148)
		(layer "In9.Cu")
		(net 85)
	)
	(segment
		(start 180.95 126.45)
		(end 181.8 127.3)
		(width 0.148)
		(layer "In9.Cu")
		(net 85)
	)
	(segment
		(start 132.038803 131.202899)
		(end 130.974299 132.267403)
		(width 0.16)
		(layer "F.Cu")
		(net 86)
	)
	(segment
		(start 130.483167 129.647262)
		(end 130.483167 129.647263)
		(width 0.16)
		(layer "F.Cu")
		(net 86)
	)
	(segment
		(start 120.903309 128.827487)
		(end 117.407486 128.827486)
		(width 0.16)
		(layer "F.Cu")
		(net 86)
	)
	(segment
		(start 129.781209 129.790606)
		(end 129.78121 129.790607)
		(width 0.16)
		(layer "F.Cu")
		(net 86)
	)
	(segment
		(start 134.427 139.735)
		(end 134.427 139.285)
		(width 0.16)
		(layer "F.Cu")
		(net 86)
	)
	(segment
		(start 117.407486 128.827486)
		(end 117.105 128.525)
		(width 0.16)
		(layer "F.Cu")
		(net 86)
	)
	(segment
		(start 132.67328 133.679697)
		(end 132.67328 133.679698)
		(width 0.16)
		(layer "F.Cu")
		(net 86)
	)
	(segment
		(start 131.971321 133.82304)
		(end 131.971319 133.823038)
		(width 0.16)
		(layer "F.Cu")
		(net 86)
	)
	(segment
		(start 127.02169 128.827486)
		(end 126.014204 127.82)
		(width 0.16)
		(layer "F.Cu")
		(net 86)
	)
	(segment
		(start 130.415684 131.708787)
		(end 131.480188 130.644284)
		(width 0.16)
		(layer "F.Cu")
		(net 86)
	)
	(segment
		(start 128.81809 128.827486)
		(end 127.02169 128.827486)
		(width 0.16)
		(layer "F.Cu")
		(net 86)
	)
	(segment
		(start 117.334513 127.865487)
		(end 118.114999 127.865487)
		(width 0.16)
		(layer "F.Cu")
		(net 86)
	)
	(segment
		(start 133.035824 131.2029)
		(end 133.035824 131.202899)
		(width 0.16)
		(layer "F.Cu")
		(net 86)
	)
	(segment
		(start 117.105 128.525)
		(end 117.105 128.095)
		(width 0.16)
		(layer "F.Cu")
		(net 86)
	)
	(segment
		(start 134.332 134.341396)
		(end 133.6703 133.679697)
		(width 0.16)
		(layer "F.Cu")
		(net 86)
	)
	(segment
		(start 121.910796 127.82)
		(end 120.903309 128.827487)
		(width 0.16)
		(layer "F.Cu")
		(net 86)
	)
	(segment
		(start 132.67328 133.679698)
		(end 132.529935 133.82304)
		(width 0.16)
		(layer "F.Cu")
		(net 86)
	)
	(segment
		(start 129.78121 129.790607)
		(end 128.81809 128.827486)
		(width 0.16)
		(layer "F.Cu")
		(net 86)
	)
	(segment
		(start 134.427 139.285)
		(end 134.332 139.19)
		(width 0.16)
		(layer "F.Cu")
		(net 86)
	)
	(segment
		(start 132.114663 133.121081)
		(end 133.035824 132.19992)
		(width 0.16)
		(layer "F.Cu")
		(net 86)
	)
	(segment
		(start 134.332 139.19)
		(end 134.332 134.341396)
		(width 0.16)
		(layer "F.Cu")
		(net 86)
	)
	(segment
		(start 126.014204 127.82)
		(end 121.910796 127.82)
		(width 0.16)
		(layer "F.Cu")
		(net 86)
	)
	(segment
		(start 130.415684 131.708788)
		(end 130.415684 131.708787)
		(width 0.16)
		(layer "F.Cu")
		(net 86)
	)
	(segment
		(start 131.480188 129.647264)
		(end 131.480188 129.647263)
		(width 0.16)
		(layer "F.Cu")
		(net 86)
	)
	(segment
		(start 130.483167 129.647263)
		(end 130.339823 129.790606)
		(width 0.16)
		(layer "F.Cu")
		(net 86)
	)
	(segment
		(start 117.105 128.095)
		(end 117.334513 127.865487)
		(width 0.16)
		(layer "F.Cu")
		(net 86)
	)
	(segment
		(start 131.971319 133.264424)
		(end 132.114663 133.121081)
		(width 0.16)
		(layer "F.Cu")
		(net 86)
	)
	(segment
		(start 132.038803 131.202898)
		(end 132.038803 131.202899)
		(width 0.16)
		(layer "F.Cu")
		(net 86)
	)
	(arc
		(start 133.035824 132.19992)
		(mid 133.242314 131.70141)
		(end 133.035824 131.2029)
		(width 0.16)
		(layer "F.Cu")
		(net 86)
	)
	(arc
		(start 130.339823 129.790606)
		(mid 130.060516 129.906299)
		(end 129.781209 129.790606)
		(width 0.16)
		(layer "F.Cu")
		(net 86)
	)
	(arc
		(start 131.971319 133.823038)
		(mid 131.855626 133.543731)
		(end 131.971319 133.264424)
		(width 0.16)
		(layer "F.Cu")
		(net 86)
	)
	(arc
		(start 133.6703 133.679697)
		(mid 133.17179 133.473207)
		(end 132.67328 133.679697)
		(width 0.16)
		(layer "F.Cu")
		(net 86)
	)
	(arc
		(start 132.529935 133.82304)
		(mid 132.250628 133.938733)
		(end 131.971321 133.82304)
		(width 0.16)
		(layer "F.Cu")
		(net 86)
	)
	(arc
		(start 130.415685 132.267403)
		(mid 130.299992 131.988096)
		(end 130.415684 131.708788)
		(width 0.16)
		(layer "F.Cu")
		(net 86)
	)
	(arc
		(start 131.480188 129.647263)
		(mid 130.981678 129.440773)
		(end 130.483167 129.647262)
		(width 0.16)
		(layer "F.Cu")
		(net 86)
	)
	(arc
		(start 131.480188 130.644284)
		(mid 131.686678 130.145774)
		(end 131.480188 129.647264)
		(width 0.16)
		(layer "F.Cu")
		(net 86)
	)
	(arc
		(start 130.974299 132.267403)
		(mid 130.694992 132.383096)
		(end 130.415685 132.267403)
		(width 0.16)
		(layer "F.Cu")
		(net 86)
	)
	(arc
		(start 133.035824 131.202899)
		(mid 132.537314 130.996409)
		(end 132.038803 131.202898)
		(width 0.16)
		(layer "F.Cu")
		(net 86)
	)
	(segment
		(start 117.2 122.9)
		(end 117.312513 122.787487)
		(width 0.16)
		(layer "F.Cu")
		(net 87)
	)
	(segment
		(start 135.425 139.735)
		(end 135.425 139.285)
		(width 0.16)
		(layer "F.Cu")
		(net 87)
	)
	(segment
		(start 120.603076 123.719999)
		(end 117.389203 123.719999)
		(width 0.16)
		(layer "F.Cu")
		(net 87)
	)
	(segment
		(start 120.606445 123.72)
		(end 120.603077 123.72)
		(width 0.16)
		(layer "F.Cu")
		(net 87)
	)
	(segment
		(start 117.312513 122.787487)
		(end 118.114999 122.787487)
		(width 0.16)
		(layer "F.Cu")
		(net 87)
	)
	(segment
		(start 125.66 124.945151)
		(end 125.23015 124.945151)
		(width 0.16)
		(layer "F.Cu")
		(net 87)
	)
	(segment
		(start 120.890445 123.72)
		(end 120.606445 123.72)
		(width 0.16)
		(layer "F.Cu")
		(net 87)
	)
	(segment
		(start 124.850075 124.565076)
		(end 124.850075 124.410075)
		(width 0.16)
		(layer "F.Cu")
		(net 87)
	)
	(segment
		(start 122.723445 124.443)
		(end 122.723445 125.093747)
		(width 0.16)
		(layer "F.Cu")
		(net 87)
	)
	(segment
		(start 117.389203 123.719999)
		(end 117.2 123.530796)
		(width 0.16)
		(layer "F.Cu")
		(net 87)
	)
	(segment
		(start 126.040075 124.410075)
		(end 126.040075 124.565076)
		(width 0.16)
		(layer "F.Cu")
		(net 87)
	)
	(segment
		(start 117.2 123.530796)
		(end 117.2 122.9)
		(width 0.16)
		(layer "F.Cu")
		(net 87)
	)
	(segment
		(start 135.33 139.19)
		(end 135.33 131.376996)
		(width 0.16)
		(layer "F.Cu")
		(net 87)
	)
	(segment
		(start 123.730074 123.72)
		(end 123.446445 123.72)
		(width 0.16)
		(layer "F.Cu")
		(net 87)
	)
	(segment
		(start 135.33 131.376996)
		(end 127.673004 123.72)
		(width 0.16)
		(layer "F.Cu")
		(net 87)
	)
	(segment
		(start 121.613445 125.093747)
		(end 121.613445 124.443)
		(width 0.16)
		(layer "F.Cu")
		(net 87)
	)
	(segment
		(start 135.425 139.285)
		(end 135.33 139.19)
		(width 0.16)
		(layer "F.Cu")
		(net 87)
	)
	(segment
		(start 124.16 123.72)
		(end 123.730074 123.72)
		(width 0.16)
		(layer "F.Cu")
		(net 87)
	)
	(segment
		(start 122.310445 125.506747)
		(end 122.026445 125.506747)
		(width 0.16)
		(layer "F.Cu")
		(net 87)
	)
	(segment
		(start 120.603077 123.72)
		(end 120.603076 123.719999)
		(width 0.16)
		(layer "F.Cu")
		(net 87)
	)
	(segment
		(start 127.673004 123.72)
		(end 126.73015 123.72)
		(width 0.16)
		(layer "F.Cu")
		(net 87)
	)
	(arc
		(start 122.723445 125.093747)
		(mid 122.60248 125.385782)
		(end 122.310445 125.506747)
		(width 0.16)
		(layer "F.Cu")
		(net 87)
	)
	(arc
		(start 126.73015 123.72)
		(mid 126.242193 123.922118)
		(end 126.040075 124.410075)
		(width 0.16)
		(layer "F.Cu")
		(net 87)
	)
	(arc
		(start 123.446445 123.72)
		(mid 122.935207 123.931762)
		(end 122.723445 124.443)
		(width 0.16)
		(layer "F.Cu")
		(net 87)
	)
	(arc
		(start 122.026445 125.506747)
		(mid 121.73441 125.385782)
		(end 121.613445 125.093747)
		(width 0.16)
		(layer "F.Cu")
		(net 87)
	)
	(arc
		(start 125.23015 124.945151)
		(mid 124.961396 124.83383)
		(end 124.850075 124.565076)
		(width 0.16)
		(layer "F.Cu")
		(net 87)
	)
	(arc
		(start 124.850075 124.410075)
		(mid 124.647957 123.922118)
		(end 124.16 123.72)
		(width 0.16)
		(layer "F.Cu")
		(net 87)
	)
	(arc
		(start 121.613445 124.443)
		(mid 121.401683 123.931762)
		(end 120.890445 123.72)
		(width 0.16)
		(layer "F.Cu")
		(net 87)
	)
	(arc
		(start 126.040075 124.565076)
		(mid 125.928754 124.83383)
		(end 125.66 124.945151)
		(width 0.16)
		(layer "F.Cu")
		(net 87)
	)
	(segment
		(start 117.282513 120.247487)
		(end 117.075 120.455)
		(width 0.16)
		(layer "F.Cu")
		(net 88)
	)
	(segment
		(start 118.114999 120.247487)
		(end 117.282513 120.247487)
		(width 0.16)
		(layer "F.Cu")
		(net 88)
	)
	(segment
		(start 136.83 128.950796)
		(end 136.83 139.19)
		(width 0.16)
		(layer "F.Cu")
		(net 88)
	)
	(segment
		(start 117.075 120.455)
		(end 117.075 120.965)
		(width 0.16)
		(layer "F.Cu")
		(net 88)
	)
	(segment
		(start 129.08569 121.206486)
		(end 136.83 128.950796)
		(width 0.16)
		(layer "F.Cu")
		(net 88)
	)
	(segment
		(start 117.316486 121.206486)
		(end 129.08569 121.206486)
		(width 0.16)
		(layer "F.Cu")
		(net 88)
	)
	(segment
		(start 136.925 139.285)
		(end 136.925 139.735)
		(width 0.16)
		(layer "F.Cu")
		(net 88)
	)
	(segment
		(start 117.075 120.965)
		(end 117.316486 121.206486)
		(width 0.16)
		(layer "F.Cu")
		(net 88)
	)
	(segment
		(start 136.83 139.19)
		(end 136.925 139.285)
		(width 0.16)
		(layer "F.Cu")
		(net 88)
	)
	(segment
		(start 130.487755 135.554079)
		(end 130.417045 135.483369)
		(width 0.16)
		(layer "F.Cu")
		(net 89)
	)
	(segment
		(start 124.245 132.399)
		(end 124.245 133.463401)
		(width 0.16)
		(layer "F.Cu")
		(net 89)
	)
	(segment
		(start 119.636167 131.694)
		(end 117.612703 131.694)
		(width 0.16)
		(layer "F.Cu")
		(net 89)
	)
	(segment
		(start 128.331804 131.694)
		(end 127.15 131.694)
		(width 0.16)
		(layer "F.Cu")
		(net 89)
	)
	(segment
		(start 126.445 132.399)
		(end 126.445 133.463418)
		(width 0.16)
		(layer "F.Cu")
		(net 89)
	)
	(segment
		(start 123.455 133.463401)
		(end 123.455 132.399)
		(width 0.16)
		(layer "F.Cu")
		(net 89)
	)
	(segment
		(start 117.612703 131.694)
		(end 117.41 131.491297)
		(width 0.16)
		(layer "F.Cu")
		(net 89)
	)
	(segment
		(start 121.255 133.463401)
		(end 121.255 132.399)
		(width 0.16)
		(layer "F.Cu")
		(net 89)
	)
	(segment
		(start 125.655 133.463418)
		(end 125.655 132.399)
		(width 0.16)
		(layer "F.Cu")
		(net 89)
	)
	(segment
		(start 128.861409 133.927733)
		(end 128.790699 133.857023)
		(width 0.16)
		(layer "F.Cu")
		(net 89)
	)
	(segment
		(start 128.900301 133.224163)
		(end 128.900301 133.224164)
		(width 0.16)
		(layer "F.Cu")
		(net 89)
	)
	(segment
		(start 132.926 139.285)
		(end 132.831 139.19)
		(width 0.16)
		(layer "F.Cu")
		(net 89)
	)
	(segment
		(start 130.417045 135.483369)
		(end 130.417044 135.483369)
		(width 0.16)
		(layer "F.Cu")
		(net 89)
	)
	(segment
		(start 129.384668 133.927733)
		(end 129.384668 133.927734)
		(width 0.16)
		(layer "F.Cu")
		(net 89)
	)
	(segment
		(start 132.831 136.193196)
		(end 132.082281 135.444477)
		(width 0.16)
		(layer "F.Cu")
		(net 89)
	)
	(segment
		(start 130.526647 133.888844)
		(end 130.455934 133.818131)
		(width 0.16)
		(layer "F.Cu")
		(net 89)
	)
	(segment
		(start 130.526647 134.850509)
		(end 130.526647 134.85051)
		(width 0.16)
		(layer "F.Cu")
		(net 89)
	)
	(segment
		(start 128.900301 132.262498)
		(end 128.331804 131.694)
		(width 0.16)
		(layer "F.Cu")
		(net 89)
	)
	(segment
		(start 131.011014 135.554079)
		(end 131.011014 135.55408)
		(width 0.16)
		(layer "F.Cu")
		(net 89)
	)
	(segment
		(start 120.55 131.694)
		(end 119.636167 131.694)
		(width 0.16)
		(layer "F.Cu")
		(net 89)
	)
	(segment
		(start 129.494269 133.818131)
		(end 129.384668 133.927733)
		(width 0.16)
		(layer "F.Cu")
		(net 89)
	)
	(segment
		(start 117.41 131.111486)
		(end 118.114999 130.406487)
		(width 0.16)
		(layer "F.Cu")
		(net 89)
	)
	(segment
		(start 132.926 139.735)
		(end 132.926 139.285)
		(width 0.16)
		(layer "F.Cu")
		(net 89)
	)
	(segment
		(start 132.831 139.19)
		(end 132.831 136.193196)
		(width 0.16)
		(layer "F.Cu")
		(net 89)
	)
	(segment
		(start 131.120615 135.444477)
		(end 131.011014 135.554079)
		(width 0.16)
		(layer "F.Cu")
		(net 89)
	)
	(segment
		(start 128.790699 133.857023)
		(end 128.790698 133.857023)
		(width 0.16)
		(layer "F.Cu")
		(net 89)
	)
	(segment
		(start 130.417045 134.96011)
		(end 130.526647 134.850509)
		(width 0.16)
		(layer "F.Cu")
		(net 89)
	)
	(segment
		(start 117.41 131.491297)
		(end 117.41 131.111486)
		(width 0.16)
		(layer "F.Cu")
		(net 89)
	)
	(segment
		(start 130.455934 133.818131)
		(end 130.455935 133.818131)
		(width 0.16)
		(layer "F.Cu")
		(net 89)
	)
	(segment
		(start 128.790699 133.333764)
		(end 128.900301 133.224163)
		(width 0.16)
		(layer "F.Cu")
		(net 89)
	)
	(segment
		(start 122.045 132.399)
		(end 122.045 133.463401)
		(width 0.16)
		(layer "F.Cu")
		(net 89)
	)
	(arc
		(start 122.75 131.694)
		(mid 122.25149 131.90049)
		(end 122.045 132.399)
		(width 0.16)
		(layer "F.Cu")
		(net 89)
	)
	(arc
		(start 130.526647 134.85051)
		(mid 130.725815 134.369677)
		(end 130.526647 133.888844)
		(width 0.16)
		(layer "F.Cu")
		(net 89)
	)
	(arc
		(start 124.95 131.694)
		(mid 124.45149 131.90049)
		(end 124.245 132.399)
		(width 0.16)
		(layer "F.Cu")
		(net 89)
	)
	(arc
		(start 121.65 133.858401)
		(mid 121.370693 133.742708)
		(end 121.255 133.463401)
		(width 0.16)
		(layer "F.Cu")
		(net 89)
	)
	(arc
		(start 128.790698 133.857023)
		(mid 128.682328 133.595393)
		(end 128.790699 133.333764)
		(width 0.16)
		(layer "F.Cu")
		(net 89)
	)
	(arc
		(start 132.082281 135.444477)
		(mid 131.601448 135.245309)
		(end 131.120615 135.444477)
		(width 0.16)
		(layer "F.Cu")
		(net 89)
	)
	(arc
		(start 123.455 132.399)
		(mid 123.24851 131.90049)
		(end 122.75 131.694)
		(width 0.16)
		(layer "F.Cu")
		(net 89)
	)
	(arc
		(start 121.255 132.399)
		(mid 121.04851 131.90049)
		(end 120.55 131.694)
		(width 0.16)
		(layer "F.Cu")
		(net 89)
	)
	(arc
		(start 125.655 132.399)
		(mid 125.44851 131.90049)
		(end 124.95 131.694)
		(width 0.16)
		(layer "F.Cu")
		(net 89)
	)
	(arc
		(start 128.900301 133.224164)
		(mid 129.099469 132.743331)
		(end 128.900301 132.262498)
		(width 0.16)
		(layer "F.Cu")
		(net 89)
	)
	(arc
		(start 126.05 133.858418)
		(mid 125.770693 133.742725)
		(end 125.655 133.463418)
		(width 0.16)
		(layer "F.Cu")
		(net 89)
	)
	(arc
		(start 127.15 131.694)
		(mid 126.65149 131.90049)
		(end 126.445 132.399)
		(width 0.16)
		(layer "F.Cu")
		(net 89)
	)
	(arc
		(start 126.445 133.463418)
		(mid 126.329307 133.742725)
		(end 126.05 133.858418)
		(width 0.16)
		(layer "F.Cu")
		(net 89)
	)
	(arc
		(start 130.417044 135.483369)
		(mid 130.308674 135.221739)
		(end 130.417045 134.96011)
		(width 0.16)
		(layer "F.Cu")
		(net 89)
	)
	(arc
		(start 130.455935 133.818131)
		(mid 129.975102 133.618963)
		(end 129.494269 133.818131)
		(width 0.16)
		(layer "F.Cu")
		(net 89)
	)
	(arc
		(start 122.045 133.463401)
		(mid 121.929307 133.742708)
		(end 121.65 133.858401)
		(width 0.16)
		(layer "F.Cu")
		(net 89)
	)
	(arc
		(start 131.011014 135.55408)
		(mid 130.749384 135.66245)
		(end 130.487755 135.554079)
		(width 0.16)
		(layer "F.Cu")
		(net 89)
	)
	(arc
		(start 129.384668 133.927734)
		(mid 129.123038 134.036104)
		(end 128.861409 133.927733)
		(width 0.16)
		(layer "F.Cu")
		(net 89)
	)
	(arc
		(start 123.85 133.858401)
		(mid 123.570693 133.742708)
		(end 123.455 133.463401)
		(width 0.16)
		(layer "F.Cu")
		(net 89)
	)
	(arc
		(start 124.245 133.463401)
		(mid 124.129307 133.742708)
		(end 123.85 133.858401)
		(width 0.16)
		(layer "F.Cu")
		(net 89)
	)
	(segment
		(start 122.310445 125.816747)
		(end 122.026445 125.816747)
		(width 0.16)
		(layer "F.Cu")
		(net 90)
	)
	(segment
		(start 123.033445 124.443)
		(end 123.033445 125.093747)
		(width 0.16)
		(layer "F.Cu")
		(net 90)
	)
	(segment
		(start 117.260797 124.030001)
		(end 116.680796 123.45)
		(width 0.16)
		(layer "F.Cu")
		(net 90)
	)
	(segment
		(start 135.02 131.505404)
		(end 127.544596 124.03)
		(width 0.16)
		(layer "F.Cu")
		(net 90)
	)
	(segment
		(start 121.303445 125.093747)
		(end 121.303445 124.443)
		(width 0.16)
		(layer "F.Cu")
		(net 90)
	)
	(segment
		(start 120.603077 124.03)
		(end 120.603076 124.030001)
		(width 0.16)
		(layer "F.Cu")
		(net 90)
	)
	(segment
		(start 125.66 125.255151)
		(end 125.23015 125.255151)
		(width 0.16)
		(layer "F.Cu")
		(net 90)
	)
	(segment
		(start 120.603076 124.030001)
		(end 117.260797 124.030001)
		(width 0.16)
		(layer "F.Cu")
		(net 90)
	)
	(segment
		(start 116.182486 123.45)
		(end 115.574999 124.057487)
		(width 0.16)
		(layer "F.Cu")
		(net 90)
	)
	(segment
		(start 134.925 139.285)
		(end 135.02 139.19)
		(width 0.16)
		(layer "F.Cu")
		(net 90)
	)
	(segment
		(start 127.544596 124.03)
		(end 126.73015 124.03)
		(width 0.16)
		(layer "F.Cu")
		(net 90)
	)
	(segment
		(start 124.16 124.03)
		(end 123.730074 124.03)
		(width 0.16)
		(layer "F.Cu")
		(net 90)
	)
	(segment
		(start 120.890445 124.03)
		(end 120.606445 124.03)
		(width 0.16)
		(layer "F.Cu")
		(net 90)
	)
	(segment
		(start 124.540075 124.565076)
		(end 124.540075 124.410075)
		(width 0.16)
		(layer "F.Cu")
		(net 90)
	)
	(segment
		(start 123.730074 124.03)
		(end 123.446445 124.03)
		(width 0.16)
		(layer "F.Cu")
		(net 90)
	)
	(segment
		(start 116.680796 123.45)
		(end 116.182486 123.45)
		(width 0.16)
		(layer "F.Cu")
		(net 90)
	)
	(segment
		(start 135.02 139.19)
		(end 135.02 131.505404)
		(width 0.16)
		(layer "F.Cu")
		(net 90)
	)
	(segment
		(start 120.606445 124.03)
		(end 120.603077 124.03)
		(width 0.16)
		(layer "F.Cu")
		(net 90)
	)
	(segment
		(start 134.925 139.735)
		(end 134.925 139.285)
		(width 0.16)
		(layer "F.Cu")
		(net 90)
	)
	(segment
		(start 126.350075 124.410075)
		(end 126.350075 124.565076)
		(width 0.16)
		(layer "F.Cu")
		(net 90)
	)
	(arc
		(start 121.303445 124.443)
		(mid 121.18248 124.150965)
		(end 120.890445 124.03)
		(width 0.16)
		(layer "F.Cu")
		(net 90)
	)
	(arc
		(start 126.350075 124.565076)
		(mid 126.147957 125.053033)
		(end 125.66 125.255151)
		(width 0.16)
		(layer "F.Cu")
		(net 90)
	)
	(arc
		(start 126.73015 124.03)
		(mid 126.461396 124.141321)
		(end 126.350075 124.410075)
		(width 0.16)
		(layer "F.Cu")
		(net 90)
	)
	(arc
		(start 125.23015 125.255151)
		(mid 124.742193 125.053033)
		(end 124.540075 124.565076)
		(width 0.16)
		(layer "F.Cu")
		(net 90)
	)
	(arc
		(start 124.540075 124.410075)
		(mid 124.428754 124.141321)
		(end 124.16 124.03)
		(width 0.16)
		(layer "F.Cu")
		(net 90)
	)
	(arc
		(start 123.446445 124.03)
		(mid 123.15441 124.150965)
		(end 123.033445 124.443)
		(width 0.16)
		(layer "F.Cu")
		(net 90)
	)
	(arc
		(start 123.033445 125.093747)
		(mid 122.821683 125.604985)
		(end 122.310445 125.816747)
		(width 0.16)
		(layer "F.Cu")
		(net 90)
	)
	(arc
		(start 122.026445 125.816747)
		(mid 121.515207 125.604985)
		(end 121.303445 125.093747)
		(width 0.16)
		(layer "F.Cu")
		(net 90)
	)
	(segment
		(start 136.52 129.079204)
		(end 136.52 139.19)
		(width 0.16)
		(layer "F.Cu")
		(net 91)
	)
	(segment
		(start 136.425 139.285)
		(end 136.425 139.735)
		(width 0.16)
		(layer "F.Cu")
		(net 91)
	)
	(segment
		(start 120.825 121.791487)
		(end 120.825 121.852853)
		(width 0.16)
		(layer "F.Cu")
		(net 91)
	)
	(segment
		(start 136.52 139.19)
		(end 136.425 139.285)
		(width 0.16)
		(layer "F.Cu")
		(net 91)
	)
	(segment
		(start 121.375 121.852853)
		(end 121.375 121.791487)
		(width 0.16)
		(layer "F.Cu")
		(net 91)
	)
	(segment
		(start 128.603537 121.516487)
		(end 128.957283 121.516487)
		(width 0.16)
		(layer "F.Cu")
		(net 91)
	)
	(segment
		(start 121.65 121.516487)
		(end 128.603537 121.516487)
		(width 0.16)
		(layer "F.Cu")
		(net 91)
	)
	(segment
		(start 128.957283 121.516487)
		(end 136.52 129.079204)
		(width 0.16)
		(layer "F.Cu")
		(net 91)
	)
	(segment
		(start 115.575999 121.516487)
		(end 120.55 121.516487)
		(width 0.16)
		(layer "F.Cu")
		(net 91)
	)
	(arc
		(start 120.55 121.516487)
		(mid 120.744454 121.597033)
		(end 120.825 121.791487)
		(width 0.16)
		(layer "F.Cu")
		(net 91)
	)
	(arc
		(start 121.375 121.791487)
		(mid 121.45555 121.597041)
		(end 121.65 121.516487)
		(width 0.16)
		(layer "F.Cu")
		(net 91)
	)
	(arc
		(start 120.825 121.852853)
		(mid 120.905546 122.047307)
		(end 121.1 122.127853)
		(width 0.16)
		(layer "F.Cu")
		(net 91)
	)
	(arc
		(start 121.1 122.127853)
		(mid 121.294454 122.047307)
		(end 121.375 121.852853)
		(width 0.16)
		(layer "F.Cu")
		(net 91)
	)
	(segment
		(start 130.19648 132.486605)
		(end 130.196482 132.486606)
		(width 0.16)
		(layer "F.Cu")
		(net 92)
	)
	(segment
		(start 132.74914 134.042244)
		(end 132.892483 133.8989)
		(width 0.16)
		(layer "F.Cu")
		(net 92)
	)
	(segment
		(start 121.031717 129.137487)
		(end 122.039204 128.13)
		(width 0.16)
		(layer "F.Cu")
		(net 92)
	)
	(segment
		(start 131.616154 132.063957)
		(end 131.725754 131.954354)
		(width 0.16)
		(layer "F.Cu")
		(net 92)
	)
	(segment
		(start 126.893283 129.137487)
		(end 128.689683 129.137487)
		(width 0.16)
		(layer "F.Cu")
		(net 92)
	)
	(segment
		(start 131.752118 134.042242)
		(end 131.752119 134.042243)
		(width 0.16)
		(layer "F.Cu")
		(net 92)
	)
	(segment
		(start 130.728732 130.957331)
		(end 130.196481 131.489585)
		(width 0.16)
		(layer "F.Cu")
		(net 92)
	)
	(segment
		(start 122.039204 128.13)
		(end 125.885796 128.13)
		(width 0.16)
		(layer "F.Cu")
		(net 92)
	)
	(segment
		(start 120.775 129.428117)
		(end 120.775 129.362487)
		(width 0.16)
		(layer "F.Cu")
		(net 92)
	)
	(segment
		(start 131.89546 132.901877)
		(end 131.752118 133.045222)
		(width 0.16)
		(layer "F.Cu")
		(net 92)
	)
	(segment
		(start 131.260985 130.425081)
		(end 130.728733 130.957333)
		(width 0.16)
		(layer "F.Cu")
		(net 92)
	)
	(segment
		(start 131.725754 131.954354)
		(end 132.258006 131.422102)
		(width 0.16)
		(layer "F.Cu")
		(net 92)
	)
	(segment
		(start 132.816621 131.980717)
		(end 131.89546 132.901877)
		(width 0.16)
		(layer "F.Cu")
		(net 92)
	)
	(segment
		(start 128.689683 129.137487)
		(end 129.562005 130.009809)
		(width 0.16)
		(layer "F.Cu")
		(net 92)
	)
	(segment
		(start 130.196481 131.489585)
		(end 130.196479 131.489584)
		(width 0.16)
		(layer "F.Cu")
		(net 92)
	)
	(segment
		(start 130.728733 130.957333)
		(end 130.728732 130.957331)
		(width 0.16)
		(layer "F.Cu")
		(net 92)
	)
	(segment
		(start 125.885796 128.13)
		(end 126.893283 129.137487)
		(width 0.16)
		(layer "F.Cu")
		(net 92)
	)
	(segment
		(start 134.022 139.19)
		(end 133.927 139.285)
		(width 0.16)
		(layer "F.Cu")
		(net 92)
	)
	(segment
		(start 120.325 129.362487)
		(end 120.325 129.428117)
		(width 0.16)
		(layer "F.Cu")
		(net 92)
	)
	(segment
		(start 130.70237 129.866467)
		(end 130.70237 129.866466)
		(width 0.16)
		(layer "F.Cu")
		(net 92)
	)
	(segment
		(start 121 129.137487)
		(end 121.031717 129.137487)
		(width 0.16)
		(layer "F.Cu")
		(net 92)
	)
	(segment
		(start 115.575999 129.137487)
		(end 120.1 129.137487)
		(width 0.16)
		(layer "F.Cu")
		(net 92)
	)
	(segment
		(start 133.451097 133.8989)
		(end 134.022 134.469804)
		(width 0.16)
		(layer "F.Cu")
		(net 92)
	)
	(segment
		(start 131.193502 132.486606)
		(end 131.616154 132.063957)
		(width 0.16)
		(layer "F.Cu")
		(net 92)
	)
	(segment
		(start 134.022 134.469804)
		(end 134.022 139.19)
		(width 0.16)
		(layer "F.Cu")
		(net 92)
	)
	(segment
		(start 130.559026 130.00981)
		(end 130.70237 129.866467)
		(width 0.16)
		(layer "F.Cu")
		(net 92)
	)
	(segment
		(start 133.927 139.285)
		(end 133.927 139.735)
		(width 0.16)
		(layer "F.Cu")
		(net 92)
	)
	(arc
		(start 130.196479 131.489584)
		(mid 129.98999 131.988095)
		(end 130.19648 132.486605)
		(width 0.16)
		(layer "F.Cu")
		(net 92)
	)
	(arc
		(start 120.1 129.137487)
		(mid 120.259099 129.203388)
		(end 120.325 129.362487)
		(width 0.16)
		(layer "F.Cu")
		(net 92)
	)
	(arc
		(start 120.775 129.362487)
		(mid 120.840901 129.203388)
		(end 121 129.137487)
		(width 0.16)
		(layer "F.Cu")
		(net 92)
	)
	(arc
		(start 131.752118 133.045222)
		(mid 131.545628 133.543732)
		(end 131.752118 134.042242)
		(width 0.16)
		(layer "F.Cu")
		(net 92)
	)
	(arc
		(start 129.562005 130.009809)
		(mid 130.060515 130.216299)
		(end 130.559026 130.00981)
		(width 0.16)
		(layer "F.Cu")
		(net 92)
	)
	(arc
		(start 132.258006 131.422102)
		(mid 132.537314 131.30641)
		(end 132.816621 131.422103)
		(width 0.16)
		(layer "F.Cu")
		(net 92)
	)
	(arc
		(start 131.260985 129.866467)
		(mid 131.376678 130.145774)
		(end 131.260985 130.425081)
		(width 0.16)
		(layer "F.Cu")
		(net 92)
	)
	(arc
		(start 130.196482 132.486606)
		(mid 130.694992 132.693096)
		(end 131.193502 132.486606)
		(width 0.16)
		(layer "F.Cu")
		(net 92)
	)
	(arc
		(start 132.816621 131.422103)
		(mid 132.932314 131.70141)
		(end 132.816621 131.980717)
		(width 0.16)
		(layer "F.Cu")
		(net 92)
	)
	(arc
		(start 130.70237 129.866466)
		(mid 130.981678 129.750774)
		(end 131.260985 129.866467)
		(width 0.16)
		(layer "F.Cu")
		(net 92)
	)
	(arc
		(start 120.55 129.653117)
		(mid 120.709099 129.587216)
		(end 120.775 129.428117)
		(width 0.16)
		(layer "F.Cu")
		(net 92)
	)
	(arc
		(start 131.752119 134.042243)
		(mid 132.250629 134.248733)
		(end 132.74914 134.042244)
		(width 0.16)
		(layer "F.Cu")
		(net 92)
	)
	(arc
		(start 120.325 129.428117)
		(mid 120.390901 129.587216)
		(end 120.55 129.653117)
		(width 0.16)
		(layer "F.Cu")
		(net 92)
	)
	(arc
		(start 132.892483 133.8989)
		(mid 133.17179 133.783207)
		(end 133.451097 133.8989)
		(width 0.16)
		(layer "F.Cu")
		(net 92)
	)
	(segment
		(start 130.197842 134.740907)
		(end 130.307444 134.631306)
		(width 0.16)
		(layer "F.Cu")
		(net 93)
	)
	(segment
		(start 120.55 132.004)
		(end 119.636167 132.004)
		(width 0.16)
		(layer "F.Cu")
		(net 93)
	)
	(segment
		(start 123.145 133.463401)
		(end 123.145 132.399)
		(width 0.16)
		(layer "F.Cu")
		(net 93)
	)
	(segment
		(start 125.345 133.463418)
		(end 125.345 132.399)
		(width 0.16)
		(layer "F.Cu")
		(net 93)
	)
	(segment
		(start 130.236731 134.037334)
		(end 130.236731 134.037333)
		(width 0.16)
		(layer "F.Cu")
		(net 93)
	)
	(segment
		(start 130.268552 135.773282)
		(end 130.197842 135.702572)
		(width 0.16)
		(layer "F.Cu")
		(net 93)
	)
	(segment
		(start 129.713472 134.037334)
		(end 129.603871 134.146936)
		(width 0.16)
		(layer "F.Cu")
		(net 93)
	)
	(segment
		(start 132.426 139.285)
		(end 132.521 139.19)
		(width 0.16)
		(layer "F.Cu")
		(net 93)
	)
	(segment
		(start 131.230217 135.773282)
		(end 131.230217 135.773283)
		(width 0.16)
		(layer "F.Cu")
		(net 93)
	)
	(segment
		(start 132.426 139.735)
		(end 132.426 139.285)
		(width 0.16)
		(layer "F.Cu")
		(net 93)
	)
	(segment
		(start 126.755 132.399)
		(end 126.755 133.463418)
		(width 0.16)
		(layer "F.Cu")
		(net 93)
	)
	(segment
		(start 117.479499 132.004)
		(end 117.135499 131.66)
		(width 0.16)
		(layer "F.Cu")
		(net 93)
	)
	(segment
		(start 132.521 139.19)
		(end 132.521 136.321604)
		(width 0.16)
		(layer "F.Cu")
		(net 93)
	)
	(segment
		(start 119.636167 132.004)
		(end 117.479499 132.004)
		(width 0.16)
		(layer "F.Cu")
		(net 93)
	)
	(segment
		(start 122.355 132.399)
		(end 122.355 133.463401)
		(width 0.16)
		(layer "F.Cu")
		(net 93)
	)
	(segment
		(start 128.681098 133.00496)
		(end 128.681098 133.004961)
		(width 0.16)
		(layer "F.Cu")
		(net 93)
	)
	(segment
		(start 130.307444 134.108047)
		(end 130.236731 134.037334)
		(width 0.16)
		(layer "F.Cu")
		(net 93)
	)
	(segment
		(start 128.681098 132.481701)
		(end 128.203396 132.004)
		(width 0.16)
		(layer "F.Cu")
		(net 93)
	)
	(segment
		(start 124.555 132.399)
		(end 124.555 133.463401)
		(width 0.16)
		(layer "F.Cu")
		(net 93)
	)
	(segment
		(start 128.571496 133.114561)
		(end 128.681098 133.00496)
		(width 0.16)
		(layer "F.Cu")
		(net 93)
	)
	(segment
		(start 128.642206 134.146936)
		(end 128.571496 134.076226)
		(width 0.16)
		(layer "F.Cu")
		(net 93)
	)
	(segment
		(start 130.307444 134.631306)
		(end 130.307444 134.631307)
		(width 0.16)
		(layer "F.Cu")
		(net 93)
	)
	(segment
		(start 130.197842 135.702572)
		(end 130.197842 135.702573)
		(width 0.16)
		(layer "F.Cu")
		(net 93)
	)
	(segment
		(start 132.521 136.321604)
		(end 131.863077 135.663679)
		(width 0.16)
		(layer "F.Cu")
		(net 93)
	)
	(segment
		(start 128.203396 132.004)
		(end 127.15 132.004)
		(width 0.16)
		(layer "F.Cu")
		(net 93)
	)
	(segment
		(start 128.571496 134.076226)
		(end 128.571496 134.076227)
		(width 0.16)
		(layer "F.Cu")
		(net 93)
	)
	(segment
		(start 131.339818 135.66368)
		(end 131.230217 135.773282)
		(width 0.16)
		(layer "F.Cu")
		(net 93)
	)
	(segment
		(start 129.603871 134.146936)
		(end 129.603871 134.146937)
		(width 0.16)
		(layer "F.Cu")
		(net 93)
	)
	(segment
		(start 117.135499 131.66)
		(end 115.592486 131.66)
		(width 0.16)
		(layer "F.Cu")
		(net 93)
	)
	(segment
		(start 120.945 133.463401)
		(end 120.945 132.399)
		(width 0.16)
		(layer "F.Cu")
		(net 93)
	)
	(segment
		(start 115.592486 131.66)
		(end 115.575999 131.676487)
		(width 0.16)
		(layer "F.Cu")
		(net 93)
	)
	(arc
		(start 122.75 132.004)
		(mid 122.470693 132.119693)
		(end 122.355 132.399)
		(width 0.16)
		(layer "F.Cu")
		(net 93)
	)
	(arc
		(start 126.05 134.168418)
		(mid 125.55149 133.961928)
		(end 125.345 133.463418)
		(width 0.16)
		(layer "F.Cu")
		(net 93)
	)
	(arc
		(start 120.945 132.399)
		(mid 120.829307 132.119693)
		(end 120.55 132.004)
		(width 0.16)
		(layer "F.Cu")
		(net 93)
	)
	(arc
		(start 131.230217 135.773283)
		(mid 130.749384 135.97245)
		(end 130.268552 135.773282)
		(width 0.16)
		(layer "F.Cu")
		(net 93)
	)
	(arc
		(start 124.95 132.004)
		(mid 124.670693 132.119693)
		(end 124.555 132.399)
		(width 0.16)
		(layer "F.Cu")
		(net 93)
	)
	(arc
		(start 121.65 134.168401)
		(mid 121.15149 133.961911)
		(end 120.945 133.463401)
		(width 0.16)
		(layer "F.Cu")
		(net 93)
	)
	(arc
		(start 122.355 133.463401)
		(mid 122.14851 133.961911)
		(end 121.65 134.168401)
		(width 0.16)
		(layer "F.Cu")
		(net 93)
	)
	(arc
		(start 123.145 132.399)
		(mid 123.029307 132.119693)
		(end 122.75 132.004)
		(width 0.16)
		(layer "F.Cu")
		(net 93)
	)
	(arc
		(start 124.555 133.463401)
		(mid 124.34851 133.961911)
		(end 123.85 134.168401)
		(width 0.16)
		(layer "F.Cu")
		(net 93)
	)
	(arc
		(start 127.15 132.004)
		(mid 126.870693 132.119693)
		(end 126.755 132.399)
		(width 0.16)
		(layer "F.Cu")
		(net 93)
	)
	(arc
		(start 130.307444 134.631307)
		(mid 130.415815 134.369677)
		(end 130.307444 134.108047)
		(width 0.16)
		(layer "F.Cu")
		(net 93)
	)
	(arc
		(start 125.345 132.399)
		(mid 125.229307 132.119693)
		(end 124.95 132.004)
		(width 0.16)
		(layer "F.Cu")
		(net 93)
	)
	(arc
		(start 131.863077 135.663679)
		(mid 131.601447 135.555309)
		(end 131.339818 135.66368)
		(width 0.16)
		(layer "F.Cu")
		(net 93)
	)
	(arc
		(start 129.603871 134.146937)
		(mid 129.123038 134.346104)
		(end 128.642206 134.146936)
		(width 0.16)
		(layer "F.Cu")
		(net 93)
	)
	(arc
		(start 128.571496 134.076227)
		(mid 128.372328 133.595394)
		(end 128.571496 133.114561)
		(width 0.16)
		(layer "F.Cu")
		(net 93)
	)
	(arc
		(start 130.236731 134.037333)
		(mid 129.975101 133.928963)
		(end 129.713472 134.037334)
		(width 0.16)
		(layer "F.Cu")
		(net 93)
	)
	(arc
		(start 128.681098 133.004961)
		(mid 128.789469 132.743331)
		(end 128.681098 132.481701)
		(width 0.16)
		(layer "F.Cu")
		(net 93)
	)
	(arc
		(start 130.197842 135.702573)
		(mid 129.998674 135.22174)
		(end 130.197842 134.740907)
		(width 0.16)
		(layer "F.Cu")
		(net 93)
	)
	(arc
		(start 126.755 133.463418)
		(mid 126.54851 133.961928)
		(end 126.05 134.168418)
		(width 0.16)
		(layer "F.Cu")
		(net 93)
	)
	(arc
		(start 123.85 134.168401)
		(mid 123.35149 133.961911)
		(end 123.145 133.463401)
		(width 0.16)
		(layer "F.Cu")
		(net 93)
	)
	(segment
		(start 195.0005 145.9995)
		(end 195.5 145.5)
		(width 0.256)
		(layer "F.Cu")
		(net 94)
	)
	(segment
		(start 243.151 106)
		(end 243.151 107.152)
		(width 0.38)
		(layer "F.Cu")
		(net 94)
	)
	(via
		(at 243.15 107.152)
		(size 0.45)
		(drill 0.1)
		(layers "F.Cu" "B.Cu")
		(remove_unused_layers yes)
		(keep_end_layers yes)
		(zone_layer_connections)
		(net 94)
	)
	(via
		(at 195.5 145.5)
		(size 0.45)
		(drill 0.1)
		(layers "F.Cu" "B.Cu")
		(remove_unused_layers yes)
		(keep_end_layers yes)
		(zone_layer_connections)
		(net 94)
	)
	(segment
		(start 222.702353 132.55787)
		(end 222.702353 132.557871)
		(width 0.13)
		(layer "In2.Cu")
		(net 94)
	)
	(segment
		(start 243.546248 106.096248)
		(end 243.610356 106.160355)
		(width 0.13)
		(layer "In2.Cu")
		(net 94)
	)
	(segment
		(start 219.315148 138.99239)
		(end 219.315149 138.99239)
		(width 0.13)
		(layer "In2.Cu")
		(net 94)
	)
	(segment
		(start 220.800074 137.507464)
		(end 220.800075 137.507464)
		(width 0.13)
		(layer "In2.Cu")
		(net 94)
	)
	(segment
		(start 222.285 136.022538)
		(end 222.285001 136.022538)
		(width 0.13)
		(layer "In2.Cu")
		(net 94)
	)
	(segment
		(start 195.51 145.16)
		(end 195.45 145.1)
		(width 0.1)
		(layer "In2.Cu")
		(net 94)
	)
	(segment
		(start 201.855 149.88)
		(end 204.200294 149.88)
		(width 0.13)
		(layer "In2.Cu")
		(net 94)
	)
	(segment
		(start 247.900294 105.72)
		(end 243.599706 105.72)
		(width 0.13)
		(layer "In2.Cu")
		(net 94)
	)
	(segment
		(start 222.129639 134.042841)
		(end 223.19717 135.110372)
		(width 0.13)
		(layer "In2.Cu")
		(net 94)
	)
	(segment
		(start 223.769927 134.537612)
		(end 222.702353 133.470038)
		(width 0.13)
		(layer "In2.Cu")
		(net 94)
	)
	(segment
		(start 218.247593 137.012666)
		(end 218.247593 137.012667)
		(width 0.13)
		(layer "In2.Cu")
		(net 94)
	)
	(segment
		(start 226.739778 132.14052)
		(end 226.739777 132.140518)
		(width 0.13)
		(layer "In2.Cu")
		(net 94)
	)
	(segment
		(start 243.546248 106.091653)
		(end 243.546248 106.096248)
		(width 0.13)
		(layer "In2.Cu")
		(net 94)
	)
	(segment
		(start 224.187301 131.072966)
		(end 224.187301 131.072967)
		(width 0.13)
		(layer "In2.Cu")
		(net 94)
	)
	(segment
		(start 219.315149 138.99239)
		(end 218.247593 137.924834)
		(width 0.13)
		(layer "In2.Cu")
		(net 94)
	)
	(segment
		(start 247.971811 106.443873)
		(end 247.97181 106.443873)
		(width 0.13)
		(layer "In2.Cu")
		(net 94)
	)
	(segment
		(start 222.285001 136.022538)
		(end 221.217471 134.955008)
		(width 0.13)
		(layer "In2.Cu")
		(net 94)
	)
	(segment
		(start 219.050297 139.83)
		(end 219.050297 139.829997)
		(width 0.13)
		(layer "In2.Cu")
		(net 94)
	)
	(segment
		(start 197.321422 149.88)
		(end 201.855 149.88)
		(width 0.1)
		(layer "In2.Cu")
		(net 94)
	)
	(segment
		(start 245.225294 116.355)
		(end 248.28 113.300294)
		(width 0.13)
		(layer "In2.Cu")
		(net 94)
	)
	(segment
		(start 242.845 106.474706)
		(end 242.845 106.847)
		(width 0.13)
		(layer "In2.Cu")
		(net 94)
	)
	(segment
		(start 243.292158 106.478555)
		(end 243.263406 106.449803)
		(width 0.13)
		(layer "In2.Cu")
		(net 94)
	)
	(segment
		(start 248.73 106.549706)
		(end 248.580831 106.400536)
		(width 0.13)
		(layer "In2.Cu")
		(net 94)
	)
	(segment
		(start 247.971811 106.16103)
		(end 248.015146 106.117696)
		(width 0.13)
		(layer "In2.Cu")
		(net 94)
	)
	(segment
		(start 248.28 110.125294)
		(end 248.73 109.675294)
		(width 0.13)
		(layer "In2.Cu")
		(net 94)
	)
	(segment
		(start 220.644713 135.527767)
		(end 221.712244 136.595298)
		(width 0.13)
		(layer "In2.Cu")
		(net 94)
	)
	(segment
		(start 225.254854 133.625445)
		(end 225.254852 133.625444)
		(width 0.13)
		(layer "In2.Cu")
		(net 94)
	)
	(segment
		(start 243.599706 105.72)
		(end 243.546248 105.773455)
		(width 0.13)
		(layer "In2.Cu")
		(net 94)
	)
	(segment
		(start 223.614521 132.557871)
		(end 224.682096 133.625446)
		(width 0.13)
		(layer "In2.Cu")
		(net 94)
	)
	(segment
		(start 223.769926 134.537612)
		(end 223.769927 134.537612)
		(width 0.13)
		(layer "In2.Cu")
		(net 94)
	)
	(segment
		(start 195.85 146.741422)
		(end 195.85 146.715685)
		(width 0.1)
		(layer "In2.Cu")
		(net 94)
	)
	(segment
		(start 248.297988 106.400537)
		(end 248.254654 106.443872)
		(width 0.13)
		(layer "In2.Cu")
		(net 94)
	)
	(segment
		(start 219.732545 135.527766)
		(end 219.732545 135.527767)
		(width 0.13)
		(layer "In2.Cu")
		(net 94)
	)
	(segment
		(start 213.350294 139.83)
		(end 219.050297 139.83)
		(width 0.13)
		(layer "In2.Cu")
		(net 94)
	)
	(segment
		(start 195.375 146)
		(end 195.375 146.05)
		(width 0.1)
		(layer "In2.Cu")
		(net 94)
	)
	(segment
		(start 225.254853 133.625447)
		(end 225.254854 133.625445)
		(width 0.13)
		(layer "In2.Cu")
		(net 94)
	)
	(segment
		(start 220.800074 138.080224)
		(end 220.800076 138.080223)
		(width 0.13)
		(layer "In2.Cu")
		(net 94)
	)
	(segment
		(start 196.741422 146.891422)
		(end 197.1 147.25)
		(width 0.1)
		(layer "In2.Cu")
		(net 94)
	)
	(segment
		(start 223.769926 135.110372)
		(end 223.769925 135.11037)
		(width 0.13)
		(layer "In2.Cu")
		(net 94)
	)
	(segment
		(start 195.289989 145.1)
		(end 195.125 145.264989)
		(width 0.1)
		(layer "In2.Cu")
		(net 94)
	)
	(segment
		(start 219.159761 137.012667)
		(end 220.227318 138.080224)
		(width 0.13)
		(layer "In2.Cu")
		(net 94)
	)
	(segment
		(start 222.702352 132.557871)
		(end 222.702353 132.55787)
		(width 0.13)
		(layer "In2.Cu")
		(net 94)
	)
	(segment
		(start 225.099469 131.072967)
		(end 226.167022 132.14052)
		(width 0.13)
		(layer "In2.Cu")
		(net 94)
	)
	(segment
		(start 209.78 144.300294)
		(end 209.78 143.400294)
		(width 0.13)
		(layer "In2.Cu")
		(net 94)
	)
	(segment
		(start 225.254852 133.052686)
		(end 225.254853 133.052686)
		(width 0.13)
		(layer "In2.Cu")
		(net 94)
	)
	(segment
		(start 248.73 109.675294)
		(end 248.73 106.549706)
		(width 0.13)
		(layer "In2.Cu")
		(net 94)
	)
	(segment
		(start 197.1 147.25)
		(end 197.1 149.658578)
		(width 0.1)
		(layer "In2.Cu")
		(net 94)
	)
	(segment
		(start 197.1 149.658578)
		(end 197.321422 149.88)
		(width 0.1)
		(layer "In2.Cu")
		(net 94)
	)
	(segment
		(start 248.28 113.300294)
		(end 248.28 110.125294)
		(width 0.13)
		(layer "In2.Cu")
		(net 94)
	)
	(segment
		(start 219.050297 139.829997)
		(end 219.315148 139.565148)
		(width 0.13)
		(layer "In2.Cu")
		(net 94)
	)
	(segment
		(start 223.769925 135.11037)
		(end 223.769926 135.11037)
		(width 0.13)
		(layer "In2.Cu")
		(net 94)
	)
	(segment
		(start 195.5 145.5)
		(end 195.51 145.49)
		(width 0.1)
		(layer "In2.Cu")
		(net 94)
	)
	(segment
		(start 243.263406 106.449803)
		(end 243.263406 106.445208)
		(width 0.13)
		(layer "In2.Cu")
		(net 94)
	)
	(segment
		(start 225.254853 133.052686)
		(end 224.187301 131.985134)
		(width 0.13)
		(layer "In2.Cu")
		(net 94)
	)
	(segment
		(start 196.3 146.891422)
		(end 196.741422 146.891422)
		(width 0.1)
		(layer "In2.Cu")
		(net 94)
	)
	(segment
		(start 196.15 146.715685)
		(end 196.15 146.741422)
		(width 0.1)
		(layer "In2.Cu")
		(net 94)
	)
	(segment
		(start 242.845 106.847)
		(end 243.15 107.152)
		(width 0.13)
		(layer "In2.Cu")
		(net 94)
	)
	(segment
		(start 222.284999 136.595296)
		(end 222.285 136.595296)
		(width 0.13)
		(layer "In2.Cu")
		(net 94)
	)
	(segment
		(start 195.125 146.75)
		(end 195.266422 146.891422)
		(width 0.1)
		(layer "In2.Cu")
		(net 94)
	)
	(segment
		(start 209.78 143.400294)
		(end 213.350294 139.83)
		(width 0.13)
		(layer "In2.Cu")
		(net 94)
	)
	(segment
		(start 195.45 145.1)
		(end 195.289989 145.1)
		(width 0.1)
		(layer "In2.Cu")
		(net 94)
	)
	(segment
		(start 242.909853 106.409853)
		(end 242.845 106.474706)
		(width 0.13)
		(layer "In2.Cu")
		(net 94)
	)
	(segment
		(start 195.51 145.49)
		(end 195.51 145.16)
		(width 0.1)
		(layer "In2.Cu")
		(net 94)
	)
	(segment
		(start 222.285 136.595298)
		(end 222.284999 136.595296)
		(width 0.13)
		(layer "In2.Cu")
		(net 94)
	)
	(segment
		(start 221.217471 134.04284)
		(end 221.217471 134.042841)
		(width 0.13)
		(layer "In2.Cu")
		(net 94)
	)
	(segment
		(start 220.800076 138.080223)
		(end 220.800074 138.080222)
		(width 0.13)
		(layer "In2.Cu")
		(net 94)
	)
	(segment
		(start 248.015147 105.834853)
		(end 247.900294 105.72)
		(width 0.13)
		(layer "In2.Cu")
		(net 94)
	)
	(segment
		(start 226.739777 132.140518)
		(end 242.525294 116.355)
		(width 0.13)
		(layer "In2.Cu")
		(net 94)
	)
	(segment
		(start 195.125 146.3)
		(end 195.125 146.75)
		(width 0.1)
		(layer "In2.Cu")
		(net 94)
	)
	(segment
		(start 220.800075 137.507464)
		(end 219.732545 136.439934)
		(width 0.13)
		(layer "In2.Cu")
		(net 94)
	)
	(segment
		(start 242.525294 116.355)
		(end 245.225294 116.355)
		(width 0.13)
		(layer "In2.Cu")
		(net 94)
	)
	(segment
		(start 204.200294 149.88)
		(end 209.78 144.300294)
		(width 0.13)
		(layer "In2.Cu")
		(net 94)
	)
	(segment
		(start 195.125 145.264989)
		(end 195.125 145.75)
		(width 0.1)
		(layer "In2.Cu")
		(net 94)
	)
	(segment
		(start 195.266422 146.891422)
		(end 195.7 146.891422)
		(width 0.1)
		(layer "In2.Cu")
		(net 94)
	)
	(segment
		(start 243.263406 106.445208)
		(end 243.228051 106.409853)
		(width 0.13)
		(layer "In2.Cu")
		(net 94)
	)
	(arc
		(start 248.580831 106.400536)
		(mid 248.439409 106.341958)
		(end 248.297988 106.400537)
		(width 0.13)
		(layer "In2.Cu")
		(net 94)
	)
	(arc
		(start 243.610356 106.478555)
		(mid 243.451257 106.544456)
		(end 243.292158 106.478555)
		(width 0.13)
		(layer "In2.Cu")
		(net 94)
	)
	(arc
		(start 222.285 136.595296)
		(mid 222.403623 136.308916)
		(end 222.285 136.022538)
		(width 0.13)
		(layer "In2.Cu")
		(net 94)
	)
	(arc
		(start 220.800074 138.080222)
		(mid 220.918697 137.793842)
		(end 220.800074 137.507464)
		(width 0.13)
		(layer "In2.Cu")
		(net 94)
	)
	(arc
		(start 243.228051 106.409853)
		(mid 243.068952 106.343952)
		(end 242.909853 106.409853)
		(width 0.13)
		(layer "In2.Cu")
		(net 94)
	)
	(arc
		(start 195.25 145.875)
		(mid 195.338388 145.911612)
		(end 195.375 146)
		(width 0.1)
		(layer "In2.Cu")
		(net 94)
	)
	(arc
		(start 219.315148 139.565148)
		(mid 219.433771 139.278768)
		(end 219.315148 138.99239)
		(width 0.13)
		(layer "In2.Cu")
		(net 94)
	)
	(arc
		(start 195.7 146.891422)
		(mid 195.806066 146.847488)
		(end 195.85 146.741422)
		(width 0.1)
		(layer "In2.Cu")
		(net 94)
	)
	(arc
		(start 221.217471 134.955008)
		(mid 221.028555 134.498924)
		(end 221.217471 134.04284)
		(width 0.13)
		(layer "In2.Cu")
		(net 94)
	)
	(arc
		(start 218.247593 137.924834)
		(mid 218.058677 137.46875)
		(end 218.247593 137.012666)
		(width 0.13)
		(layer "In2.Cu")
		(net 94)
	)
	(arc
		(start 248.015146 106.117696)
		(mid 248.073725 105.976275)
		(end 248.015147 105.834853)
		(width 0.13)
		(layer "In2.Cu")
		(net 94)
	)
	(arc
		(start 221.217471 134.042841)
		(mid 221.673555 133.853925)
		(end 222.129639 134.042841)
		(width 0.13)
		(layer "In2.Cu")
		(net 94)
	)
	(arc
		(start 219.732545 136.439934)
		(mid 219.543629 135.98385)
		(end 219.732545 135.527766)
		(width 0.13)
		(layer "In2.Cu")
		(net 94)
	)
	(arc
		(start 224.187301 131.072967)
		(mid 224.643385 130.884051)
		(end 225.099469 131.072967)
		(width 0.13)
		(layer "In2.Cu")
		(net 94)
	)
	(arc
		(start 248.254654 106.443872)
		(mid 248.113233 106.502451)
		(end 247.971811 106.443873)
		(width 0.13)
		(layer "In2.Cu")
		(net 94)
	)
	(arc
		(start 224.682096 133.625446)
		(mid 224.968474 133.744068)
		(end 225.254853 133.625447)
		(width 0.13)
		(layer "In2.Cu")
		(net 94)
	)
	(arc
		(start 220.227318 138.080224)
		(mid 220.513696 138.198846)
		(end 220.800074 138.080224)
		(width 0.13)
		(layer "In2.Cu")
		(net 94)
	)
	(arc
		(start 195.85 146.715685)
		(mid 195.893934 146.609619)
		(end 196 146.565685)
		(width 0.1)
		(layer "In2.Cu")
		(net 94)
	)
	(arc
		(start 222.702353 132.557871)
		(mid 223.158437 132.368955)
		(end 223.614521 132.557871)
		(width 0.13)
		(layer "In2.Cu")
		(net 94)
	)
	(arc
		(start 196 146.565685)
		(mid 196.106066 146.609619)
		(end 196.15 146.715685)
		(width 0.1)
		(layer "In2.Cu")
		(net 94)
	)
	(arc
		(start 222.702353 133.470038)
		(mid 222.513436 133.013956)
		(end 222.702352 132.557871)
		(width 0.13)
		(layer "In2.Cu")
		(net 94)
	)
	(arc
		(start 247.97181 106.443873)
		(mid 247.913232 106.302451)
		(end 247.971811 106.16103)
		(width 0.13)
		(layer "In2.Cu")
		(net 94)
	)
	(arc
		(start 243.546248 105.773455)
		(mid 243.480347 105.932554)
		(end 243.546248 106.091653)
		(width 0.13)
		(layer "In2.Cu")
		(net 94)
	)
	(arc
		(start 195.375 146.05)
		(mid 195.338388 146.138388)
		(end 195.25 146.175)
		(width 0.1)
		(layer "In2.Cu")
		(net 94)
	)
	(arc
		(start 223.769926 135.11037)
		(mid 223.888549 134.82399)
		(end 223.769926 134.537612)
		(width 0.13)
		(layer "In2.Cu")
		(net 94)
	)
	(arc
		(start 218.247593 137.012667)
		(mid 218.703677 136.823751)
		(end 219.159761 137.012667)
		(width 0.13)
		(layer "In2.Cu")
		(net 94)
	)
	(arc
		(start 195.25 146.175)
		(mid 195.161612 146.211612)
		(end 195.125 146.3)
		(width 0.1)
		(layer "In2.Cu")
		(net 94)
	)
	(arc
		(start 219.732545 135.527767)
		(mid 220.188629 135.338851)
		(end 220.644713 135.527767)
		(width 0.13)
		(layer "In2.Cu")
		(net 94)
	)
	(arc
		(start 226.167022 132.14052)
		(mid 226.4534 132.259142)
		(end 226.739778 132.14052)
		(width 0.13)
		(layer "In2.Cu")
		(net 94)
	)
	(arc
		(start 243.610356 106.160355)
		(mid 243.676257 106.319455)
		(end 243.610356 106.478555)
		(width 0.13)
		(layer "In2.Cu")
		(net 94)
	)
	(arc
		(start 195.125 145.75)
		(mid 195.161612 145.838388)
		(end 195.25 145.875)
		(width 0.1)
		(layer "In2.Cu")
		(net 94)
	)
	(arc
		(start 221.712244 136.595298)
		(mid 221.998622 136.71392)
		(end 222.285 136.595298)
		(width 0.13)
		(layer "In2.Cu")
		(net 94)
	)
	(arc
		(start 225.254852 133.625444)
		(mid 225.373475 133.339064)
		(end 225.254852 133.052686)
		(width 0.13)
		(layer "In2.Cu")
		(net 94)
	)
	(arc
		(start 196.15 146.741422)
		(mid 196.193934 146.847488)
		(end 196.3 146.891422)
		(width 0.1)
		(layer "In2.Cu")
		(net 94)
	)
	(arc
		(start 223.19717 135.110372)
		(mid 223.483548 135.228994)
		(end 223.769926 135.110372)
		(width 0.13)
		(layer "In2.Cu")
		(net 94)
	)
	(arc
		(start 224.187301 131.985134)
		(mid 223.998385 131.52905)
		(end 224.187301 131.072966)
		(width 0.13)
		(layer "In2.Cu")
		(net 94)
	)
	(segment
		(start 135.925 139.807851)
		(end 135.925 138.907851)
		(width 0.15)
		(layer "F.Cu")
		(net 95)
	)
	(segment
		(start 133.425 139.807851)
		(end 133.425 138.907851)
		(width 0.15)
		(layer "F.Cu")
		(net 95)
	)
	(via
		(at 135.925 138.907851)
		(size 0.45)
		(drill 0.1)
		(layers "F.Cu" "B.Cu")
		(remove_unused_layers yes)
		(keep_end_layers yes)
		(zone_layer_connections)
		(net 95)
	)
	(via
		(at 133.425 138.907851)
		(size 0.45)
		(drill 0.1)
		(layers "F.Cu" "B.Cu")
		(remove_unused_layers yes)
		(keep_end_layers yes)
		(zone_layer_connections)
		(net 95)
	)
	(segment
		(start 135.224499 139.999)
		(end 136.424499 139.999)
		(width 0.256)
		(layer "B.Cu")
		(net 95)
	)
	(segment
		(start 134.161328 139.216157)
		(end 134.161328 139.962171)
		(width 0.256)
		(layer "B.Cu")
		(net 95)
	)
	(segment
		(start 135.099328 141.007157)
		(end 135.174499 140.931986)
		(width 0.256)
		(layer "B.Cu")
		(net 95)
	)
	(segment
		(start 136.724499 139.699)
		(end 136.724499 139.233)
		(width 0.256)
		(layer "B.Cu")
		(net 95)
	)
	(segment
		(start 132.624499 139.216157)
		(end 132.624499 139.699)
		(width 0.256)
		(layer "B.Cu")
		(net 95)
	)
	(segment
		(start 135.174499 139.999)
		(end 135.024499 139.999)
		(width 0.256)
		(layer "B.Cu")
		(net 95)
	)
	(segment
		(start 135.024499 139.999)
		(end 135.224499 139.999)
		(width 0.256)
		(layer "B.Cu")
		(net 95)
	)
	(segment
		(start 135.174499 140.931986)
		(end 135.174499 139.999)
		(width 0.256)
		(layer "B.Cu")
		(net 95)
	)
	(segment
		(start 134.146328 139.217157)
		(end 133.837022 138.907851)
		(width 0.2)
		(layer "B.Cu")
		(net 95)
	)
	(segment
		(start 134.161328 139.962171)
		(end 134.124499 139.999)
		(width 0.256)
		(layer "B.Cu")
		(net 95)
	)
	(segment
		(start 133.837022 138.907851)
		(end 133.425 138.907851)
		(width 0.2)
		(layer "B.Cu")
		(net 95)
	)
	(segment
		(start 135.186328 139.960829)
		(end 135.224499 139.999)
		(width 0.256)
		(layer "B.Cu")
		(net 95)
	)
	(segment
		(start 135.495634 138.907851)
		(end 135.186328 139.217157)
		(width 0.2)
		(layer "B.Cu")
		(net 95)
	)
	(segment
		(start 134.124499 139.999)
		(end 135.024499 139.999)
		(width 0.256)
		(layer "B.Cu")
		(net 95)
	)
	(segment
		(start 132.624499 139.699)
		(end 132.924499 139.999)
		(width 0.256)
		(layer "B.Cu")
		(net 95)
	)
	(segment
		(start 135.186328 139.216157)
		(end 135.186328 139.960829)
		(width 0.256)
		(layer "B.Cu")
		(net 95)
	)
	(segment
		(start 135.925 138.907851)
		(end 135.495634 138.907851)
		(width 0.2)
		(layer "B.Cu")
		(net 95)
	)
	(segment
		(start 132.924499 139.999)
		(end 134.124499 139.999)
		(width 0.256)
		(layer "B.Cu")
		(net 95)
	)
	(segment
		(start 136.424499 139.999)
		(end 136.724499 139.699)
		(width 0.256)
		(layer "B.Cu")
		(net 95)
	)
	(segment
		(start 142.625 144.422851)
		(end 141.525 144.422851)
		(width 0.4)
		(layer "F.Cu")
		(net 96)
	)
	(segment
		(start 143.725 144.422851)
		(end 142.625 144.422851)
		(width 0.4)
		(layer "F.Cu")
		(net 96)
	)
	(segment
		(start 144.925 144.672149)
		(end 144.675702 144.422851)
		(width 0.2)
		(layer "F.Cu")
		(net 96)
	)
	(segment
		(start 144.675702 144.422851)
		(end 143.725 144.422851)
		(width 0.4)
		(layer "F.Cu")
		(net 96)
	)
	(segment
		(start 141.452149 144.362149)
		(end 141.525 144.362149)
		(width 0.256)
		(layer "F.Cu")
		(net 96)
	)
	(segment
		(start 138.107149 142.49)
		(end 139.58 142.49)
		(width 0.256)
		(layer "F.Cu")
		(net 96)
	)
	(segment
		(start 138.102149 142.485)
		(end 138.107149 142.49)
		(width 0.256)
		(layer "F.Cu")
		(net 96)
	)
	(segment
		(start 139.58 142.49)
		(end 141.452149 144.362149)
		(width 0.256)
		(layer "F.Cu")
		(net 96)
	)
	(segment
		(start 137.425 139.807851)
		(end 137.425 138.907851)
		(width 0.15)
		(layer "F.Cu")
		(net 97)
	)
	(segment
		(start 131.925 139.807851)
		(end 131.925 138.907851)
		(width 0.15)
		(layer "F.Cu")
		(net 97)
	)
	(via
		(at 137.425 138.907851)
		(size 0.45)
		(drill 0.1)
		(layers "F.Cu" "B.Cu")
		(remove_unused_layers yes)
		(keep_end_layers yes)
		(zone_layer_connections)
		(net 97)
	)
	(via
		(at 131.925 138.907851)
		(size 0.45)
		(drill 0.1)
		(layers "F.Cu" "B.Cu")
		(remove_unused_layers yes)
		(keep_end_layers yes)
		(zone_layer_connections)
		(net 97)
	)
	(segment
		(start 137.425 138.907851)
		(end 137.774306 139.257157)
		(width 0.2)
		(layer "B.Cu")
		(net 97)
	)
	(segment
		(start 137.774306 139.257157)
		(end 138.526328 139.257157)
		(width 0.2)
		(layer "B.Cu")
		(net 97)
	)
	(segment
		(start 130.211328 138.567157)
		(end 131.211328 138.567157)
		(width 0.2)
		(layer "B.Cu")
		(net 97)
	)
	(segment
		(start 131.925 138.907851)
		(end 131.552022 138.907851)
		(width 0.2)
		(layer "B.Cu")
		(net 97)
	)
	(segment
		(start 138.625 139.158485)
		(end 138.625 138.007851)
		(width 0.2)
		(layer "B.Cu")
		(net 97)
	)
	(segment
		(start 132.491328 137.287157)
		(end 131.211328 138.567157)
		(width 0.2)
		(layer "B.Cu")
		(net 97)
	)
	(segment
		(start 138.625 138.007851)
		(end 137.904306 137.287157)
		(width 0.2)
		(layer "B.Cu")
		(net 97)
	)
	(segment
		(start 138.526328 139.257157)
		(end 138.625 139.158485)
		(width 0.2)
		(layer "B.Cu")
		(net 97)
	)
	(segment
		(start 137.904306 137.287157)
		(end 132.491328 137.287157)
		(width 0.2)
		(layer "B.Cu")
		(net 97)
	)
	(segment
		(start 131.552022 138.907851)
		(end 131.211328 138.567157)
		(width 0.2)
		(layer "B.Cu")
		(net 97)
	)
	(segment
		(start 175.999501 156.0005)
		(end 175.5 156.5)
		(width 0.256)
		(layer "F.Cu")
		(net 98)
	)
	(via
		(at 155.65 190.8)
		(size 0.45)
		(drill 0.1)
		(layers "F.Cu" "B.Cu")
		(remove_unused_layers yes)
		(keep_end_layers yes)
		(zone_layer_connections)
		(net 98)
	)
	(via
		(at 175.5 156.5)
		(size 0.45)
		(drill 0.1)
		(layers "F.Cu" "B.Cu")
		(remove_unused_layers yes)
		(keep_end_layers yes)
		(zone_layer_connections)
		(net 98)
	)
	(segment
		(start 155.649499 194.273645)
		(end 155.649499 192.091677)
		(width 0.201)
		(layer "B.Cu")
		(net 98)
	)
	(segment
		(start 155.65 199.25)
		(end 155.65 194.274855)
		(width 0.201)
		(layer "B.Cu")
		(net 98)
	)
	(segment
		(start 155.639499 192.073631)
		(end 155.639499 191.299)
		(width 0.201)
		(layer "B.Cu")
		(net 98)
	)
	(segment
		(start 155.648947 192.083079)
		(end 155.639499 192.073631)
		(width 0.201)
		(layer "B.Cu")
		(net 98)
	)
	(segment
		(start 155.639499 191.274251)
		(end 155.639499 190.274)
		(width 0.256)
		(layer "B.Cu")
		(net 98)
	)
	(arc
		(start 155.649499 192.091677)
		(mid 155.649707 192.087495)
		(end 155.648947 192.083079)
		(width 0.201)
		(layer "B.Cu")
		(net 98)
	)
	(arc
		(start 155.639499 191.274251)
		(mid 155.644047 191.297116)
		(end 155.656999 191.3165)
		(width 0.256)
		(layer "B.Cu")
		(net 98)
	)
	(arc
		(start 155.65 194.274855)
		(mid 155.649934 194.274527)
		(end 155.649749 194.27425)
		(width 0.201)
		(layer "B.Cu")
		(net 98)
	)
	(arc
		(start 155.649749 194.27425)
		(mid 155.649563 194.273972)
		(end 155.649499 194.273645)
		(width 0.201)
		(layer "B.Cu")
		(net 98)
	)
	(segment
		(start 173.95 158.05)
		(end 168 158.05)
		(width 0.1)
		(layer "In2.Cu")
		(net 98)
	)
	(segment
		(start 175.5 156.5)
		(end 173.95 158.05)
		(width 0.1)
		(layer "In2.Cu")
		(net 98)
	)
	(segment
		(start 164.75 161.3)
		(end 164.75 169.857707)
		(width 0.1)
		(layer "In2.Cu")
		(net 98)
	)
	(segment
		(start 153.3 190.8)
		(end 155.65 190.8)
		(width 0.1)
		(layer "In2.Cu")
		(net 98)
	)
	(segment
		(start 152 182.607707)
		(end 152 189.5)
		(width 0.1)
		(layer "In2.Cu")
		(net 98)
	)
	(segment
		(start 164.75 169.857707)
		(end 152 182.607707)
		(width 0.1)
		(layer "In2.Cu")
		(net 98)
	)
	(segment
		(start 168 158.05)
		(end 164.75 161.3)
		(width 0.1)
		(layer "In2.Cu")
		(net 98)
	)
	(segment
		(start 152 189.5)
		(end 153.3 190.8)
		(width 0.1)
		(layer "In2.Cu")
		(net 98)
	)
	(segment
		(start 171.75 106)
		(end 171.75 107.152)
		(width 0.38)
		(layer "F.Cu")
		(net 99)
	)
	(segment
		(start 189.0005 145.9995)
		(end 189.5 145.5)
		(width 0.256)
		(layer "F.Cu")
		(net 99)
	)
	(via
		(at 171.75 107.152)
		(size 0.45)
		(drill 0.1)
		(layers "F.Cu" "B.Cu")
		(remove_unused_layers yes)
		(keep_end_layers yes)
		(zone_layer_connections)
		(net 99)
	)
	(via
		(at 189.5 145.5)
		(size 0.45)
		(drill 0.1)
		(layers "F.Cu" "B.Cu")
		(remove_unused_layers yes)
		(keep_end_layers yes)
		(zone_layer_connections)
		(net 99)
	)
	(segment
		(start 190 146)
		(end 190 146.8)
		(width 0.148)
		(layer "In6.Cu")
		(net 99)
	)
	(segment
		(start 190.2 147)
		(end 194.75 147)
		(width 0.148)
		(layer "In6.Cu")
		(net 99)
	)
	(segment
		(start 194.75 147)
		(end 195 146.75)
		(width 0.148)
		(layer "In6.Cu")
		(net 99)
	)
	(segment
		(start 190 146.8)
		(end 190.2 147)
		(width 0.148)
		(layer "In6.Cu")
		(net 99)
	)
	(segment
		(start 189.5 145.5)
		(end 190 146)
		(width 0.148)
		(layer "In6.Cu")
		(net 99)
	)
	(segment
		(start 174.275 112.25)
		(end 174.275 111.180364)
		(width 0.148)
		(layer "In6.Cu")
		(net 99)
	)
	(segment
		(start 172.85 108.252)
		(end 171.75 107.152)
		(width 0.148)
		(layer "In6.Cu")
		(net 99)
	)
	(segment
		(start 174.275 111.180364)
		(end 172.85 109.755364)
		(width 0.148)
		(layer "In6.Cu")
		(net 99)
	)
	(segment
		(start 195 128)
		(end 180.025 113.025)
		(width 0.148)
		(layer "In6.Cu")
		(net 99)
	)
	(segment
		(start 195 146.75)
		(end 195 128)
		(width 0.148)
		(layer "In6.Cu")
		(net 99)
	)
	(segment
		(start 175.05 113.025)
		(end 174.275 112.25)
		(width 0.148)
		(layer "In6.Cu")
		(net 99)
	)
	(segment
		(start 172.85 109.755364)
		(end 172.85 108.252)
		(width 0.148)
		(layer "In6.Cu")
		(net 99)
	)
	(segment
		(start 180.025 113.025)
		(end 175.05 113.025)
		(width 0.148)
		(layer "In6.Cu")
		(net 99)
	)
	(segment
		(start 190.0005 144.9995)
		(end 190.5 144.5)
		(width 0.256)
		(layer "F.Cu")
		(net 100)
	)
	(segment
		(start 170.05 106)
		(end 170.05 107.152)
		(width 0.38)
		(layer "F.Cu")
		(net 100)
	)
	(via
		(at 170.05 107.152)
		(size 0.45)
		(drill 0.1)
		(layers "F.Cu" "B.Cu")
		(remove_unused_layers yes)
		(keep_end_layers yes)
		(zone_layer_connections)
		(net 100)
	)
	(via
		(at 190.5 144.5)
		(size 0.45)
		(drill 0.1)
		(layers "F.Cu" "B.Cu")
		(remove_unused_layers yes)
		(keep_end_layers yes)
		(zone_layer_connections)
		(net 100)
	)
	(segment
		(start 193 144.75)
		(end 192.75 145)
		(width 0.148)
		(layer "In6.Cu")
		(net 100)
	)
	(segment
		(start 175.270675 115.920676)
		(end 175.270675 115.920675)
		(width 0.148)
		(layer "In6.Cu")
		(net 100)
	)
	(segment
		(start 193 129)
		(end 193 144.75)
		(width 0.148)
		(layer "In6.Cu")
		(net 100)
	)
	(segment
		(start 191 145)
		(end 190.5 144.5)
		(width 0.148)
		(layer "In6.Cu")
		(net 100)
	)
	(segment
		(start 174.04135 116.141351)
		(end 175.05 116.141351)
		(width 0.148)
		(layer "In6.Cu")
		(net 100)
	)
	(segment
		(start 170.05 110.825)
		(end 170.05 112.8)
		(width 0.148)
		(layer "In6.Cu")
		(net 100)
	)
	(segment
		(start 179.4 115.7)
		(end 179.7 115.7)
		(width 0.148)
		(layer "In6.Cu")
		(net 100)
	)
	(segment
		(start 170.05 107.152)
		(end 170.825 107.927)
		(width 0.148)
		(layer "In6.Cu")
		(net 100)
	)
	(segment
		(start 170.05 112.8)
		(end 172.95 115.7)
		(width 0.148)
		(layer "In6.Cu")
		(net 100)
	)
	(segment
		(start 173.820675 115.920675)
		(end 173.820675 115.920676)
		(width 0.148)
		(layer "In6.Cu")
		(net 100)
	)
	(segment
		(start 172.95 115.7)
		(end 173.6 115.7)
		(width 0.148)
		(layer "In6.Cu")
		(net 100)
	)
	(segment
		(start 170.825 110.05)
		(end 170.05 110.825)
		(width 0.148)
		(layer "In6.Cu")
		(net 100)
	)
	(segment
		(start 170.825 107.927)
		(end 170.825 110.05)
		(width 0.148)
		(layer "In6.Cu")
		(net 100)
	)
	(segment
		(start 192.75 145)
		(end 191 145)
		(width 0.148)
		(layer "In6.Cu")
		(net 100)
	)
	(segment
		(start 178.39135 115.7)
		(end 179.4 115.7)
		(width 0.148)
		(layer "In6.Cu")
		(net 100)
	)
	(segment
		(start 176.720675 115.920675)
		(end 176.720675 115.920676)
		(width 0.148)
		(layer "In6.Cu")
		(net 100)
	)
	(segment
		(start 178.170675 115.920676)
		(end 178.170675 115.920675)
		(width 0.148)
		(layer "In6.Cu")
		(net 100)
	)
	(segment
		(start 175.49135 115.7)
		(end 176.5 115.7)
		(width 0.148)
		(layer "In6.Cu")
		(net 100)
	)
	(segment
		(start 179.7 115.7)
		(end 193 129)
		(width 0.148)
		(layer "In6.Cu")
		(net 100)
	)
	(segment
		(start 176.94135 116.141351)
		(end 177.95 116.141351)
		(width 0.148)
		(layer "In6.Cu")
		(net 100)
	)
	(arc
		(start 173.6 115.7)
		(mid 173.756041 115.764634)
		(end 173.820675 115.920675)
		(width 0.148)
		(layer "In6.Cu")
		(net 100)
	)
	(arc
		(start 177.95 116.141351)
		(mid 178.106041 116.076717)
		(end 178.170675 115.920676)
		(width 0.148)
		(layer "In6.Cu")
		(net 100)
	)
	(arc
		(start 176.720675 115.920676)
		(mid 176.785309 116.076717)
		(end 176.94135 116.141351)
		(width 0.148)
		(layer "In6.Cu")
		(net 100)
	)
	(arc
		(start 178.170675 115.920675)
		(mid 178.235309 115.764634)
		(end 178.39135 115.7)
		(width 0.148)
		(layer "In6.Cu")
		(net 100)
	)
	(arc
		(start 175.05 116.141351)
		(mid 175.206041 116.076717)
		(end 175.270675 115.920676)
		(width 0.148)
		(layer "In6.Cu")
		(net 100)
	)
	(arc
		(start 176.5 115.7)
		(mid 176.656041 115.764634)
		(end 176.720675 115.920675)
		(width 0.148)
		(layer "In6.Cu")
		(net 100)
	)
	(arc
		(start 175.270675 115.920675)
		(mid 175.335309 115.764634)
		(end 175.49135 115.7)
		(width 0.148)
		(layer "In6.Cu")
		(net 100)
	)
	(arc
		(start 173.820675 115.920676)
		(mid 173.885309 116.076717)
		(end 174.04135 116.141351)
		(width 0.148)
		(layer "In6.Cu")
		(net 100)
	)
	(segment
		(start 195.0005 144.9995)
		(end 195.5 144.5)
		(width 0.256)
		(layer "F.Cu")
		(net 101)
	)
	(segment
		(start 242.301 106)
		(end 242.301 107.152)
		(width 0.38)
		(layer "F.Cu")
		(net 101)
	)
	(via
		(at 242.3 107.152)
		(size 0.45)
		(drill 0.1)
		(layers "F.Cu" "B.Cu")
		(remove_unused_layers yes)
		(keep_end_layers yes)
		(zone_layer_connections)
		(net 101)
	)
	(via
		(at 195.5 144.5)
		(size 0.45)
		(drill 0.1)
		(layers "F.Cu" "B.Cu")
		(remove_unused_layers yes)
		(keep_end_layers yes)
		(zone_layer_connections)
		(net 101)
	)
	(segment
		(start 222.872057 132.727577)
		(end 222.872059 132.727576)
		(width 0.13)
		(layer "In2.Cu")
		(net 101)
	)
	(segment
		(start 220.969779 137.337759)
		(end 220.96978 137.337759)
		(width 0.13)
		(layer "In2.Cu")
		(net 101)
	)
	(segment
		(start 194.925 145.182145)
		(end 194.925 146.832844)
		(width 0.1)
		(layer "In2.Cu")
		(net 101)
	)
	(segment
		(start 226.909483 132.310224)
		(end 242.624706 116.595)
		(width 0.13)
		(layer "In2.Cu")
		(net 101)
	)
	(segment
		(start 219.149706 140.07)
		(end 219.484853 139.734853)
		(width 0.13)
		(layer "In2.Cu")
		(net 101)
	)
	(segment
		(start 225.424557 132.882981)
		(end 225.424558 132.882981)
		(width 0.13)
		(layer "In2.Cu")
		(net 101)
	)
	(segment
		(start 248.52 110.224706)
		(end 248.97 109.774706)
		(width 0.13)
		(layer "In2.Cu")
		(net 101)
	)
	(segment
		(start 218.417297 137.182373)
		(end 218.417299 137.182372)
		(width 0.13)
		(layer "In2.Cu")
		(net 101)
	)
	(segment
		(start 243.500294 105.48)
		(end 242.605 106.375294)
		(width 0.13)
		(layer "In2.Cu")
		(net 101)
	)
	(segment
		(start 242.605 106.375294)
		(end 242.605 106.847)
		(width 0.13)
		(layer "In2.Cu")
		(net 101)
	)
	(segment
		(start 222.872057 132.727576)
		(end 222.872057 132.727577)
		(width 0.13)
		(layer "In2.Cu")
		(net 101)
	)
	(segment
		(start 218.990055 137.182372)
		(end 218.990055 137.182373)
		(width 0.13)
		(layer "In2.Cu")
		(net 101)
	)
	(segment
		(start 220.96978 138.24993)
		(end 220.969779 138.249928)
		(width 0.13)
		(layer "In2.Cu")
		(net 101)
	)
	(segment
		(start 195.207145 144.9)
		(end 194.925 145.182145)
		(width 0.1)
		(layer "In2.Cu")
		(net 101)
	)
	(segment
		(start 221.387176 134.212547)
		(end 221.387176 134.212548)
		(width 0.13)
		(layer "In2.Cu")
		(net 101)
	)
	(segment
		(start 196.658578 147.091422)
		(end 196.9 147.332844)
		(width 0.1)
		(layer "In2.Cu")
		(net 101)
	)
	(segment
		(start 221.959932 134.212548)
		(end 221.959934 134.212547)
		(width 0.13)
		(layer "In2.Cu")
		(net 101)
	)
	(segment
		(start 204.299706 150.12)
		(end 210.02 144.399706)
		(width 0.13)
		(layer "In2.Cu")
		(net 101)
	)
	(segment
		(start 194.925 146.832844)
		(end 195.183578 147.091422)
		(width 0.1)
		(layer "In2.Cu")
		(net 101)
	)
	(segment
		(start 223.444815 132.727577)
		(end 224.51239 133.795152)
		(width 0.13)
		(layer "In2.Cu")
		(net 101)
	)
	(segment
		(start 224.357006 131.242673)
		(end 224.357006 131.242674)
		(width 0.13)
		(layer "In2.Cu")
		(net 101)
	)
	(segment
		(start 196.9 149.741422)
		(end 197.278578 150.12)
		(width 0.1)
		(layer "In2.Cu")
		(net 101)
	)
	(segment
		(start 242.624706 116.595)
		(end 245.324706 116.595)
		(width 0.13)
		(layer "In2.Cu")
		(net 101)
	)
	(segment
		(start 220.969779 138.249928)
		(end 220.969779 138.249927)
		(width 0.13)
		(layer "In2.Cu")
		(net 101)
	)
	(segment
		(start 201.855 150.12)
		(end 204.299706 150.12)
		(width 0.13)
		(layer "In2.Cu")
		(net 101)
	)
	(segment
		(start 219.90225 135.697473)
		(end 219.90225 135.697474)
		(width 0.13)
		(layer "In2.Cu")
		(net 101)
	)
	(segment
		(start 245.324706 116.595)
		(end 248.52 113.399706)
		(width 0.13)
		(layer "In2.Cu")
		(net 101)
	)
	(segment
		(start 226.909485 132.310226)
		(end 226.909483 132.310224)
		(width 0.13)
		(layer "In2.Cu")
		(net 101)
	)
	(segment
		(start 248.97 106.450294)
		(end 247.999706 105.48)
		(width 0.13)
		(layer "In2.Cu")
		(net 101)
	)
	(segment
		(start 196.9 147.332844)
		(end 196.9 149.741422)
		(width 0.1)
		(layer "In2.Cu")
		(net 101)
	)
	(segment
		(start 195.45 144.9)
		(end 195.207145 144.9)
		(width 0.1)
		(layer "In2.Cu")
		(net 101)
	)
	(segment
		(start 222.454705 135.852833)
		(end 222.454706 135.852833)
		(width 0.13)
		(layer "In2.Cu")
		(net 101)
	)
	(segment
		(start 225.424557 133.795153)
		(end 225.424558 133.795152)
		(width 0.13)
		(layer "In2.Cu")
		(net 101)
	)
	(segment
		(start 224.929764 131.242673)
		(end 225.997317 132.310226)
		(width 0.13)
		(layer "In2.Cu")
		(net 101)
	)
	(segment
		(start 221.959934 134.212547)
		(end 223.027465 135.280078)
		(width 0.13)
		(layer "In2.Cu")
		(net 101)
	)
	(segment
		(start 223.939631 134.367907)
		(end 223.939632 134.367907)
		(width 0.13)
		(layer "In2.Cu")
		(net 101)
	)
	(segment
		(start 195.183578 147.091422)
		(end 196.658578 147.091422)
		(width 0.1)
		(layer "In2.Cu")
		(net 101)
	)
	(segment
		(start 213.449706 140.07)
		(end 219.149706 140.07)
		(width 0.13)
		(layer "In2.Cu")
		(net 101)
	)
	(segment
		(start 223.939631 135.280076)
		(end 223.939631 135.280075)
		(width 0.13)
		(layer "In2.Cu")
		(net 101)
	)
	(segment
		(start 220.475006 135.697474)
		(end 220.475008 135.697473)
		(width 0.13)
		(layer "In2.Cu")
		(net 101)
	)
	(segment
		(start 222.454707 136.765004)
		(end 222.454705 136.765002)
		(width 0.13)
		(layer "In2.Cu")
		(net 101)
	)
	(segment
		(start 197.278578 150.12)
		(end 201.855 150.12)
		(width 0.1)
		(layer "In2.Cu")
		(net 101)
	)
	(segment
		(start 222.454706 135.852833)
		(end 221.387176 134.785303)
		(width 0.13)
		(layer "In2.Cu")
		(net 101)
	)
	(segment
		(start 223.444815 132.727576)
		(end 223.444815 132.727577)
		(width 0.13)
		(layer "In2.Cu")
		(net 101)
	)
	(segment
		(start 242.605 106.847)
		(end 242.3 107.152)
		(width 0.13)
		(layer "In2.Cu")
		(net 101)
	)
	(segment
		(start 219.484854 138.822685)
		(end 218.417298 137.755129)
		(width 0.13)
		(layer "In2.Cu")
		(net 101)
	)
	(segment
		(start 218.990055 137.182373)
		(end 220.057612 138.24993)
		(width 0.13)
		(layer "In2.Cu")
		(net 101)
	)
	(segment
		(start 224.929762 131.242674)
		(end 224.929764 131.242673)
		(width 0.13)
		(layer "In2.Cu")
		(net 101)
	)
	(segment
		(start 223.939632 134.367907)
		(end 222.872058 133.300333)
		(width 0.13)
		(layer "In2.Cu")
		(net 101)
	)
	(segment
		(start 220.475008 135.697473)
		(end 221.542539 136.765004)
		(width 0.13)
		(layer "In2.Cu")
		(net 101)
	)
	(segment
		(start 210.02 144.399706)
		(end 210.02 143.499706)
		(width 0.13)
		(layer "In2.Cu")
		(net 101)
	)
	(segment
		(start 219.484853 138.822685)
		(end 219.484854 138.822685)
		(width 0.13)
		(layer "In2.Cu")
		(net 101)
	)
	(segment
		(start 247.999706 105.48)
		(end 243.500294 105.48)
		(width 0.13)
		(layer "In2.Cu")
		(net 101)
	)
	(segment
		(start 225.424558 133.795152)
		(end 225.424557 133.795149)
		(width 0.13)
		(layer "In2.Cu")
		(net 101)
	)
	(segment
		(start 195.5 144.849999)
		(end 195.45 144.9)
		(width 0.1)
		(layer "In2.Cu")
		(net 101)
	)
	(segment
		(start 223.939633 135.280078)
		(end 223.939631 135.280076)
		(width 0.13)
		(layer "In2.Cu")
		(net 101)
	)
	(segment
		(start 210.02 143.499706)
		(end 213.449706 140.07)
		(width 0.13)
		(layer "In2.Cu")
		(net 101)
	)
	(segment
		(start 195.5 144.5)
		(end 195.5 144.849999)
		(width 0.1)
		(layer "In2.Cu")
		(net 101)
	)
	(segment
		(start 248.97 109.774706)
		(end 248.97 106.450294)
		(width 0.13)
		(layer "In2.Cu")
		(net 101)
	)
	(segment
		(start 248.52 113.399706)
		(end 248.52 110.224706)
		(width 0.13)
		(layer "In2.Cu")
		(net 101)
	)
	(segment
		(start 218.417298 137.182373)
		(end 218.417297 137.182373)
		(width 0.13)
		(layer "In2.Cu")
		(net 101)
	)
	(segment
		(start 222.454705 136.765002)
		(end 222.454705 136.765001)
		(width 0.13)
		(layer "In2.Cu")
		(net 101)
	)
	(segment
		(start 220.96978 137.337759)
		(end 219.90225 136.270229)
		(width 0.13)
		(layer "In2.Cu")
		(net 101)
	)
	(segment
		(start 225.424558 132.882981)
		(end 224.357006 131.815429)
		(width 0.13)
		(layer "In2.Cu")
		(net 101)
	)
	(arc
		(start 221.542539 136.765004)
		(mid 221.998623 136.95392)
		(end 222.454707 136.765004)
		(width 0.13)
		(layer "In2.Cu")
		(net 101)
	)
	(arc
		(start 224.51239 133.795152)
		(mid 224.968474 133.984067)
		(end 225.424557 133.795153)
		(width 0.13)
		(layer "In2.Cu")
		(net 101)
	)
	(arc
		(start 224.357006 131.242674)
		(mid 224.643384 131.124052)
		(end 224.929762 131.242674)
		(width 0.13)
		(layer "In2.Cu")
		(net 101)
	)
	(arc
		(start 225.997317 132.310226)
		(mid 226.453401 132.499142)
		(end 226.909485 132.310226)
		(width 0.13)
		(layer "In2.Cu")
		(net 101)
	)
	(arc
		(start 222.454705 136.765001)
		(mid 222.643621 136.308917)
		(end 222.454705 135.852833)
		(width 0.13)
		(layer "In2.Cu")
		(net 101)
	)
	(arc
		(start 219.484853 139.734853)
		(mid 219.673769 139.278769)
		(end 219.484853 138.822685)
		(width 0.13)
		(layer "In2.Cu")
		(net 101)
	)
	(arc
		(start 218.417298 137.755129)
		(mid 218.298676 137.468751)
		(end 218.417298 137.182373)
		(width 0.13)
		(layer "In2.Cu")
		(net 101)
	)
	(arc
		(start 218.417299 137.182372)
		(mid 218.703677 137.06375)
		(end 218.990055 137.182372)
		(width 0.13)
		(layer "In2.Cu")
		(net 101)
	)
	(arc
		(start 221.387176 134.785303)
		(mid 221.268554 134.498925)
		(end 221.387176 134.212547)
		(width 0.13)
		(layer "In2.Cu")
		(net 101)
	)
	(arc
		(start 220.057612 138.24993)
		(mid 220.513696 138.438846)
		(end 220.96978 138.24993)
		(width 0.13)
		(layer "In2.Cu")
		(net 101)
	)
	(arc
		(start 222.872059 132.727576)
		(mid 223.158437 132.608954)
		(end 223.444815 132.727576)
		(width 0.13)
		(layer "In2.Cu")
		(net 101)
	)
	(arc
		(start 223.027465 135.280078)
		(mid 223.483549 135.468994)
		(end 223.939633 135.280078)
		(width 0.13)
		(layer "In2.Cu")
		(net 101)
	)
	(arc
		(start 219.90225 135.697474)
		(mid 220.188628 135.578852)
		(end 220.475006 135.697474)
		(width 0.13)
		(layer "In2.Cu")
		(net 101)
	)
	(arc
		(start 225.424557 133.795149)
		(mid 225.613473 133.339065)
		(end 225.424557 132.882981)
		(width 0.13)
		(layer "In2.Cu")
		(net 101)
	)
	(arc
		(start 219.90225 136.270229)
		(mid 219.783628 135.983851)
		(end 219.90225 135.697473)
		(width 0.13)
		(layer "In2.Cu")
		(net 101)
	)
	(arc
		(start 223.939631 135.280075)
		(mid 224.128547 134.823991)
		(end 223.939631 134.367907)
		(width 0.13)
		(layer "In2.Cu")
		(net 101)
	)
	(arc
		(start 220.969779 138.249927)
		(mid 221.158695 137.793843)
		(end 220.969779 137.337759)
		(width 0.13)
		(layer "In2.Cu")
		(net 101)
	)
	(arc
		(start 222.872058 133.300333)
		(mid 222.753436 133.013955)
		(end 222.872057 132.727576)
		(width 0.13)
		(layer "In2.Cu")
		(net 101)
	)
	(arc
		(start 224.357006 131.815429)
		(mid 224.238384 131.529051)
		(end 224.357006 131.242673)
		(width 0.13)
		(layer "In2.Cu")
		(net 101)
	)
	(arc
		(start 221.387176 134.212548)
		(mid 221.673554 134.093926)
		(end 221.959932 134.212548)
		(width 0.13)
		(layer "In2.Cu")
		(net 101)
	)
	(segment
		(start 233.801 106)
		(end 233.801 107.152)
		(width 0.38)
		(layer "F.Cu")
		(net 102)
	)
	(segment
		(start 199.0005 145.9995)
		(end 199.5 145.5)
		(width 0.256)
		(layer "F.Cu")
		(net 102)
	)
	(via
		(at 233.8 107.152)
		(size 0.45)
		(drill 0.1)
		(layers "F.Cu" "B.Cu")
		(remove_unused_layers yes)
		(keep_end_layers yes)
		(zone_layer_connections)
		(net 102)
	)
	(via
		(at 199.5 145.5)
		(size 0.45)
		(drill 0.1)
		(layers "F.Cu" "B.Cu")
		(remove_unused_layers yes)
		(keep_end_layers yes)
		(zone_layer_connections)
		(net 102)
	)
	(segment
		(start 222.05 121.985)
		(end 221.352364 121.985)
		(width 0.13)
		(layer "In4.Cu")
		(net 102)
	)
	(segment
		(start 207.135 142.045294)
		(end 204.300294 144.88)
		(width 0.13)
		(layer "In4.Cu")
		(net 102)
	)
	(segment
		(start 208.402364 137.085)
		(end 207.135 138.352364)
		(width 0.13)
		(layer "In4.Cu")
		(net 102)
	)
	(segment
		(start 219.620891 123.716477)
		(end 219.62089 123.716479)
		(width 0.13)
		(layer "In4.Cu")
		(net 102)
	)
	(segment
		(start 233.495 106.575294)
		(end 233.249706 106.33)
		(width 0.13)
		(layer "In4.Cu")
		(net 102)
	)
	(segment
		(start 222.59 123.84)
		(end 222.59 122.525)
		(width 0.13)
		(layer "In4.Cu")
		(net 102)
	)
	(segment
		(start 199.5 145.5)
		(end 199.85 145.5)
		(width 0.1)
		(layer "In4.Cu")
		(net 102)
	)
	(segment
		(start 227.552364 121.985)
		(end 227.15 121.985)
		(width 0.13)
		(layer "In4.Cu")
		(net 102)
	)
	(segment
		(start 223.21 122.525)
		(end 223.21 123.84)
		(width 0.13)
		(layer "In4.Cu")
		(net 102)
	)
	(segment
		(start 224.29 123.84)
		(end 224.29 122.525)
		(width 0.13)
		(layer "In4.Cu")
		(net 102)
	)
	(segment
		(start 221.352364 121.985)
		(end 220.893683 122.443683)
		(width 0.13)
		(layer "In4.Cu")
		(net 102)
	)
	(segment
		(start 225.99 123.84)
		(end 225.99 122.525)
		(width 0.13)
		(layer "In4.Cu")
		(net 102)
	)
	(segment
		(start 231.98 109.274706)
		(end 233.63 110.924706)
		(width 0.13)
		(layer "In4.Cu")
		(net 102)
	)
	(segment
		(start 207.135 138.352364)
		(end 207.135 142.045294)
		(width 0.13)
		(layer "In4.Cu")
		(net 102)
	)
	(segment
		(start 219.710288 125.552431)
		(end 219.147129 124.989272)
		(width 0.13)
		(layer "In4.Cu")
		(net 102)
	)
	(segment
		(start 218.348097 124.989272)
		(end 218.348095 124.98927)
		(width 0.13)
		(layer "In4.Cu")
		(net 102)
	)
	(segment
		(start 218.085 125.252364)
		(end 218.085 133.352364)
		(width 0.13)
		(layer "In4.Cu")
		(net 102)
	)
	(segment
		(start 233.249706 106.33)
		(end 232.450294 106.33)
		(width 0.13)
		(layer "In4.Cu")
		(net 102)
	)
	(segment
		(start 233.495 106.847)
		(end 233.495 106.575294)
		(width 0.13)
		(layer "In4.Cu")
		(net 102)
	)
	(segment
		(start 233.63 110.924706)
		(end 233.63 114.257364)
		(width 0.13)
		(layer "In4.Cu")
		(net 102)
	)
	(segment
		(start 228.935 120.602364)
		(end 227.552364 121.985)
		(width 0.13)
		(layer "In4.Cu")
		(net 102)
	)
	(segment
		(start 220.184049 125.552429)
		(end 220.184048 125.552431)
		(width 0.13)
		(layer "In4.Cu")
		(net 102)
	)
	(segment
		(start 221.456836 124.279631)
		(end 221.456837 124.279631)
		(width 0.13)
		(layer "In4.Cu")
		(net 102)
	)
	(segment
		(start 199.9 145.45)
		(end 199.9 145.258578)
		(width 0.1)
		(layer "In4.Cu")
		(net 102)
	)
	(segment
		(start 199.9 145.258578)
		(end 200.258578 144.9)
		(width 0.1)
		(layer "In4.Cu")
		(net 102)
	)
	(segment
		(start 228.935 118.952364)
		(end 228.935 120.602364)
		(width 0.13)
		(layer "In4.Cu")
		(net 102)
	)
	(segment
		(start 233.63 114.257364)
		(end 228.935 118.952364)
		(width 0.13)
		(layer "In4.Cu")
		(net 102)
	)
	(segment
		(start 226.61 122.525)
		(end 226.61 123.84)
		(width 0.13)
		(layer "In4.Cu")
		(net 102)
	)
	(segment
		(start 204.300294 144.88)
		(end 201.7 144.88)
		(width 0.13)
		(layer "In4.Cu")
		(net 102)
	)
	(segment
		(start 218.085 133.352364)
		(end 214.352364 137.085)
		(width 0.13)
		(layer "In4.Cu")
		(net 102)
	)
	(segment
		(start 232.450294 106.33)
		(end 231.98 106.800294)
		(width 0.13)
		(layer "In4.Cu")
		(net 102)
	)
	(segment
		(start 199.85 145.5)
		(end 199.9 145.45)
		(width 0.1)
		(layer "In4.Cu")
		(net 102)
	)
	(segment
		(start 214.352364 137.085)
		(end 208.402364 137.085)
		(width 0.13)
		(layer "In4.Cu")
		(net 102)
	)
	(segment
		(start 218.348095 124.98927)
		(end 218.085 125.252364)
		(width 0.13)
		(layer "In4.Cu")
		(net 102)
	)
	(segment
		(start 201.68 144.9)
		(end 201.7 144.88)
		(width 0.1)
		(layer "In4.Cu")
		(net 102)
	)
	(segment
		(start 224.91 122.525)
		(end 224.91 123.84)
		(width 0.13)
		(layer "In4.Cu")
		(net 102)
	)
	(segment
		(start 233.8 107.152)
		(end 233.495 106.847)
		(width 0.13)
		(layer "In4.Cu")
		(net 102)
	)
	(segment
		(start 219.62089 123.716479)
		(end 219.620889 123.716477)
		(width 0.13)
		(layer "In4.Cu")
		(net 102)
	)
	(segment
		(start 219.620889 124.515509)
		(end 220.184049 125.078669)
		(width 0.13)
		(layer "In4.Cu")
		(net 102)
	)
	(segment
		(start 220.983077 124.279631)
		(end 220.419924 123.716478)
		(width 0.13)
		(layer "In4.Cu")
		(net 102)
	)
	(segment
		(start 231.98 106.800294)
		(end 231.98 109.274706)
		(width 0.13)
		(layer "In4.Cu")
		(net 102)
	)
	(segment
		(start 220.893683 123.242715)
		(end 221.456837 123.805869)
		(width 0.13)
		(layer "In4.Cu")
		(net 102)
	)
	(segment
		(start 200.258578 144.9)
		(end 201.68 144.9)
		(width 0.1)
		(layer "In4.Cu")
		(net 102)
	)
	(segment
		(start 221.456838 124.27963)
		(end 221.456836 124.279631)
		(width 0.13)
		(layer "In4.Cu")
		(net 102)
	)
	(arc
		(start 220.893683 122.443683)
		(mid 220.728197 122.8432)
		(end 220.893683 123.242715)
		(width 0.13)
		(layer "In4.Cu")
		(net 102)
	)
	(arc
		(start 222.9 124.15)
		(mid 222.680797 124.059203)
		(end 222.59 123.84)
		(width 0.13)
		(layer "In4.Cu")
		(net 102)
	)
	(arc
		(start 221.456837 123.805869)
		(mid 221.554957 124.042749)
		(end 221.456838 124.27963)
		(width 0.13)
		(layer "In4.Cu")
		(net 102)
	)
	(arc
		(start 220.184048 125.552431)
		(mid 219.947169 125.650549)
		(end 219.710288 125.552431)
		(width 0.13)
		(layer "In4.Cu")
		(net 102)
	)
	(arc
		(start 224.6 124.15)
		(mid 224.380797 124.059203)
		(end 224.29 123.84)
		(width 0.13)
		(layer "In4.Cu")
		(net 102)
	)
	(arc
		(start 222.59 122.525)
		(mid 222.431838 122.143162)
		(end 222.05 121.985)
		(width 0.13)
		(layer "In4.Cu")
		(net 102)
	)
	(arc
		(start 220.184049 125.078669)
		(mid 220.282167 125.31555)
		(end 220.184049 125.552429)
		(width 0.13)
		(layer "In4.Cu")
		(net 102)
	)
	(arc
		(start 227.15 121.985)
		(mid 226.768162 122.143162)
		(end 226.61 122.525)
		(width 0.13)
		(layer "In4.Cu")
		(net 102)
	)
	(arc
		(start 223.75 121.985)
		(mid 223.368162 122.143162)
		(end 223.21 122.525)
		(width 0.13)
		(layer "In4.Cu")
		(net 102)
	)
	(arc
		(start 224.91 123.84)
		(mid 224.819203 124.059203)
		(end 224.6 124.15)
		(width 0.13)
		(layer "In4.Cu")
		(net 102)
	)
	(arc
		(start 219.620889 123.716477)
		(mid 219.455403 124.115994)
		(end 219.620889 124.515509)
		(width 0.13)
		(layer "In4.Cu")
		(net 102)
	)
	(arc
		(start 219.147129 124.989272)
		(mid 218.747614 124.823786)
		(end 218.348097 124.989272)
		(width 0.13)
		(layer "In4.Cu")
		(net 102)
	)
	(arc
		(start 226.3 124.15)
		(mid 226.080797 124.059203)
		(end 225.99 123.84)
		(width 0.13)
		(layer "In4.Cu")
		(net 102)
	)
	(arc
		(start 226.61 123.84)
		(mid 226.519203 124.059203)
		(end 226.3 124.15)
		(width 0.13)
		(layer "In4.Cu")
		(net 102)
	)
	(arc
		(start 220.419924 123.716478)
		(mid 220.020408 123.550992)
		(end 219.620891 123.716477)
		(width 0.13)
		(layer "In4.Cu")
		(net 102)
	)
	(arc
		(start 224.29 122.525)
		(mid 224.131838 122.143162)
		(end 223.75 121.985)
		(width 0.13)
		(layer "In4.Cu")
		(net 102)
	)
	(arc
		(start 221.456837 124.279631)
		(mid 221.219956 124.377751)
		(end 220.983077 124.279631)
		(width 0.13)
		(layer "In4.Cu")
		(net 102)
	)
	(arc
		(start 225.45 121.985)
		(mid 225.068162 122.143162)
		(end 224.91 122.525)
		(width 0.13)
		(layer "In4.Cu")
		(net 102)
	)
	(arc
		(start 223.21 123.84)
		(mid 223.119203 124.059203)
		(end 222.9 124.15)
		(width 0.13)
		(layer "In4.Cu")
		(net 102)
	)
	(arc
		(start 225.99 122.525)
		(mid 225.831838 122.143162)
		(end 225.45 121.985)
		(width 0.13)
		(layer "In4.Cu")
		(net 102)
	)
	(segment
		(start 165.8 106)
		(end 165.8 107.152)
		(width 0.38)
		(layer "F.Cu")
		(net 103)
	)
	(segment
		(start 189.000501 146.9995)
		(end 189.5 146.5)
		(width 0.256)
		(layer "F.Cu")
		(net 103)
	)
	(via
		(at 165.8 107.152)
		(size 0.45)
		(drill 0.1)
		(layers "F.Cu" "B.Cu")
		(remove_unused_layers yes)
		(keep_end_layers yes)
		(zone_layer_connections)
		(net 103)
	)
	(via
		(at 189.5 146.5)
		(size 0.45)
		(drill 0.1)
		(layers "F.Cu" "B.Cu")
		(remove_unused_layers yes)
		(keep_end_layers yes)
		(zone_layer_connections)
		(net 103)
	)
	(segment
		(start 167.264972 119.141271)
		(end 167.264971 119.14127)
		(width 0.148)
		(layer "In6.Cu")
		(net 103)
	)
	(segment
		(start 169.793741 120.218741)
		(end 169.793743 120.218743)
		(width 0.148)
		(layer "In6.Cu")
		(net 103)
	)
	(segment
		(start 188.95 142.35)
		(end 188 143.3)
		(width 0.148)
		(layer "In6.Cu")
		(net 103)
	)
	(segment
		(start 166.663949 117.93917)
		(end 166.788539 117.814579)
		(width 0.148)
		(layer "In6.Cu")
		(net 103)
	)
	(segment
		(start 167.866011 119.14127)
		(end 167.99062 119.01666)
		(width 0.148)
		(layer "In6.Cu")
		(net 103)
	)
	(segment
		(start 168.591662 119.617702)
		(end 168.46703 119.742333)
		(width 0.148)
		(layer "In6.Cu")
		(net 103)
	)
	(segment
		(start 167.866012 119.141269)
		(end 167.866011 119.14127)
		(width 0.148)
		(layer "In6.Cu")
		(net 103)
	)
	(segment
		(start 167.389579 117.814579)
		(end 167.389581 117.814581)
		(width 0.148)
		(layer "In6.Cu")
		(net 103)
	)
	(segment
		(start 176.1 122.15)
		(end 188.95 135)
		(width 0.148)
		(layer "In6.Cu")
		(net 103)
	)
	(segment
		(start 166.187499 117.213541)
		(end 166.1875 117.21354)
		(width 0.148)
		(layer "In6.Cu")
		(net 103)
	)
	(segment
		(start 169.793743 120.819783)
		(end 169.669097 120.944428)
		(width 0.148)
		(layer "In6.Cu")
		(net 103)
	)
	(segment
		(start 165.8 110.975)
		(end 165.8 116.225)
		(width 0.148)
		(layer "In6.Cu")
		(net 103)
	)
	(segment
		(start 167.38958 117.81458)
		(end 167.389579 117.814579)
		(width 0.148)
		(layer "In6.Cu")
		(net 103)
	)
	(segment
		(start 169.06807 120.343373)
		(end 169.192701 120.218741)
		(width 0.148)
		(layer "In6.Cu")
		(net 103)
	)
	(segment
		(start 166.1875 117.21354)
		(end 166.062909 117.33813)
		(width 0.148)
		(layer "In6.Cu")
		(net 103)
	)
	(segment
		(start 166.06291 117.939171)
		(end 166.062909 117.93917)
		(width 0.148)
		(layer "In6.Cu")
		(net 103)
	)
	(segment
		(start 166.66395 117.939169)
		(end 166.663949 117.93917)
		(width 0.148)
		(layer "In6.Cu")
		(net 103)
	)
	(segment
		(start 188 145)
		(end 189.5 146.5)
		(width 0.148)
		(layer "In6.Cu")
		(net 103)
	)
	(segment
		(start 170.995823 121.420822)
		(end 170.995823 121.420823)
		(width 0.148)
		(layer "In6.Cu")
		(net 103)
	)
	(segment
		(start 165.8 107.152)
		(end 165 107.952)
		(width 0.148)
		(layer "In6.Cu")
		(net 103)
	)
	(segment
		(start 165 110.175)
		(end 165.8 110.975)
		(width 0.148)
		(layer "In6.Cu")
		(net 103)
	)
	(segment
		(start 171.725 122.15)
		(end 176.1 122.15)
		(width 0.148)
		(layer "In6.Cu")
		(net 103)
	)
	(segment
		(start 169.669096 121.545469)
		(end 169.669097 121.545469)
		(width 0.148)
		(layer "In6.Cu")
		(net 103)
	)
	(segment
		(start 169.068071 120.343372)
		(end 169.06807 120.343373)
		(width 0.148)
		(layer "In6.Cu")
		(net 103)
	)
	(segment
		(start 168.467031 120.343374)
		(end 168.46703 120.343373)
		(width 0.148)
		(layer "In6.Cu")
		(net 103)
	)
	(segment
		(start 188.95 135)
		(end 188.95 142.35)
		(width 0.148)
		(layer "In6.Cu")
		(net 103)
	)
	(segment
		(start 170.995823 121.420823)
		(end 171.725 122.15)
		(width 0.148)
		(layer "In6.Cu")
		(net 103)
	)
	(segment
		(start 167.389581 118.415621)
		(end 167.264971 118.54023)
		(width 0.148)
		(layer "In6.Cu")
		(net 103)
	)
	(segment
		(start 165 107.952)
		(end 165 110.175)
		(width 0.148)
		(layer "In6.Cu")
		(net 103)
	)
	(segment
		(start 168.59166 119.01666)
		(end 168.591662 119.016662)
		(width 0.148)
		(layer "In6.Cu")
		(net 103)
	)
	(segment
		(start 170.270137 121.545469)
		(end 170.394782 121.420823)
		(width 0.148)
		(layer "In6.Cu")
		(net 103)
	)
	(segment
		(start 169.793742 120.819784)
		(end 169.793743 120.819783)
		(width 0.148)
		(layer "In6.Cu")
		(net 103)
	)
	(segment
		(start 169.793742 120.218742)
		(end 169.793741 120.218741)
		(width 0.148)
		(layer "In6.Cu")
		(net 103)
	)
	(segment
		(start 168.591661 119.617703)
		(end 168.591662 119.617702)
		(width 0.148)
		(layer "In6.Cu")
		(net 103)
	)
	(segment
		(start 188 143.3)
		(end 188 145)
		(width 0.148)
		(layer "In6.Cu")
		(net 103)
	)
	(segment
		(start 168.591661 119.016661)
		(end 168.59166 119.01666)
		(width 0.148)
		(layer "In6.Cu")
		(net 103)
	)
	(segment
		(start 167.38958 118.415622)
		(end 167.389581 118.415621)
		(width 0.148)
		(layer "In6.Cu")
		(net 103)
	)
	(segment
		(start 165.8 116.225)
		(end 166.1875 116.6125)
		(width 0.148)
		(layer "In6.Cu")
		(net 103)
	)
	(segment
		(start 170.270138 121.545468)
		(end 170.270137 121.545469)
		(width 0.148)
		(layer "In6.Cu")
		(net 103)
	)
	(arc
		(start 168.591662 119.016662)
		(mid 168.716141 119.317183)
		(end 168.591661 119.617703)
		(width 0.148)
		(layer "In6.Cu")
		(net 103)
	)
	(arc
		(start 169.793743 120.218743)
		(mid 169.918222 120.519264)
		(end 169.793742 120.819784)
		(width 0.148)
		(layer "In6.Cu")
		(net 103)
	)
	(arc
		(start 168.46703 119.742333)
		(mid 168.342551 120.042854)
		(end 168.467031 120.343374)
		(width 0.148)
		(layer "In6.Cu")
		(net 103)
	)
	(arc
		(start 167.389581 117.814581)
		(mid 167.51406 118.115102)
		(end 167.38958 118.415622)
		(width 0.148)
		(layer "In6.Cu")
		(net 103)
	)
	(arc
		(start 166.788539 117.814579)
		(mid 167.08906 117.6901)
		(end 167.38958 117.81458)
		(width 0.148)
		(layer "In6.Cu")
		(net 103)
	)
	(arc
		(start 166.062909 117.33813)
		(mid 165.93843 117.638651)
		(end 166.06291 117.939171)
		(width 0.148)
		(layer "In6.Cu")
		(net 103)
	)
	(arc
		(start 166.062909 117.93917)
		(mid 166.36343 118.063649)
		(end 166.66395 117.939169)
		(width 0.148)
		(layer "In6.Cu")
		(net 103)
	)
	(arc
		(start 167.99062 119.01666)
		(mid 168.291141 118.892181)
		(end 168.591661 119.016661)
		(width 0.148)
		(layer "In6.Cu")
		(net 103)
	)
	(arc
		(start 169.669097 121.545469)
		(mid 169.969618 121.669948)
		(end 170.270138 121.545468)
		(width 0.148)
		(layer "In6.Cu")
		(net 103)
	)
	(arc
		(start 169.669097 120.944428)
		(mid 169.544617 121.244948)
		(end 169.669096 121.545469)
		(width 0.148)
		(layer "In6.Cu")
		(net 103)
	)
	(arc
		(start 166.1875 116.6125)
		(mid 166.311979 116.913021)
		(end 166.187499 117.213541)
		(width 0.148)
		(layer "In6.Cu")
		(net 103)
	)
	(arc
		(start 170.394782 121.420823)
		(mid 170.695302 121.296343)
		(end 170.995823 121.420822)
		(width 0.148)
		(layer "In6.Cu")
		(net 103)
	)
	(arc
		(start 168.46703 120.343373)
		(mid 168.767551 120.467852)
		(end 169.068071 120.343372)
		(width 0.148)
		(layer "In6.Cu")
		(net 103)
	)
	(arc
		(start 167.264971 118.54023)
		(mid 167.140492 118.840751)
		(end 167.264972 119.141271)
		(width 0.148)
		(layer "In6.Cu")
		(net 103)
	)
	(arc
		(start 167.264971 119.14127)
		(mid 167.565492 119.265749)
		(end 167.866012 119.141269)
		(width 0.148)
		(layer "In6.Cu")
		(net 103)
	)
	(arc
		(start 169.192701 120.218741)
		(mid 169.493222 120.094262)
		(end 169.793742 120.218742)
		(width 0.148)
		(layer "In6.Cu")
		(net 103)
	)
	(segment
		(start 232.95 106)
		(end 232.95 107.152)
		(width 0.38)
		(layer "F.Cu")
		(net 104)
	)
	(segment
		(start 200.0005 145.9995)
		(end 200.5 145.499999)
		(width 0.256)
		(layer "F.Cu")
		(net 104)
	)
	(via
		(at 232.95 107.152)
		(size 0.45)
		(drill 0.1)
		(layers "F.Cu" "B.Cu")
		(remove_unused_layers yes)
		(keep_end_layers yes)
		(zone_layer_connections)
		(net 104)
	)
	(via
		(at 200.5 145.499999)
		(size 0.45)
		(drill 0.1)
		(layers "F.Cu" "B.Cu")
		(remove_unused_layers yes)
		(keep_end_layers yes)
		(zone_layer_connections)
		(net 104)
	)
	(segment
		(start 220.346683 125.715066)
		(end 220.346684 125.715066)
		(width 0.13)
		(layer "In4.Cu")
		(net 104)
	)
	(segment
		(start 233.255 106.847)
		(end 233.255 106.674706)
		(width 0.13)
		(layer "In4.Cu")
		(net 104)
	)
	(segment
		(start 233.87 114.342636)
		(end 229.165 119.047636)
		(width 0.13)
		(layer "In4.Cu")
		(net 104)
	)
	(segment
		(start 218.315 125.347636)
		(end 218.315 133.447636)
		(width 0.13)
		(layer "In4.Cu")
		(net 104)
	)
	(segment
		(start 221.447636 122.215)
		(end 221.056318 122.606318)
		(width 0.13)
		(layer "In4.Cu")
		(net 104)
	)
	(segment
		(start 200.341422 145.1)
		(end 200.1 145.341422)
		(width 0.1)
		(layer "In4.Cu")
		(net 104)
	)
	(segment
		(start 201.125 145.225)
		(end 201.125 145.247982)
		(width 0.1)
		(layer "In4.Cu")
		(net 104)
	)
	(segment
		(start 218.510733 125.151907)
		(end 218.510731 125.151906)
		(width 0.13)
		(layer "In4.Cu")
		(net 104)
	)
	(segment
		(start 232.95 107.152)
		(end 233.255 106.847)
		(width 0.13)
		(layer "In4.Cu")
		(net 104)
	)
	(segment
		(start 233.150294 106.57)
		(end 232.549706 106.57)
		(width 0.13)
		(layer "In4.Cu")
		(net 104)
	)
	(segment
		(start 232.395 107.575)
		(end 232.425 107.575)
		(width 0.13)
		(layer "In4.Cu")
		(net 104)
	)
	(segment
		(start 233.255 106.674706)
		(end 233.150294 106.57)
		(width 0.13)
		(layer "In4.Cu")
		(net 104)
	)
	(segment
		(start 200.1 145.45)
		(end 200.149999 145.499999)
		(width 0.1)
		(layer "In4.Cu")
		(net 104)
	)
	(segment
		(start 226.84 122.525)
		(end 226.84 123.84)
		(width 0.13)
		(layer "In4.Cu")
		(net 104)
	)
	(segment
		(start 224.06 123.84)
		(end 224.06 122.525)
		(width 0.13)
		(layer "In4.Cu")
		(net 104)
	)
	(segment
		(start 207.365 142.154706)
		(end 204.399706 145.12)
		(width 0.13)
		(layer "In4.Cu")
		(net 104)
	)
	(segment
		(start 219.783525 123.879114)
		(end 219.783526 123.879114)
		(width 0.13)
		(layer "In4.Cu")
		(net 104)
	)
	(segment
		(start 218.510731 125.151906)
		(end 218.315 125.347636)
		(width 0.13)
		(layer "In4.Cu")
		(net 104)
	)
	(segment
		(start 214.447636 137.315)
		(end 208.497636 137.315)
		(width 0.13)
		(layer "In4.Cu")
		(net 104)
	)
	(segment
		(start 201.7 145.12)
		(end 201.68 145.1)
		(width 0.1)
		(layer "In4.Cu")
		(net 104)
	)
	(segment
		(start 200.149999 145.499999)
		(end 200.5 145.499999)
		(width 0.1)
		(layer "In4.Cu")
		(net 104)
	)
	(segment
		(start 207.365 138.447636)
		(end 207.365 142.154706)
		(width 0.13)
		(layer "In4.Cu")
		(net 104)
	)
	(segment
		(start 232.549706 106.57)
		(end 232.22 106.899706)
		(width 0.13)
		(layer "In4.Cu")
		(net 104)
	)
	(segment
		(start 232.425 107.975)
		(end 232.395 107.975)
		(width 0.13)
		(layer "In4.Cu")
		(net 104)
	)
	(segment
		(start 219.783523 124.352874)
		(end 220.346683 124.916034)
		(width 0.13)
		(layer "In4.Cu")
		(net 104)
	)
	(segment
		(start 229.165 120.697636)
		(end 227.647636 122.215)
		(width 0.13)
		(layer "In4.Cu")
		(net 104)
	)
	(segment
		(start 201.68 145.1)
		(end 201.233796 145.1)
		(width 0.1)
		(layer "In4.Cu")
		(net 104)
	)
	(segment
		(start 221.619472 124.442266)
		(end 221.619471 124.442268)
		(width 0.13)
		(layer "In4.Cu")
		(net 104)
	)
	(segment
		(start 229.165 119.047636)
		(end 229.165 120.697636)
		(width 0.13)
		(layer "In4.Cu")
		(net 104)
	)
	(segment
		(start 221.056317 123.08008)
		(end 221.619471 123.643234)
		(width 0.13)
		(layer "In4.Cu")
		(net 104)
	)
	(segment
		(start 219.783524 124.352874)
		(end 219.783523 124.352874)
		(width 0.13)
		(layer "In4.Cu")
		(net 104)
	)
	(segment
		(start 204.399706 145.12)
		(end 201.7 145.12)
		(width 0.13)
		(layer "In4.Cu")
		(net 104)
	)
	(segment
		(start 225.14 122.525)
		(end 225.14 123.84)
		(width 0.13)
		(layer "In4.Cu")
		(net 104)
	)
	(segment
		(start 232.22 108.15)
		(end 232.22 109.175294)
		(width 0.13)
		(layer "In4.Cu")
		(net 104)
	)
	(segment
		(start 221.056318 123.08008)
		(end 221.056317 123.08008)
		(width 0.13)
		(layer "In4.Cu")
		(net 104)
	)
	(segment
		(start 200.664316 145.1)
		(end 200.341422 145.1)
		(width 0.1)
		(layer "In4.Cu")
		(net 104)
	)
	(segment
		(start 201.125 145.225)
		(end 201.125 145.208796)
		(width 0.1)
		(layer "In4.Cu")
		(net 104)
	)
	(segment
		(start 232.22 106.899706)
		(end 232.22 107.4)
		(width 0.13)
		(layer "In4.Cu")
		(net 104)
	)
	(segment
		(start 200.75 145.1)
		(end 200.664316 145.1)
		(width 0.1)
		(layer "In4.Cu")
		(net 104)
	)
	(segment
		(start 223.44 122.525)
		(end 223.44 123.84)
		(width 0.13)
		(layer "In4.Cu")
		(net 104)
	)
	(segment
		(start 200.1 145.341422)
		(end 200.1 145.45)
		(width 0.1)
		(layer "In4.Cu")
		(net 104)
	)
	(segment
		(start 225.76 123.84)
		(end 225.76 122.525)
		(width 0.13)
		(layer "In4.Cu")
		(net 104)
	)
	(segment
		(start 220.820439 124.442268)
		(end 220.257286 123.879115)
		(width 0.13)
		(layer "In4.Cu")
		(net 104)
	)
	(segment
		(start 222.05 122.215)
		(end 221.447636 122.215)
		(width 0.13)
		(layer "In4.Cu")
		(net 104)
	)
	(segment
		(start 219.783526 123.879114)
		(end 219.783524 123.879112)
		(width 0.13)
		(layer "In4.Cu")
		(net 104)
	)
	(segment
		(start 219.547652 125.715066)
		(end 218.984493 125.151907)
		(width 0.13)
		(layer "In4.Cu")
		(net 104)
	)
	(segment
		(start 233.87 110.825294)
		(end 233.87 114.342636)
		(width 0.13)
		(layer "In4.Cu")
		(net 104)
	)
	(segment
		(start 208.497636 137.315)
		(end 207.365 138.447636)
		(width 0.13)
		(layer "In4.Cu")
		(net 104)
	)
	(segment
		(start 232.6 107.75)
		(end 232.6 107.8)
		(width 0.13)
		(layer "In4.Cu")
		(net 104)
	)
	(segment
		(start 232.22 109.175294)
		(end 233.87 110.825294)
		(width 0.13)
		(layer "In4.Cu")
		(net 104)
	)
	(segment
		(start 227.647636 122.215)
		(end 227.15 122.215)
		(width 0.13)
		(layer "In4.Cu")
		(net 104)
	)
	(segment
		(start 221.619472 124.442267)
		(end 221.619472 124.442266)
		(width 0.13)
		(layer "In4.Cu")
		(net 104)
	)
	(segment
		(start 200.875 145.247982)
		(end 200.875 145.225)
		(width 0.1)
		(layer "In4.Cu")
		(net 104)
	)
	(segment
		(start 218.315 133.447636)
		(end 214.447636 137.315)
		(width 0.13)
		(layer "In4.Cu")
		(net 104)
	)
	(segment
		(start 222.36 123.84)
		(end 222.36 122.525)
		(width 0.13)
		(layer "In4.Cu")
		(net 104)
	)
	(arc
		(start 219.783524 123.879112)
		(mid 219.685405 124.115993)
		(end 219.783524 124.352874)
		(width 0.13)
		(layer "In4.Cu")
		(net 104)
	)
	(arc
		(start 224.06 122.525)
		(mid 223.969203 122.305797)
		(end 223.75 122.215)
		(width 0.13)
		(layer "In4.Cu")
		(net 104)
	)
	(arc
		(start 220.257286 123.879115)
		(mid 220.020406 123.780995)
		(end 219.783525 123.879114)
		(width 0.13)
		(layer "In4.Cu")
		(net 104)
	)
	(arc
		(start 222.36 122.525)
		(mid 222.269203 122.305797)
		(end 222.05 122.215)
		(width 0.13)
		(layer "In4.Cu")
		(net 104)
	)
	(arc
		(start 225.14 123.84)
		(mid 224.981838 124.221838)
		(end 224.6 124.38)
		(width 0.13)
		(layer "In4.Cu")
		(net 104)
	)
	(arc
		(start 232.395 107.975)
		(mid 232.271256 108.026256)
		(end 232.22 108.15)
		(width 0.13)
		(layer "In4.Cu")
		(net 104)
	)
	(arc
		(start 225.76 122.525)
		(mid 225.669203 122.305797)
		(end 225.45 122.215)
		(width 0.13)
		(layer "In4.Cu")
		(net 104)
	)
	(arc
		(start 220.346683 124.916034)
		(mid 220.512169 125.315549)
		(end 220.346683 125.715066)
		(width 0.13)
		(layer "In4.Cu")
		(net 104)
	)
	(arc
		(start 218.984493 125.151907)
		(mid 218.747612 125.053789)
		(end 218.510733 125.151907)
		(width 0.13)
		(layer "In4.Cu")
		(net 104)
	)
	(arc
		(start 223.75 122.215)
		(mid 223.530797 122.305797)
		(end 223.44 122.525)
		(width 0.13)
		(layer "In4.Cu")
		(net 104)
	)
	(arc
		(start 221.619471 124.442268)
		(mid 221.219956 124.607752)
		(end 220.820439 124.442268)
		(width 0.13)
		(layer "In4.Cu")
		(net 104)
	)
	(arc
		(start 232.425 107.575)
		(mid 232.548744 107.626256)
		(end 232.6 107.75)
		(width 0.13)
		(layer "In4.Cu")
		(net 104)
	)
	(arc
		(start 232.6 107.8)
		(mid 232.548744 107.923744)
		(end 232.425 107.975)
		(width 0.13)
		(layer "In4.Cu")
		(net 104)
	)
	(arc
		(start 200.875 145.225)
		(mid 200.838388 145.136612)
		(end 200.75 145.1)
		(width 0.1)
		(layer "In4.Cu")
		(net 104)
	)
	(arc
		(start 222.9 124.38)
		(mid 222.518162 124.221838)
		(end 222.36 123.84)
		(width 0.13)
		(layer "In4.Cu")
		(net 104)
	)
	(arc
		(start 223.44 123.84)
		(mid 223.281838 124.221838)
		(end 222.9 124.38)
		(width 0.13)
		(layer "In4.Cu")
		(net 104)
	)
	(arc
		(start 201.125 145.247982)
		(mid 201.088388 145.33637)
		(end 201 145.372982)
		(width 0.1)
		(layer "In4.Cu")
		(net 104)
	)
	(arc
		(start 221.056318 122.606318)
		(mid 220.958199 122.843199)
		(end 221.056318 123.08008)
		(width 0.13)
		(layer "In4.Cu")
		(net 104)
	)
	(arc
		(start 226.3 124.38)
		(mid 225.918162 124.221838)
		(end 225.76 123.84)
		(width 0.13)
		(layer "In4.Cu")
		(net 104)
	)
	(arc
		(start 232.22 107.4)
		(mid 232.271256 107.523744)
		(end 232.395 107.575)
		(width 0.13)
		(layer "In4.Cu")
		(net 104)
	)
	(arc
		(start 221.619471 123.643234)
		(mid 221.784957 124.04275)
		(end 221.619472 124.442267)
		(width 0.13)
		(layer "In4.Cu")
		(net 104)
	)
	(arc
		(start 201 145.372982)
		(mid 200.911612 145.33637)
		(end 200.875 145.247982)
		(width 0.1)
		(layer "In4.Cu")
		(net 104)
	)
	(arc
		(start 224.6 124.38)
		(mid 224.218162 124.221838)
		(end 224.06 123.84)
		(width 0.13)
		(layer "In4.Cu")
		(net 104)
	)
	(arc
		(start 225.45 122.215)
		(mid 225.230797 122.305797)
		(end 225.14 122.525)
		(width 0.13)
		(layer "In4.Cu")
		(net 104)
	)
	(arc
		(start 201.233796 145.1)
		(mid 201.156866 145.131866)
		(end 201.125 145.208796)
		(width 0.1)
		(layer "In4.Cu")
		(net 104)
	)
	(arc
		(start 227.15 122.215)
		(mid 226.930797 122.305797)
		(end 226.84 122.525)
		(width 0.13)
		(layer "In4.Cu")
		(net 104)
	)
	(arc
		(start 220.346684 125.715066)
		(mid 219.947167 125.880552)
		(end 219.547652 125.715066)
		(width 0.13)
		(layer "In4.Cu")
		(net 104)
	)
	(arc
		(start 226.84 123.84)
		(mid 226.681838 124.221838)
		(end 226.3 124.38)
		(width 0.13)
		(layer "In4.Cu")
		(net 104)
	)
	(segment
		(start 164.1 106)
		(end 164.1 107.152)
		(width 0.38)
		(layer "F.Cu")
		(net 105)
	)
	(segment
		(start 188 145)
		(end 187.5 144.5)
		(width 0.256)
		(layer "F.Cu")
		(net 105)
	)
	(via
		(at 187.5 144.5)
		(size 0.45)
		(drill 0.1)
		(layers "F.Cu" "B.Cu")
		(remove_unused_layers yes)
		(keep_end_layers yes)
		(zone_layer_connections)
		(net 105)
	)
	(via
		(at 164.1 107.152)
		(size 0.45)
		(drill 0.1)
		(layers "F.Cu" "B.Cu")
		(remove_unused_layers yes)
		(keep_end_layers yes)
		(zone_layer_connections)
		(net 105)
	)
	(segment
		(start 164.1 110.85)
		(end 164.1 112.575)
		(width 0.148)
		(layer "In6.Cu")
		(net 105)
	)
	(segment
		(start 172.490253 125.543197)
		(end 172.030634 126.002817)
		(width 0.148)
		(layer "In6.Cu")
		(net 105)
	)
	(segment
		(start 187.507498 142.692502)
		(end 187 143.2)
		(width 0.148)
		(layer "In6.Cu")
		(net 105)
	)
	(segment
		(start 164.1 112.575)
		(end 163.85 112.825)
		(width 0.148)
		(layer "In6.Cu")
		(net 105)
	)
	(segment
		(start 187 143.2)
		(end 187 144)
		(width 0.148)
		(layer "In6.Cu")
		(net 105)
	)
	(segment
		(start 182.116598 132.7)
		(end 184.825 132.7)
		(width 0.148)
		(layer "In6.Cu")
		(net 105)
	)
	(segment
		(start 172.030634 126.780635)
		(end 172.030633 126.780633)
		(width 0.148)
		(layer "In6.Cu")
		(net 105)
	)
	(segment
		(start 164.1 107.152)
		(end 163.425 107.827)
		(width 0.148)
		(layer "In6.Cu")
		(net 105)
	)
	(segment
		(start 171.252818 125.225001)
		(end 171.712436 124.76538)
		(width 0.148)
		(layer "In6.Cu")
		(net 105)
	)
	(segment
		(start 163.425 110.175)
		(end 164.1 110.85)
		(width 0.148)
		(layer "In6.Cu")
		(net 105)
	)
	(segment
		(start 177.95 132.7)
		(end 179.125 132.7)
		(width 0.148)
		(layer "In6.Cu")
		(net 105)
	)
	(segment
		(start 188.05 138.9)
		(end 188.05 141.625)
		(width 0.148)
		(layer "In6.Cu")
		(net 105)
	)
	(segment
		(start 172.030633 126.780633)
		(end 177.95 132.7)
		(width 0.148)
		(layer "In6.Cu")
		(net 105)
	)
	(segment
		(start 187.507498 142.167502)
		(end 187.507498 142.692502)
		(width 0.148)
		(layer "In6.Cu")
		(net 105)
	)
	(segment
		(start 172.490254 124.76538)
		(end 172.490254 124.765381)
		(width 0.148)
		(layer "In6.Cu")
		(net 105)
	)
	(segment
		(start 163.85 119.475)
		(end 168.775 124.4)
		(width 0.148)
		(layer "In6.Cu")
		(net 105)
	)
	(segment
		(start 187 144)
		(end 187.5 144.5)
		(width 0.148)
		(layer "In6.Cu")
		(net 105)
	)
	(segment
		(start 179.7 132.125)
		(end 179.7 131.366124)
		(width 0.148)
		(layer "In6.Cu")
		(net 105)
	)
	(segment
		(start 168.775 124.4)
		(end 169.65 124.4)
		(width 0.148)
		(layer "In6.Cu")
		(net 105)
	)
	(segment
		(start 184.825 132.7)
		(end 187.7 135.575)
		(width 0.148)
		(layer "In6.Cu")
		(net 105)
	)
	(segment
		(start 163.425 107.827)
		(end 163.425 110.175)
		(width 0.148)
		(layer "In6.Cu")
		(net 105)
	)
	(segment
		(start 181.425 132.7)
		(end 182.116598 132.7)
		(width 0.148)
		(layer "In6.Cu")
		(net 105)
	)
	(segment
		(start 163.85 112.825)
		(end 163.85 119.475)
		(width 0.148)
		(layer "In6.Cu")
		(net 105)
	)
	(segment
		(start 188.05 141.625)
		(end 187.507498 142.167502)
		(width 0.148)
		(layer "In6.Cu")
		(net 105)
	)
	(segment
		(start 169.65 124.4)
		(end 170.475 125.225)
		(width 0.148)
		(layer "In6.Cu")
		(net 105)
	)
	(segment
		(start 187.7 135.575)
		(end 187.7 138.55)
		(width 0.148)
		(layer "In6.Cu")
		(net 105)
	)
	(segment
		(start 172.490253 125.543198)
		(end 172.490253 125.543197)
		(width 0.148)
		(layer "In6.Cu")
		(net 105)
	)
	(segment
		(start 180.85 131.366124)
		(end 180.85 132.125)
		(width 0.148)
		(layer "In6.Cu")
		(net 105)
	)
	(segment
		(start 171.252817 125.224999)
		(end 171.252818 125.225001)
		(width 0.148)
		(layer "In6.Cu")
		(net 105)
	)
	(segment
		(start 187.7 138.55)
		(end 188.05 138.9)
		(width 0.148)
		(layer "In6.Cu")
		(net 105)
	)
	(arc
		(start 172.490254 124.765381)
		(mid 172.651345 125.15429)
		(end 172.490253 125.543198)
		(width 0.148)
		(layer "In6.Cu")
		(net 105)
	)
	(arc
		(start 179.7 131.366124)
		(mid 179.868414 130.959538)
		(end 180.275 130.791124)
		(width 0.148)
		(layer "In6.Cu")
		(net 105)
	)
	(arc
		(start 179.125 132.7)
		(mid 179.531586 132.531586)
		(end 179.7 132.125)
		(width 0.148)
		(layer "In6.Cu")
		(net 105)
	)
	(arc
		(start 171.712436 124.76538)
		(mid 172.101345 124.604289)
		(end 172.490254 124.76538)
		(width 0.148)
		(layer "In6.Cu")
		(net 105)
	)
	(arc
		(start 180.85 132.125)
		(mid 181.018414 132.531586)
		(end 181.425 132.7)
		(width 0.148)
		(layer "In6.Cu")
		(net 105)
	)
	(arc
		(start 170.475 125.225)
		(mid 170.863909 125.386091)
		(end 171.252817 125.224999)
		(width 0.148)
		(layer "In6.Cu")
		(net 105)
	)
	(arc
		(start 180.275 130.791124)
		(mid 180.681586 130.959538)
		(end 180.85 131.366124)
		(width 0.148)
		(layer "In6.Cu")
		(net 105)
	)
	(arc
		(start 172.030634 126.002817)
		(mid 171.869543 126.391726)
		(end 172.030634 126.780635)
		(width 0.148)
		(layer "In6.Cu")
		(net 105)
	)
	(segment
		(start 162.4 106)
		(end 162.4 107.152)
		(width 0.38)
		(layer "F.Cu")
		(net 106)
	)
	(segment
		(start 186.9995 144.9995)
		(end 186.5 144.5)
		(width 0.256)
		(layer "F.Cu")
		(net 106)
	)
	(via
		(at 186.5 144.5)
		(size 0.45)
		(drill 0.1)
		(layers "F.Cu" "B.Cu")
		(remove_unused_layers yes)
		(keep_end_layers yes)
		(zone_layer_connections)
		(net 106)
	)
	(via
		(at 162.4 107.152)
		(size 0.45)
		(drill 0.1)
		(layers "F.Cu" "B.Cu")
		(remove_unused_layers yes)
		(keep_end_layers yes)
		(zone_layer_connections)
		(net 106)
	)
	(segment
		(start 186.975 143.35)
		(end 186.975 144.025)
		(width 0.148)
		(layer "In2.Cu")
		(net 106)
	)
	(segment
		(start 164.929484 121.829485)
		(end 164.95 121.829485)
		(width 0.148)
		(layer "In2.Cu")
		(net 106)
	)
	(segment
		(start 167.314742 121.364743)
		(end 167.314742 121.364742)
		(width 0.148)
		(layer "In2.Cu")
		(net 106)
	)
	(segment
		(start 162.564742 121.364742)
		(end 162.564742 121.364743)
		(width 0.148)
		(layer "In2.Cu")
		(net 106)
	)
	(segment
		(start 157 106.5)
		(end 157 107.8)
		(width 0.148)
		(layer "In2.Cu")
		(net 106)
	)
	(segment
		(start 169.679448 120.9)
		(end 169.7 120.9)
		(width 0.148)
		(layer "In2.Cu")
		(net 106)
	)
	(segment
		(start 188.3875 138.7125)
		(end 188.5 138.825)
		(width 0.148)
		(layer "In2.Cu")
		(net 106)
	)
	(segment
		(start 174.15 120.9)
		(end 188.3875 135.1375)
		(width 0.148)
		(layer "In2.Cu")
		(net 106)
	)
	(segment
		(start 173.014775 121.364776)
		(end 173.014775 121.364775)
		(width 0.148)
		(layer "In2.Cu")
		(net 106)
	)
	(segment
		(start 188.3875 135.1375)
		(end 188.3875 138.7125)
		(width 0.148)
		(layer "In2.Cu")
		(net 106)
	)
	(segment
		(start 163.514742 121.364743)
		(end 163.514742 121.364742)
		(width 0.148)
		(layer "In2.Cu")
		(net 106)
	)
	(segment
		(start 170.164742 121.364742)
		(end 170.164742 121.364743)
		(width 0.148)
		(layer "In2.Cu")
		(net 106)
	)
	(segment
		(start 172.064775 121.364775)
		(end 172.064775 121.364776)
		(width 0.148)
		(layer "In2.Cu")
		(net 106)
	)
	(segment
		(start 165.879484 120.9)
		(end 165.9 120.9)
		(width 0.148)
		(layer "In2.Cu")
		(net 106)
	)
	(segment
		(start 186.975 144.025)
		(end 186.5 144.5)
		(width 0.148)
		(layer "In2.Cu")
		(net 106)
	)
	(segment
		(start 188.5 138.825)
		(end 188.5 142.025)
		(width 0.148)
		(layer "In2.Cu")
		(net 106)
	)
	(segment
		(start 155.975 110.45)
		(end 156.175 110.65)
		(width 0.148)
		(layer "In2.Cu")
		(net 106)
	)
	(segment
		(start 166.364742 121.364742)
		(end 166.364742 121.364743)
		(width 0.148)
		(layer "In2.Cu")
		(net 106)
	)
	(segment
		(start 170.629484 121.829485)
		(end 170.65 121.829485)
		(width 0.148)
		(layer "In2.Cu")
		(net 106)
	)
	(segment
		(start 165.414742 121.364743)
		(end 165.414742 121.364742)
		(width 0.148)
		(layer "In2.Cu")
		(net 106)
	)
	(segment
		(start 168.729448 121.829449)
		(end 168.75 121.829449)
		(width 0.148)
		(layer "In2.Cu")
		(net 106)
	)
	(segment
		(start 166.829484 121.829485)
		(end 166.85 121.829485)
		(width 0.148)
		(layer "In2.Cu")
		(net 106)
	)
	(segment
		(start 173.47955 120.9)
		(end 174.15 120.9)
		(width 0.148)
		(layer "In2.Cu")
		(net 106)
	)
	(segment
		(start 163.029484 121.829485)
		(end 163.05 121.829485)
		(width 0.148)
		(layer "In2.Cu")
		(net 106)
	)
	(segment
		(start 187.325 143)
		(end 186.975 143.35)
		(width 0.148)
		(layer "In2.Cu")
		(net 106)
	)
	(segment
		(start 155.975 108.825)
		(end 155.975 110.45)
		(width 0.148)
		(layer "In2.Cu")
		(net 106)
	)
	(segment
		(start 157.75 105.75)
		(end 157 106.5)
		(width 0.148)
		(layer "In2.Cu")
		(net 106)
	)
	(segment
		(start 167.779484 120.9)
		(end 167.8 120.9)
		(width 0.148)
		(layer "In2.Cu")
		(net 106)
	)
	(segment
		(start 171.114742 121.364743)
		(end 171.114742 121.364742)
		(width 0.148)
		(layer "In2.Cu")
		(net 106)
	)
	(segment
		(start 188.5 142.025)
		(end 187.525 143)
		(width 0.148)
		(layer "In2.Cu")
		(net 106)
	)
	(segment
		(start 161.45 105.75)
		(end 157.75 105.75)
		(width 0.148)
		(layer "In2.Cu")
		(net 106)
	)
	(segment
		(start 169.214724 121.364725)
		(end 169.214724 121.364724)
		(width 0.148)
		(layer "In2.Cu")
		(net 106)
	)
	(segment
		(start 171.579484 120.9)
		(end 171.6 120.9)
		(width 0.148)
		(layer "In2.Cu")
		(net 106)
	)
	(segment
		(start 156.175 115.675)
		(end 161.4 120.9)
		(width 0.148)
		(layer "In2.Cu")
		(net 106)
	)
	(segment
		(start 162.4 107.152)
		(end 162.4 106.7)
		(width 0.148)
		(layer "In2.Cu")
		(net 106)
	)
	(segment
		(start 168.264724 121.364724)
		(end 168.264724 121.364725)
		(width 0.148)
		(layer "In2.Cu")
		(net 106)
	)
	(segment
		(start 157 107.8)
		(end 155.975 108.825)
		(width 0.148)
		(layer "In2.Cu")
		(net 106)
	)
	(segment
		(start 164.464742 121.364742)
		(end 164.464742 121.364743)
		(width 0.148)
		(layer "In2.Cu")
		(net 106)
	)
	(segment
		(start 156.175 110.65)
		(end 156.175 115.675)
		(width 0.148)
		(layer "In2.Cu")
		(net 106)
	)
	(segment
		(start 172.52955 121.829551)
		(end 172.55 121.829551)
		(width 0.148)
		(layer "In2.Cu")
		(net 106)
	)
	(segment
		(start 187.525 143)
		(end 187.325 143)
		(width 0.148)
		(layer "In2.Cu")
		(net 106)
	)
	(segment
		(start 162.4 106.7)
		(end 161.45 105.75)
		(width 0.148)
		(layer "In2.Cu")
		(net 106)
	)
	(segment
		(start 161.4 120.9)
		(end 162.1 120.9)
		(width 0.148)
		(layer "In2.Cu")
		(net 106)
	)
	(segment
		(start 163.979484 120.9)
		(end 164 120.9)
		(width 0.148)
		(layer "In2.Cu")
		(net 106)
	)
	(arc
		(start 165.9 120.9)
		(mid 166.228622 121.03612)
		(end 166.364742 121.364742)
		(width 0.148)
		(layer "In2.Cu")
		(net 106)
	)
	(arc
		(start 166.85 121.829485)
		(mid 167.178622 121.693365)
		(end 167.314742 121.364743)
		(width 0.148)
		(layer "In2.Cu")
		(net 106)
	)
	(arc
		(start 173.014775 121.364775)
		(mid 173.150904 121.036129)
		(end 173.47955 120.9)
		(width 0.148)
		(layer "In2.Cu")
		(net 106)
	)
	(arc
		(start 164.95 121.829485)
		(mid 165.278622 121.693365)
		(end 165.414742 121.364743)
		(width 0.148)
		(layer "In2.Cu")
		(net 106)
	)
	(arc
		(start 172.55 121.829551)
		(mid 172.878646 121.693422)
		(end 173.014775 121.364776)
		(width 0.148)
		(layer "In2.Cu")
		(net 106)
	)
	(arc
		(start 167.8 120.9)
		(mid 168.128609 121.036115)
		(end 168.264724 121.364724)
		(width 0.148)
		(layer "In2.Cu")
		(net 106)
	)
	(arc
		(start 169.214724 121.364724)
		(mid 169.350839 121.036115)
		(end 169.679448 120.9)
		(width 0.148)
		(layer "In2.Cu")
		(net 106)
	)
	(arc
		(start 165.414742 121.364742)
		(mid 165.550862 121.03612)
		(end 165.879484 120.9)
		(width 0.148)
		(layer "In2.Cu")
		(net 106)
	)
	(arc
		(start 162.564742 121.364743)
		(mid 162.700862 121.693365)
		(end 163.029484 121.829485)
		(width 0.148)
		(layer "In2.Cu")
		(net 106)
	)
	(arc
		(start 166.364742 121.364743)
		(mid 166.500862 121.693365)
		(end 166.829484 121.829485)
		(width 0.148)
		(layer "In2.Cu")
		(net 106)
	)
	(arc
		(start 163.514742 121.364742)
		(mid 163.650862 121.03612)
		(end 163.979484 120.9)
		(width 0.148)
		(layer "In2.Cu")
		(net 106)
	)
	(arc
		(start 168.75 121.829449)
		(mid 169.078609 121.693334)
		(end 169.214724 121.364725)
		(width 0.148)
		(layer "In2.Cu")
		(net 106)
	)
	(arc
		(start 171.114742 121.364742)
		(mid 171.250862 121.03612)
		(end 171.579484 120.9)
		(width 0.148)
		(layer "In2.Cu")
		(net 106)
	)
	(arc
		(start 170.164742 121.364743)
		(mid 170.300862 121.693365)
		(end 170.629484 121.829485)
		(width 0.148)
		(layer "In2.Cu")
		(net 106)
	)
	(arc
		(start 164 120.9)
		(mid 164.328622 121.03612)
		(end 164.464742 121.364742)
		(width 0.148)
		(layer "In2.Cu")
		(net 106)
	)
	(arc
		(start 167.314742 121.364742)
		(mid 167.450862 121.03612)
		(end 167.779484 120.9)
		(width 0.148)
		(layer "In2.Cu")
		(net 106)
	)
	(arc
		(start 163.05 121.829485)
		(mid 163.378622 121.693365)
		(end 163.514742 121.364743)
		(width 0.148)
		(layer "In2.Cu")
		(net 106)
	)
	(arc
		(start 170.65 121.829485)
		(mid 170.978622 121.693365)
		(end 171.114742 121.364743)
		(width 0.148)
		(layer "In2.Cu")
		(net 106)
	)
	(arc
		(start 172.064775 121.364776)
		(mid 172.200904 121.693422)
		(end 172.52955 121.829551)
		(width 0.148)
		(layer "In2.Cu")
		(net 106)
	)
	(arc
		(start 171.6 120.9)
		(mid 171.928646 121.036129)
		(end 172.064775 121.364775)
		(width 0.148)
		(layer "In2.Cu")
		(net 106)
	)
	(arc
		(start 169.7 120.9)
		(mid 170.028622 121.03612)
		(end 170.164742 121.364742)
		(width 0.148)
		(layer "In2.Cu")
		(net 106)
	)
	(arc
		(start 164.464742 121.364743)
		(mid 164.600862 121.693365)
		(end 164.929484 121.829485)
		(width 0.148)
		(layer "In2.Cu")
		(net 106)
	)
	(arc
		(start 162.1 120.9)
		(mid 162.428622 121.03612)
		(end 162.564742 121.364742)
		(width 0.148)
		(layer "In2.Cu")
		(net 106)
	)
	(arc
		(start 168.264724 121.364725)
		(mid 168.400839 121.693334)
		(end 168.729448 121.829449)
		(width 0.148)
		(layer "In2.Cu")
		(net 106)
	)
	(segment
		(start 186.9995 145.9995)
		(end 186.5 145.5)
		(width 0.256)
		(layer "F.Cu")
		(net 107)
	)
	(segment
		(start 160.7 106)
		(end 160.7 107.152)
		(width 0.38)
		(layer "F.Cu")
		(net 107)
	)
	(via
		(at 160.7 107.152)
		(size 0.45)
		(drill 0.1)
		(layers "F.Cu" "B.Cu")
		(remove_unused_layers yes)
		(keep_end_layers yes)
		(zone_layer_connections)
		(net 107)
	)
	(via
		(at 186.5 145.5)
		(size 0.45)
		(drill 0.1)
		(layers "F.Cu" "B.Cu")
		(remove_unused_layers yes)
		(keep_end_layers yes)
		(zone_layer_connections)
		(net 107)
	)
	(segment
		(start 160.7 106.7)
		(end 160.5 106.5)
		(width 0.148)
		(layer "In2.Cu")
		(net 107)
	)
	(segment
		(start 156.7 110.675)
		(end 156.7 114.7)
		(width 0.148)
		(layer "In2.Cu")
		(net 107)
	)
	(segment
		(start 177.804833 122.695213)
		(end 177.804834 122.695215)
		(width 0.148)
		(layer "In2.Cu")
		(net 107)
	)
	(segment
		(start 178.787956 122.631331)
		(end 178.264452 123.154832)
		(width 0.148)
		(layer "In2.Cu")
		(net 107)
	)
	(segment
		(start 175.966358 120.856739)
		(end 176.489823 120.333271)
		(width 0.148)
		(layer "In2.Cu")
		(net 107)
	)
	(segment
		(start 176.885596 121.775977)
		(end 177.40908 121.25249)
		(width 0.148)
		(layer "In2.Cu")
		(net 107)
	)
	(segment
		(start 177.868699 121.712109)
		(end 177.868701 121.71211)
		(width 0.148)
		(layer "In2.Cu")
		(net 107)
	)
	(segment
		(start 188.025 144.65)
		(end 187.675 145)
		(width 0.148)
		(layer "In2.Cu")
		(net 107)
	)
	(segment
		(start 178.264451 123.614451)
		(end 178.264452 123.614452)
		(width 0.148)
		(layer "In2.Cu")
		(net 107)
	)
	(segment
		(start 158 106.5)
		(end 157.6 106.9)
		(width 0.148)
		(layer "In2.Cu")
		(net 107)
	)
	(segment
		(start 188.025 143.409728)
		(end 188.025 144.65)
		(width 0.148)
		(layer "In2.Cu")
		(net 107)
	)
	(segment
		(start 161.75 119.75)
		(end 174.4 119.75)
		(width 0.148)
		(layer "In2.Cu")
		(net 107)
	)
	(segment
		(start 176.030189 119.873667)
		(end 175.506738 120.397119)
		(width 0.148)
		(layer "In2.Cu")
		(net 107)
	)
	(segment
		(start 177.804834 122.695215)
		(end 178.328335 122.171711)
		(width 0.148)
		(layer "In2.Cu")
		(net 107)
	)
	(segment
		(start 176.885595 121.775975)
		(end 176.885596 121.775977)
		(width 0.148)
		(layer "In2.Cu")
		(net 107)
	)
	(segment
		(start 175.506737 120.856737)
		(end 175.506738 120.856738)
		(width 0.148)
		(layer "In2.Cu")
		(net 107)
	)
	(segment
		(start 188.95 142.484728)
		(end 188.025 143.409728)
		(width 0.148)
		(layer "In2.Cu")
		(net 107)
	)
	(segment
		(start 157.6 106.9)
		(end 157.6 109.775)
		(width 0.148)
		(layer "In2.Cu")
		(net 107)
	)
	(segment
		(start 177.868701 121.71211)
		(end 177.345214 122.235594)
		(width 0.148)
		(layer "In2.Cu")
		(net 107)
	)
	(segment
		(start 178.264452 123.614452)
		(end 188.95 134.3)
		(width 0.148)
		(layer "In2.Cu")
		(net 107)
	)
	(segment
		(start 176.425975 121.775975)
		(end 176.425976 121.775976)
		(width 0.148)
		(layer "In2.Cu")
		(net 107)
	)
	(segment
		(start 178.787954 122.63133)
		(end 178.787956 122.631331)
		(width 0.148)
		(layer "In2.Cu")
		(net 107)
	)
	(segment
		(start 187.675 145)
		(end 187 145)
		(width 0.148)
		(layer "In2.Cu")
		(net 107)
	)
	(segment
		(start 176.949442 120.33327)
		(end 176.949443 120.333271)
		(width 0.148)
		(layer "In2.Cu")
		(net 107)
	)
	(segment
		(start 175.047119 119.937499)
		(end 175.04712 119.937501)
		(width 0.148)
		(layer "In2.Cu")
		(net 107)
	)
	(segment
		(start 177.868699 121.252489)
		(end 177.8687 121.25249)
		(width 0.148)
		(layer "In2.Cu")
		(net 107)
	)
	(segment
		(start 157.6 109.775)
		(end 156.7 110.675)
		(width 0.148)
		(layer "In2.Cu")
		(net 107)
	)
	(segment
		(start 176.949444 120.792891)
		(end 176.425976 121.316356)
		(width 0.148)
		(layer "In2.Cu")
		(net 107)
	)
	(segment
		(start 175.966357 120.856737)
		(end 175.966358 120.856739)
		(width 0.148)
		(layer "In2.Cu")
		(net 107)
	)
	(segment
		(start 187 145)
		(end 186.5 145.5)
		(width 0.148)
		(layer "In2.Cu")
		(net 107)
	)
	(segment
		(start 160.7 107.152)
		(end 160.7 106.7)
		(width 0.148)
		(layer "In2.Cu")
		(net 107)
	)
	(segment
		(start 175.04712 119.937501)
		(end 175.57057 119.414048)
		(width 0.148)
		(layer "In2.Cu")
		(net 107)
	)
	(segment
		(start 177.345213 122.695213)
		(end 177.345214 122.695214)
		(width 0.148)
		(layer "In2.Cu")
		(net 107)
	)
	(segment
		(start 174.4 119.75)
		(end 174.5875 119.9375)
		(width 0.148)
		(layer "In2.Cu")
		(net 107)
	)
	(segment
		(start 176.03019 119.414048)
		(end 176.03019 119.414049)
		(width 0.148)
		(layer "In2.Cu")
		(net 107)
	)
	(segment
		(start 156.7 114.7)
		(end 161.75 119.75)
		(width 0.148)
		(layer "In2.Cu")
		(net 107)
	)
	(segment
		(start 176.949442 120.79289)
		(end 176.949444 120.792891)
		(width 0.148)
		(layer "In2.Cu")
		(net 107)
	)
	(segment
		(start 175.506738 120.856739)
		(end 175.506737 120.856737)
		(width 0.148)
		(layer "In2.Cu")
		(net 107)
	)
	(segment
		(start 176.030189 119.873668)
		(end 176.030189 119.873667)
		(width 0.148)
		(layer "In2.Cu")
		(net 107)
	)
	(segment
		(start 188.95 134.3)
		(end 188.95 142.484728)
		(width 0.148)
		(layer "In2.Cu")
		(net 107)
	)
	(segment
		(start 160.5 106.5)
		(end 158 106.5)
		(width 0.148)
		(layer "In2.Cu")
		(net 107)
	)
	(segment
		(start 178.787954 122.17171)
		(end 178.787955 122.171711)
		(width 0.148)
		(layer "In2.Cu")
		(net 107)
	)
	(arc
		(start 175.506738 120.856738)
		(mid 175.736548 120.951928)
		(end 175.966357 120.856737)
		(width 0.148)
		(layer "In2.Cu")
		(net 107)
	)
	(arc
		(start 176.425976 121.316356)
		(mid 176.330785 121.546165)
		(end 176.425975 121.775975)
		(width 0.148)
		(layer "In2.Cu")
		(net 107)
	)
	(arc
		(start 177.40908 121.25249)
		(mid 177.638889 121.157299)
		(end 177.868699 121.252489)
		(width 0.148)
		(layer "In2.Cu")
		(net 107)
	)
	(arc
		(start 176.949443 120.333271)
		(mid 177.044633 120.563081)
		(end 176.949442 120.79289)
		(width 0.148)
		(layer "In2.Cu")
		(net 107)
	)
	(arc
		(start 176.03019 119.414049)
		(mid 176.12538 119.643859)
		(end 176.030189 119.873668)
		(width 0.148)
		(layer "In2.Cu")
		(net 107)
	)
	(arc
		(start 177.345214 122.235594)
		(mid 177.250023 122.465403)
		(end 177.345213 122.695213)
		(width 0.148)
		(layer "In2.Cu")
		(net 107)
	)
	(arc
		(start 176.489823 120.333271)
		(mid 176.719632 120.23808)
		(end 176.949442 120.33327)
		(width 0.148)
		(layer "In2.Cu")
		(net 107)
	)
	(arc
		(start 178.328335 122.171711)
		(mid 178.558144 122.07652)
		(end 178.787954 122.17171)
		(width 0.148)
		(layer "In2.Cu")
		(net 107)
	)
	(arc
		(start 174.5875 119.9375)
		(mid 174.81731 120.03269)
		(end 175.047119 119.937499)
		(width 0.148)
		(layer "In2.Cu")
		(net 107)
	)
	(arc
		(start 175.57057 119.414048)
		(mid 175.80038 119.318858)
		(end 176.03019 119.414048)
		(width 0.148)
		(layer "In2.Cu")
		(net 107)
	)
	(arc
		(start 175.506738 120.397119)
		(mid 175.411548 120.626929)
		(end 175.506738 120.856739)
		(width 0.148)
		(layer "In2.Cu")
		(net 107)
	)
	(arc
		(start 178.787955 122.171711)
		(mid 178.883145 122.401521)
		(end 178.787954 122.63133)
		(width 0.148)
		(layer "In2.Cu")
		(net 107)
	)
	(arc
		(start 177.345214 122.695214)
		(mid 177.575024 122.790404)
		(end 177.804833 122.695213)
		(width 0.148)
		(layer "In2.Cu")
		(net 107)
	)
	(arc
		(start 177.8687 121.25249)
		(mid 177.96389 121.4823)
		(end 177.868699 121.712109)
		(width 0.148)
		(layer "In2.Cu")
		(net 107)
	)
	(arc
		(start 176.425976 121.775976)
		(mid 176.655786 121.871166)
		(end 176.885595 121.775975)
		(width 0.148)
		(layer "In2.Cu")
		(net 107)
	)
	(arc
		(start 178.264452 123.154832)
		(mid 178.169261 123.384641)
		(end 178.264451 123.614451)
		(width 0.148)
		(layer "In2.Cu")
		(net 107)
	)
	(segment
		(start 200.0005 143.9995)
		(end 200.5 143.5)
		(width 0.256)
		(layer "F.Cu")
		(net 108)
	)
	(segment
		(start 224.45 106)
		(end 224.45 107.152)
		(width 0.38)
		(layer "F.Cu")
		(net 108)
	)
	(via
		(at 200.5 143.5)
		(size 0.45)
		(drill 0.1)
		(layers "F.Cu" "B.Cu")
		(remove_unused_layers yes)
		(keep_end_layers yes)
		(zone_layer_connections)
		(net 108)
	)
	(via
		(at 224.45 107.152)
		(size 0.45)
		(drill 0.1)
		(layers "F.Cu" "B.Cu")
		(remove_unused_layers yes)
		(keep_end_layers yes)
		(zone_layer_connections)
		(net 108)
	)
	(segment
		(start 203.3439 127.155056)
		(end 203.022279 126.833435)
		(width 0.13)
		(layer "In2.Cu")
		(net 108)
	)
	(segment
		(start 200.85 143.5)
		(end 200.9 143.45)
		(width 0.1)
		(layer "In2.Cu")
		(net 108)
	)
	(segment
		(start 202.88 141.920294)
		(end 202.88 128.050294)
		(width 0.13)
		(layer "In2.Cu")
		(net 108)
	)
	(segment
		(start 204.545983 126.384311)
		(end 204.545982 126.384309)
		(width 0.13)
		(layer "In2.Cu")
		(net 108)
	)
	(segment
		(start 225.5 106.32)
		(end 225.5 106.36)
		(width 0.13)
		(layer "In2.Cu")
		(net 108)
	)
	(segment
		(start 230.205 109.800294)
		(end 229.43 110.575294)
		(width 0.13)
		(layer "In2.Cu")
		(net 108)
	)
	(segment
		(start 202.88 128.050294)
		(end 203.2589 127.671391)
		(width 0.13)
		(layer "In2.Cu")
		(net 108)
	)
	(segment
		(start 203.793026 126.062689)
		(end 204.114648 126.384311)
		(width 0.13)
		(layer "In2.Cu")
		(net 108)
	)
	(segment
		(start 200.9 143.45)
		(end 200.9 143.258578)
		(width 0.1)
		(layer "In2.Cu")
		(net 108)
	)
	(segment
		(start 225.9 106.36)
		(end 225.9 106.32)
		(width 0.13)
		(layer "In2.Cu")
		(net 108)
	)
	(segment
		(start 228.58 107.324706)
		(end 230.205 108.949706)
		(width 0.13)
		(layer "In2.Cu")
		(net 108)
	)
	(segment
		(start 229.43 110.575294)
		(end 229.43 115.650294)
		(width 0.13)
		(layer "In2.Cu")
		(net 108)
	)
	(segment
		(start 201.278578 142.88)
		(end 201.69446 142.88)
		(width 0.1)
		(layer "In2.Cu")
		(net 108)
	)
	(segment
		(start 204.995067 124.860566)
		(end 205.31673 125.182229)
		(width 0.13)
		(layer "In2.Cu")
		(net 108)
	)
	(segment
		(start 228.58 106.899706)
		(end 228.58 107.324706)
		(width 0.13)
		(layer "In2.Cu")
		(net 108)
	)
	(segment
		(start 200.5 143.5)
		(end 200.85 143.5)
		(width 0.1)
		(layer "In2.Cu")
		(net 108)
	)
	(segment
		(start 224.399706 106.17)
		(end 224.55 106.17)
		(width 0.13)
		(layer "In2.Cu")
		(net 108)
	)
	(segment
		(start 225.65 106.51)
		(end 225.75 106.51)
		(width 0.13)
		(layer "In2.Cu")
		(net 108)
	)
	(segment
		(start 225.25 106.17)
		(end 225.35 106.17)
		(width 0.13)
		(layer "In2.Cu")
		(net 108)
	)
	(segment
		(start 201.69446 142.88)
		(end 201.920294 142.88)
		(width 0.13)
		(layer "In2.Cu")
		(net 108)
	)
	(segment
		(start 204.224321 124.860566)
		(end 204.22432 124.860567)
		(width 0.13)
		(layer "In2.Cu")
		(net 108)
	)
	(segment
		(start 230.205 108.949706)
		(end 230.205 109.800294)
		(width 0.13)
		(layer "In2.Cu")
		(net 108)
	)
	(segment
		(start 224.85 106.47)
		(end 224.95 106.47)
		(width 0.13)
		(layer "In2.Cu")
		(net 108)
	)
	(segment
		(start 206.19719 123.658525)
		(end 206.518812 123.980147)
		(width 0.13)
		(layer "In2.Cu")
		(net 108)
	)
	(segment
		(start 203.258903 127.671391)
		(end 203.343901 127.586391)
		(width 0.13)
		(layer "In2.Cu")
		(net 108)
	)
	(segment
		(start 207.200294 123.73)
		(end 206.950147 123.980147)
		(width 0.13)
		(layer "In2.Cu")
		(net 108)
	)
	(segment
		(start 203.2589 127.671391)
		(end 203.258903 127.671391)
		(width 0.13)
		(layer "In2.Cu")
		(net 108)
	)
	(segment
		(start 227.850294 106.17)
		(end 228.58 106.899706)
		(width 0.13)
		(layer "In2.Cu")
		(net 108)
	)
	(segment
		(start 204.114648 126.384311)
		(end 204.114647 126.384311)
		(width 0.13)
		(layer "In2.Cu")
		(net 108)
	)
	(segment
		(start 204.545983 125.952974)
		(end 204.224321 125.631312)
		(width 0.13)
		(layer "In2.Cu")
		(net 108)
	)
	(segment
		(start 224.145 106.424706)
		(end 224.399706 106.17)
		(width 0.13)
		(layer "In2.Cu")
		(net 108)
	)
	(segment
		(start 221.350294 123.73)
		(end 207.200294 123.73)
		(width 0.13)
		(layer "In2.Cu")
		(net 108)
	)
	(segment
		(start 224.45 107.152)
		(end 224.145 106.847)
		(width 0.13)
		(layer "In2.Cu")
		(net 108)
	)
	(segment
		(start 200.9 143.258578)
		(end 201.278578 142.88)
		(width 0.1)
		(layer "In2.Cu")
		(net 108)
	)
	(segment
		(start 205.748064 124.750892)
		(end 205.426443 124.429271)
		(width 0.13)
		(layer "In2.Cu")
		(net 108)
	)
	(segment
		(start 201.920294 142.88)
		(end 202.88 141.920294)
		(width 0.13)
		(layer "In2.Cu")
		(net 108)
	)
	(segment
		(start 224.145 106.847)
		(end 224.145 106.424706)
		(width 0.13)
		(layer "In2.Cu")
		(net 108)
	)
	(segment
		(start 203.022279 126.062689)
		(end 203.022279 126.062688)
		(width 0.13)
		(layer "In2.Cu")
		(net 108)
	)
	(segment
		(start 226.05 106.17)
		(end 227.850294 106.17)
		(width 0.13)
		(layer "In2.Cu")
		(net 108)
	)
	(segment
		(start 229.43 115.650294)
		(end 221.350294 123.73)
		(width 0.13)
		(layer "In2.Cu")
		(net 108)
	)
	(arc
		(start 204.22432 124.860567)
		(mid 204.609693 124.70094)
		(end 204.995067 124.860566)
		(width 0.13)
		(layer "In2.Cu")
		(net 108)
	)
	(arc
		(start 203.022279 126.833435)
		(mid 202.862652 126.448062)
		(end 203.022279 126.062689)
		(width 0.13)
		(layer "In2.Cu")
		(net 108)
	)
	(arc
		(start 204.545982 126.384309)
		(mid 204.635315 126.168642)
		(end 204.545983 125.952974)
		(width 0.13)
		(layer "In2.Cu")
		(net 108)
	)
	(arc
		(start 204.224321 125.631312)
		(mid 204.064694 125.245939)
		(end 204.224321 124.860566)
		(width 0.13)
		(layer "In2.Cu")
		(net 108)
	)
	(arc
		(start 225.75 106.51)
		(mid 225.856066 106.466066)
		(end 225.9 106.36)
		(width 0.13)
		(layer "In2.Cu")
		(net 108)
	)
	(arc
		(start 225.9 106.32)
		(mid 225.943934 106.213934)
		(end 226.05 106.17)
		(width 0.13)
		(layer "In2.Cu")
		(net 108)
	)
	(arc
		(start 225.1 106.32)
		(mid 225.143934 106.213934)
		(end 225.25 106.17)
		(width 0.13)
		(layer "In2.Cu")
		(net 108)
	)
	(arc
		(start 205.316729 125.182229)
		(mid 205.532397 125.271562)
		(end 205.748065 125.182229)
		(width 0.13)
		(layer "In2.Cu")
		(net 108)
	)
	(arc
		(start 224.7 106.32)
		(mid 224.743934 106.426066)
		(end 224.85 106.47)
		(width 0.13)
		(layer "In2.Cu")
		(net 108)
	)
	(arc
		(start 203.343901 127.586391)
		(mid 203.433233 127.370723)
		(end 203.3439 127.155056)
		(width 0.13)
		(layer "In2.Cu")
		(net 108)
	)
	(arc
		(start 205.426443 123.658524)
		(mid 205.811817 123.498898)
		(end 206.19719 123.658525)
		(width 0.13)
		(layer "In2.Cu")
		(net 108)
	)
	(arc
		(start 225.35 106.17)
		(mid 225.456066 106.213934)
		(end 225.5 106.32)
		(width 0.13)
		(layer "In2.Cu")
		(net 108)
	)
	(arc
		(start 205.748065 125.182227)
		(mid 205.837397 124.966559)
		(end 205.748064 124.750892)
		(width 0.13)
		(layer "In2.Cu")
		(net 108)
	)
	(arc
		(start 206.950147 123.980147)
		(mid 206.734479 124.06948)
		(end 206.518811 123.980147)
		(width 0.13)
		(layer "In2.Cu")
		(net 108)
	)
	(arc
		(start 204.114647 126.384311)
		(mid 204.330315 126.473644)
		(end 204.545983 126.384311)
		(width 0.13)
		(layer "In2.Cu")
		(net 108)
	)
	(arc
		(start 225.5 106.36)
		(mid 225.543934 106.466066)
		(end 225.65 106.51)
		(width 0.13)
		(layer "In2.Cu")
		(net 108)
	)
	(arc
		(start 224.55 106.17)
		(mid 224.656066 106.213934)
		(end 224.7 106.32)
		(width 0.13)
		(layer "In2.Cu")
		(net 108)
	)
	(arc
		(start 224.95 106.47)
		(mid 225.056066 106.426066)
		(end 225.1 106.32)
		(width 0.13)
		(layer "In2.Cu")
		(net 108)
	)
	(arc
		(start 205.426443 124.429271)
		(mid 205.266816 124.043898)
		(end 205.426443 123.658525)
		(width 0.13)
		(layer "In2.Cu")
		(net 108)
	)
	(arc
		(start 203.022279 126.062688)
		(mid 203.407653 125.903062)
		(end 203.793026 126.062689)
		(width 0.13)
		(layer "In2.Cu")
		(net 108)
	)
	(segment
		(start 223.6 106)
		(end 223.6 107.152)
		(width 0.38)
		(layer "F.Cu")
		(net 109)
	)
	(segment
		(start 201.0005 143.9995)
		(end 201.5 143.5)
		(width 0.256)
		(layer "F.Cu")
		(net 109)
	)
	(via
		(at 223.6 107.152)
		(size 0.45)
		(drill 0.1)
		(layers "F.Cu" "B.Cu")
		(remove_unused_layers yes)
		(keep_end_layers yes)
		(zone_layer_connections)
		(net 109)
	)
	(via
		(at 201.5 143.5)
		(size 0.45)
		(drill 0.1)
		(layers "F.Cu" "B.Cu")
		(remove_unused_layers yes)
		(keep_end_layers yes)
		(zone_layer_connections)
		(net 109)
	)
	(segment
		(start 202.019706 143.12)
		(end 201.69446 143.12)
		(width 0.13)
		(layer "In2.Cu")
		(net 109)
	)
	(segment
		(start 204.394026 125.030272)
		(end 204.394026 125.030271)
		(width 0.13)
		(layer "In2.Cu")
		(net 109)
	)
	(segment
		(start 223.905 106.847)
		(end 223.905 106.325294)
		(width 0.13)
		(layer "In2.Cu")
		(net 109)
	)
	(segment
		(start 203.944942 126.554016)
		(end 203.62332 126.232394)
		(width 0.13)
		(layer "In2.Cu")
		(net 109)
	)
	(segment
		(start 201.1 143.341422)
		(end 201.321422 143.12)
		(width 0.1)
		(layer "In2.Cu")
		(net 109)
	)
	(segment
		(start 207.299706 123.97)
		(end 207.119852 124.149852)
		(width 0.13)
		(layer "In2.Cu")
		(net 109)
	)
	(segment
		(start 205.596149 124.259564)
		(end 205.596149 124.259565)
		(width 0.13)
		(layer "In2.Cu")
		(net 109)
	)
	(segment
		(start 203.12 128.149706)
		(end 203.12 142.019706)
		(width 0.13)
		(layer "In2.Cu")
		(net 109)
	)
	(segment
		(start 203.191985 126.663729)
		(end 203.513606 126.98535)
		(width 0.13)
		(layer "In2.Cu")
		(net 109)
	)
	(segment
		(start 205.596149 124.259565)
		(end 205.91777 124.581186)
		(width 0.13)
		(layer "In2.Cu")
		(net 109)
	)
	(segment
		(start 227.949706 105.93)
		(end 228.82 106.800294)
		(width 0.13)
		(layer "In2.Cu")
		(net 109)
	)
	(segment
		(start 230.445 108.850294)
		(end 230.445 109.899706)
		(width 0.13)
		(layer "In2.Cu")
		(net 109)
	)
	(segment
		(start 203.12 142.019706)
		(end 202.019706 143.12)
		(width 0.13)
		(layer "In2.Cu")
		(net 109)
	)
	(segment
		(start 223.905 106.325294)
		(end 224.300294 105.93)
		(width 0.13)
		(layer "In2.Cu")
		(net 109)
	)
	(segment
		(start 204.394026 125.461606)
		(end 204.715688 125.783268)
		(width 0.13)
		(layer "In2.Cu")
		(net 109)
	)
	(segment
		(start 203.513606 127.756097)
		(end 203.428609 127.841097)
		(width 0.13)
		(layer "In2.Cu")
		(net 109)
	)
	(segment
		(start 203.513607 127.756097)
		(end 203.513606 127.756097)
		(width 0.13)
		(layer "In2.Cu")
		(net 109)
	)
	(segment
		(start 228.82 107.225294)
		(end 230.445 108.850294)
		(width 0.13)
		(layer "In2.Cu")
		(net 109)
	)
	(segment
		(start 206.349106 124.149852)
		(end 206.027484 123.82823)
		(width 0.13)
		(layer "In2.Cu")
		(net 109)
	)
	(segment
		(start 229.67 115.749706)
		(end 221.449706 123.97)
		(width 0.13)
		(layer "In2.Cu")
		(net 109)
	)
	(segment
		(start 229.67 110.674706)
		(end 229.67 115.749706)
		(width 0.13)
		(layer "In2.Cu")
		(net 109)
	)
	(segment
		(start 224.300294 105.93)
		(end 227.949706 105.93)
		(width 0.13)
		(layer "In2.Cu")
		(net 109)
	)
	(segment
		(start 203.191985 126.232393)
		(end 203.191985 126.232394)
		(width 0.13)
		(layer "In2.Cu")
		(net 109)
	)
	(segment
		(start 203.191985 126.663728)
		(end 203.191985 126.663729)
		(width 0.13)
		(layer "In2.Cu")
		(net 109)
	)
	(segment
		(start 201.5 143.5)
		(end 201.15 143.5)
		(width 0.1)
		(layer "In2.Cu")
		(net 109)
	)
	(segment
		(start 230.445 109.899706)
		(end 229.67 110.674706)
		(width 0.13)
		(layer "In2.Cu")
		(net 109)
	)
	(segment
		(start 228.82 106.800294)
		(end 228.82 107.225294)
		(width 0.13)
		(layer "In2.Cu")
		(net 109)
	)
	(segment
		(start 201.321422 143.12)
		(end 201.69446 143.12)
		(width 0.1)
		(layer "In2.Cu")
		(net 109)
	)
	(segment
		(start 204.394026 125.461605)
		(end 204.394026 125.461606)
		(width 0.13)
		(layer "In2.Cu")
		(net 109)
	)
	(segment
		(start 223.6 107.152)
		(end 223.905 106.847)
		(width 0.13)
		(layer "In2.Cu")
		(net 109)
	)
	(segment
		(start 201.15 143.5)
		(end 201.1 143.45)
		(width 0.1)
		(layer "In2.Cu")
		(net 109)
	)
	(segment
		(start 221.449706 123.97)
		(end 207.299706 123.97)
		(width 0.13)
		(layer "In2.Cu")
		(net 109)
	)
	(segment
		(start 201.1 143.45)
		(end 201.1 143.341422)
		(width 0.1)
		(layer "In2.Cu")
		(net 109)
	)
	(segment
		(start 205.147024 125.351934)
		(end 204.825361 125.030271)
		(width 0.13)
		(layer "In2.Cu")
		(net 109)
	)
	(segment
		(start 203.428606 127.841097)
		(end 203.12 128.149706)
		(width 0.13)
		(layer "In2.Cu")
		(net 109)
	)
	(segment
		(start 203.428609 127.841097)
		(end 203.428606 127.841097)
		(width 0.13)
		(layer "In2.Cu")
		(net 109)
	)
	(arc
		(start 203.513606 126.98535)
		(mid 203.673233 127.370723)
		(end 203.513607 127.756097)
		(width 0.13)
		(layer "In2.Cu")
		(net 109)
	)
	(arc
		(start 203.62332 126.232394)
		(mid 203.407653 126.143061)
		(end 203.191985 126.232393)
		(width 0.13)
		(layer "In2.Cu")
		(net 109)
	)
	(arc
		(start 203.191985 126.232394)
		(mid 203.102653 126.448061)
		(end 203.191985 126.663728)
		(width 0.13)
		(layer "In2.Cu")
		(net 109)
	)
	(arc
		(start 204.715688 126.554016)
		(mid 204.330315 126.713643)
		(end 203.944942 126.554016)
		(width 0.13)
		(layer "In2.Cu")
		(net 109)
	)
	(arc
		(start 204.394026 125.030271)
		(mid 204.304694 125.245938)
		(end 204.394026 125.461605)
		(width 0.13)
		(layer "In2.Cu")
		(net 109)
	)
	(arc
		(start 206.027484 123.82823)
		(mid 205.811817 123.738897)
		(end 205.596149 123.828229)
		(width 0.13)
		(layer "In2.Cu")
		(net 109)
	)
	(arc
		(start 205.91777 125.351934)
		(mid 205.532397 125.511561)
		(end 205.147024 125.351934)
		(width 0.13)
		(layer "In2.Cu")
		(net 109)
	)
	(arc
		(start 204.825361 125.030271)
		(mid 204.609693 124.940939)
		(end 204.394026 125.030272)
		(width 0.13)
		(layer "In2.Cu")
		(net 109)
	)
	(arc
		(start 204.715688 125.783268)
		(mid 204.875314 126.168642)
		(end 204.715687 126.554015)
		(width 0.13)
		(layer "In2.Cu")
		(net 109)
	)
	(arc
		(start 205.91777 124.581186)
		(mid 206.077397 124.966559)
		(end 205.917771 125.351933)
		(width 0.13)
		(layer "In2.Cu")
		(net 109)
	)
	(arc
		(start 205.596149 123.82823)
		(mid 205.506817 124.043897)
		(end 205.596149 124.259564)
		(width 0.13)
		(layer "In2.Cu")
		(net 109)
	)
	(arc
		(start 207.119852 124.149852)
		(mid 206.734479 124.309479)
		(end 206.349106 124.149852)
		(width 0.13)
		(layer "In2.Cu")
		(net 109)
	)
	(segment
		(start 156.45 106)
		(end 156.45 107.152)
		(width 0.38)
		(layer "F.Cu")
		(net 110)
	)
	(segment
		(start 184.9995 144.9995)
		(end 184.5 144.5)
		(width 0.256)
		(layer "F.Cu")
		(net 110)
	)
	(via
		(at 156.45 107.152)
		(size 0.45)
		(drill 0.1)
		(layers "F.Cu" "B.Cu")
		(remove_unused_layers yes)
		(keep_end_layers yes)
		(zone_layer_connections)
		(net 110)
	)
	(via
		(at 184.5 144.5)
		(size 0.45)
		(drill 0.1)
		(layers "F.Cu" "B.Cu")
		(remove_unused_layers yes)
		(keep_end_layers yes)
		(zone_layer_connections)
		(net 110)
	)
	(segment
		(start 155.3 108.302)
		(end 155.3 110.4)
		(width 0.148)
		(layer "In2.Cu")
		(net 110)
	)
	(segment
		(start 185.435729 142)
		(end 185 142.435729)
		(width 0.148)
		(layer "In2.Cu")
		(net 110)
	)
	(segment
		(start 154.5 118.5)
		(end 160.75 124.75)
		(width 0.148)
		(layer "In2.Cu")
		(net 110)
	)
	(segment
		(start 175.466152 130.036968)
		(end 175.466151 130.036969)
		(width 0.148)
		(layer "In2.Cu")
		(net 110)
	)
	(segment
		(start 186.564272 142)
		(end 185.435729 142)
		(width 0.148)
		(layer "In2.Cu")
		(net 110)
	)
	(segment
		(start 155 113)
		(end 154.5 113.5)
		(width 0.148)
		(layer "In2.Cu")
		(net 110)
	)
	(segment
		(start 177.149999 127.151041)
		(end 177.15 127.15104)
		(width 0.148)
		(layer "In2.Cu")
		(net 110)
	)
	(segment
		(start 187 136.4)
		(end 187 141.564272)
		(width 0.148)
		(layer "In2.Cu")
		(net 110)
	)
	(segment
		(start 185 142.435729)
		(end 185 143.6)
		(width 0.148)
		(layer "In2.Cu")
		(net 110)
	)
	(segment
		(start 175.466151 130.036969)
		(end 177.751039 127.75208)
		(width 0.148)
		(layer "In2.Cu")
		(net 110)
	)
	(segment
		(start 187 141.564272)
		(end 186.564272 142)
		(width 0.148)
		(layer "In2.Cu")
		(net 110)
	)
	(segment
		(start 179.554161 128.954161)
		(end 187 136.4)
		(width 0.148)
		(layer "In2.Cu")
		(net 110)
	)
	(segment
		(start 156.45 107.152)
		(end 155.3 108.302)
		(width 0.148)
		(layer "In2.Cu")
		(net 110)
	)
	(segment
		(start 177.693594 130.213688)
		(end 177.693593 130.213689)
		(width 0.148)
		(layer "In2.Cu")
		(net 110)
	)
	(segment
		(start 160.75 124.75)
		(end 175.35 124.75)
		(width 0.148)
		(layer "In2.Cu")
		(net 110)
	)
	(segment
		(start 155.3 110.4)
		(end 155 110.7)
		(width 0.148)
		(layer "In2.Cu")
		(net 110)
	)
	(segment
		(start 154.5 113.5)
		(end 154.5 118.5)
		(width 0.148)
		(layer "In2.Cu")
		(net 110)
	)
	(segment
		(start 178.35208 127.75208)
		(end 178.352081 127.752081)
		(width 0.148)
		(layer "In2.Cu")
		(net 110)
	)
	(segment
		(start 178.35208 128.353122)
		(end 178.352081 128.353121)
		(width 0.148)
		(layer "In2.Cu")
		(net 110)
	)
	(segment
		(start 178.352081 128.353121)
		(end 177.092553 129.612648)
		(width 0.148)
		(layer "In2.Cu")
		(net 110)
	)
	(segment
		(start 177.092553 130.213688)
		(end 177.092553 130.213689)
		(width 0.148)
		(layer "In2.Cu")
		(net 110)
	)
	(segment
		(start 179.55416 128.954161)
		(end 179.554161 128.954161)
		(width 0.148)
		(layer "In2.Cu")
		(net 110)
	)
	(segment
		(start 177.693593 130.213689)
		(end 178.95312 128.954161)
		(width 0.148)
		(layer "In2.Cu")
		(net 110)
	)
	(segment
		(start 155 110.7)
		(end 155 113)
		(width 0.148)
		(layer "In2.Cu")
		(net 110)
	)
	(segment
		(start 174.86511 130.036969)
		(end 174.865111 130.036969)
		(width 0.148)
		(layer "In2.Cu")
		(net 110)
	)
	(segment
		(start 178.35208 127.752079)
		(end 178.35208 127.75208)
		(width 0.148)
		(layer "In2.Cu")
		(net 110)
	)
	(segment
		(start 184.5 144.1)
		(end 184.5 144.5)
		(width 0.148)
		(layer "In2.Cu")
		(net 110)
	)
	(segment
		(start 175.35 124.75)
		(end 177.15 126.55)
		(width 0.148)
		(layer "In2.Cu")
		(net 110)
	)
	(segment
		(start 185 143.6)
		(end 184.5 144.1)
		(width 0.148)
		(layer "In2.Cu")
		(net 110)
	)
	(segment
		(start 177.15 127.15104)
		(end 174.865111 129.435928)
		(width 0.148)
		(layer "In2.Cu")
		(net 110)
	)
	(arc
		(start 178.95312 128.954161)
		(mid 179.25364 128.829682)
		(end 179.55416 128.954161)
		(width 0.148)
		(layer "In2.Cu")
		(net 110)
	)
	(arc
		(start 174.865111 130.036969)
		(mid 175.165632 130.161448)
		(end 175.466152 130.036968)
		(width 0.148)
		(layer "In2.Cu")
		(net 110)
	)
	(arc
		(start 177.751039 127.75208)
		(mid 178.051559 127.6276)
		(end 178.35208 127.752079)
		(width 0.148)
		(layer "In2.Cu")
		(net 110)
	)
	(arc
		(start 177.092553 129.612648)
		(mid 176.968074 129.913168)
		(end 177.092553 130.213688)
		(width 0.148)
		(layer "In2.Cu")
		(net 110)
	)
	(arc
		(start 174.865111 129.435928)
		(mid 174.740631 129.736448)
		(end 174.86511 130.036969)
		(width 0.148)
		(layer "In2.Cu")
		(net 110)
	)
	(arc
		(start 177.092553 130.213689)
		(mid 177.393074 130.338168)
		(end 177.693594 130.213688)
		(width 0.148)
		(layer "In2.Cu")
		(net 110)
	)
	(arc
		(start 177.15 126.55)
		(mid 177.274479 126.850521)
		(end 177.149999 127.151041)
		(width 0.148)
		(layer "In2.Cu")
		(net 110)
	)
	(arc
		(start 178.352081 127.752081)
		(mid 178.47656 128.052602)
		(end 178.35208 128.353122)
		(width 0.148)
		(layer "In2.Cu")
		(net 110)
	)
	(segment
		(start 154.75 106)
		(end 154.75 107.152)
		(width 0.38)
		(layer "F.Cu")
		(net 111)
	)
	(segment
		(start 184.9995 145.9995)
		(end 184.5 145.5)
		(width 0.256)
		(layer "F.Cu")
		(net 111)
	)
	(via
		(at 154.75 107.152)
		(size 0.45)
		(drill 0.1)
		(layers "F.Cu" "B.Cu")
		(remove_unused_layers yes)
		(keep_end_layers yes)
		(zone_layer_connections)
		(net 111)
	)
	(via
		(at 184.5 145.5)
		(size 0.45)
		(drill 0.1)
		(layers "F.Cu" "B.Cu")
		(remove_unused_layers yes)
		(keep_end_layers yes)
		(zone_layer_connections)
		(net 111)
	)
	(segment
		(start 185.501 139.899)
		(end 185 140.4)
		(width 0.148)
		(layer "In2.Cu")
		(net 111)
	)
	(segment
		(start 174.59375 131.04375)
		(end 180.35625 131.04375)
		(width 0.148)
		(layer "In2.Cu")
		(net 111)
	)
	(segment
		(start 171.07708 127.527081)
		(end 171.07708 127.52708)
		(width 0.148)
		(layer "In2.Cu")
		(net 111)
	)
	(segment
		(start 169.6 126.05)
		(end 169.875 126.325)
		(width 0.148)
		(layer "In2.Cu")
		(net 111)
	)
	(segment
		(start 170.476041 126.324999)
		(end 170.47604 126.325)
		(width 0.148)
		(layer "In2.Cu")
		(net 111)
	)
	(segment
		(start 185.701 139.899)
		(end 185.501 139.899)
		(width 0.148)
		(layer "In2.Cu")
		(net 111)
	)
	(segment
		(start 160.15 126.05)
		(end 169.6 126.05)
		(width 0.148)
		(layer "In2.Cu")
		(net 111)
	)
	(segment
		(start 183.95 144.95)
		(end 184.5 145.5)
		(width 0.148)
		(layer "In2.Cu")
		(net 111)
	)
	(segment
		(start 154 107.9)
		(end 154 110.35)
		(width 0.148)
		(layer "In2.Cu")
		(net 111)
	)
	(segment
		(start 154 110.35)
		(end 154.299 110.649)
		(width 0.148)
		(layer "In2.Cu")
		(net 111)
	)
	(segment
		(start 172.279163 128.729162)
		(end 172.279161 128.729161)
		(width 0.148)
		(layer "In2.Cu")
		(net 111)
	)
	(segment
		(start 185 140.4)
		(end 185 141.564272)
		(width 0.148)
		(layer "In2.Cu")
		(net 111)
	)
	(segment
		(start 172.880203 128.729161)
		(end 172.880202 128.729162)
		(width 0.148)
		(layer "In2.Cu")
		(net 111)
	)
	(segment
		(start 153.5 119.4)
		(end 160.15 126.05)
		(width 0.148)
		(layer "In2.Cu")
		(net 111)
	)
	(segment
		(start 172.880202 128.729162)
		(end 174.11528 127.494085)
		(width 0.148)
		(layer "In2.Cu")
		(net 111)
	)
	(segment
		(start 184.536728 141.899)
		(end 183.95 142.485728)
		(width 0.148)
		(layer "In2.Cu")
		(net 111)
	)
	(segment
		(start 174.716321 127.494086)
		(end 174.71632 127.494084)
		(width 0.148)
		(layer "In2.Cu")
		(net 111)
	)
	(segment
		(start 153.5 113.5)
		(end 153.5 119.4)
		(width 0.148)
		(layer "In2.Cu")
		(net 111)
	)
	(segment
		(start 173.51424 126.292005)
		(end 173.514239 126.292003)
		(width 0.148)
		(layer "In2.Cu")
		(net 111)
	)
	(segment
		(start 186 136.6875)
		(end 186 139.6)
		(width 0.148)
		(layer "In2.Cu")
		(net 111)
	)
	(segment
		(start 172.279161 128.729161)
		(end 172.279162 128.729162)
		(width 0.148)
		(layer "In2.Cu")
		(net 111)
	)
	(segment
		(start 174.716319 128.095125)
		(end 174.71632 128.095124)
		(width 0.148)
		(layer "In2.Cu")
		(net 111)
	)
	(segment
		(start 171.498992 126.504128)
		(end 171.498993 126.504127)
		(width 0.148)
		(layer "In2.Cu")
		(net 111)
	)
	(segment
		(start 171.678121 127.527081)
		(end 172.913199 126.292004)
		(width 0.148)
		(layer "In2.Cu")
		(net 111)
	)
	(segment
		(start 171.07708 127.52708)
		(end 171.077081 127.527081)
		(width 0.148)
		(layer "In2.Cu")
		(net 111)
	)
	(segment
		(start 173.481242 129.931242)
		(end 174.59375 131.04375)
		(width 0.148)
		(layer "In2.Cu")
		(net 111)
	)
	(segment
		(start 183.95 142.485728)
		(end 183.95 144.95)
		(width 0.148)
		(layer "In2.Cu")
		(net 111)
	)
	(segment
		(start 174.71632 128.095124)
		(end 173.481243 129.330202)
		(width 0.148)
		(layer "In2.Cu")
		(net 111)
	)
	(segment
		(start 171.498994 125.903087)
		(end 171.498993 125.903087)
		(width 0.148)
		(layer "In2.Cu")
		(net 111)
	)
	(segment
		(start 173.481244 129.931243)
		(end 173.481242 129.931242)
		(width 0.148)
		(layer "In2.Cu")
		(net 111)
	)
	(segment
		(start 154.299 112.701)
		(end 153.5 113.5)
		(width 0.148)
		(layer "In2.Cu")
		(net 111)
	)
	(segment
		(start 185 141.564272)
		(end 184.665272 141.899)
		(width 0.148)
		(layer "In2.Cu")
		(net 111)
	)
	(segment
		(start 171.498993 126.504127)
		(end 171.077081 126.92604)
		(width 0.148)
		(layer "In2.Cu")
		(net 111)
	)
	(segment
		(start 184.665272 141.899)
		(end 184.536728 141.899)
		(width 0.148)
		(layer "In2.Cu")
		(net 111)
	)
	(segment
		(start 170.47604 126.325)
		(end 170.897953 125.903088)
		(width 0.148)
		(layer "In2.Cu")
		(net 111)
	)
	(segment
		(start 173.514238 126.893044)
		(end 173.514239 126.893043)
		(width 0.148)
		(layer "In2.Cu")
		(net 111)
	)
	(segment
		(start 154.75 107.15)
		(end 154 107.9)
		(width 0.148)
		(layer "In2.Cu")
		(net 111)
	)
	(segment
		(start 180.35625 131.04375)
		(end 186 136.6875)
		(width 0.148)
		(layer "In2.Cu")
		(net 111)
	)
	(segment
		(start 186 139.6)
		(end 185.701 139.899)
		(width 0.148)
		(layer "In2.Cu")
		(net 111)
	)
	(segment
		(start 173.514239 126.893043)
		(end 172.279162 128.128121)
		(width 0.148)
		(layer "In2.Cu")
		(net 111)
	)
	(segment
		(start 171.678122 127.52708)
		(end 171.678121 127.527081)
		(width 0.148)
		(layer "In2.Cu")
		(net 111)
	)
	(segment
		(start 154.299 110.649)
		(end 154.299 112.701)
		(width 0.148)
		(layer "In2.Cu")
		(net 111)
	)
	(arc
		(start 171.077081 127.527081)
		(mid 171.377602 127.65156)
		(end 171.678122 127.52708)
		(width 0.148)
		(layer "In2.Cu")
		(net 111)
	)
	(arc
		(start 174.11528 127.494085)
		(mid 174.415801 127.369606)
		(end 174.716321 127.494086)
		(width 0.148)
		(layer "In2.Cu")
		(net 111)
	)
	(arc
		(start 171.498993 125.903087)
		(mid 171.623472 126.203608)
		(end 171.498992 126.504128)
		(width 0.148)
		(layer "In2.Cu")
		(net 111)
	)
	(arc
		(start 173.481243 129.330202)
		(mid 173.356764 129.630723)
		(end 173.481244 129.931243)
		(width 0.148)
		(layer "In2.Cu")
		(net 111)
	)
	(arc
		(start 173.514239 126.292003)
		(mid 173.638718 126.592524)
		(end 173.514238 126.893044)
		(width 0.148)
		(layer "In2.Cu")
		(net 111)
	)
	(arc
		(start 174.71632 127.494084)
		(mid 174.840799 127.794605)
		(end 174.716319 128.095125)
		(width 0.148)
		(layer "In2.Cu")
		(net 111)
	)
	(arc
		(start 172.913199 126.292004)
		(mid 173.21372 126.167525)
		(end 173.51424 126.292005)
		(width 0.148)
		(layer "In2.Cu")
		(net 111)
	)
	(arc
		(start 171.077081 126.92604)
		(mid 170.952601 127.22656)
		(end 171.07708 127.527081)
		(width 0.148)
		(layer "In2.Cu")
		(net 111)
	)
	(arc
		(start 169.875 126.325)
		(mid 170.175521 126.449479)
		(end 170.476041 126.324999)
		(width 0.148)
		(layer "In2.Cu")
		(net 111)
	)
	(arc
		(start 170.897953 125.903088)
		(mid 171.198473 125.778608)
		(end 171.498994 125.903087)
		(width 0.148)
		(layer "In2.Cu")
		(net 111)
	)
	(arc
		(start 172.279162 128.128121)
		(mid 172.154683 128.428642)
		(end 172.279163 128.729162)
		(width 0.148)
		(layer "In2.Cu")
		(net 111)
	)
	(arc
		(start 172.279162 128.729162)
		(mid 172.579683 128.853641)
		(end 172.880203 128.729161)
		(width 0.148)
		(layer "In2.Cu")
		(net 111)
	)
	(segment
		(start 153.05 106)
		(end 153.05 107.152)
		(width 0.38)
		(layer "F.Cu")
		(net 112)
	)
	(segment
		(start 186.9995 139.9995)
		(end 186.5 139.5)
		(width 0.256)
		(layer "F.Cu")
		(net 112)
	)
	(via
		(at 153.05 107.152)
		(size 0.45)
		(drill 0.1)
		(layers "F.Cu" "B.Cu")
		(remove_unused_layers yes)
		(keep_end_layers yes)
		(zone_layer_connections)
		(net 112)
	)
	(via
		(at 186.5 139.5)
		(size 0.45)
		(drill 0.1)
		(layers "F.Cu" "B.Cu")
		(remove_unused_layers yes)
		(keep_end_layers yes)
		(zone_layer_connections)
		(net 112)
	)
	(segment
		(start 165.8 135.825)
		(end 169.475 135.825)
		(width 0.148)
		(layer "In6.Cu")
		(net 112)
	)
	(segment
		(start 161.012625 126.962625)
		(end 161.012626 126.962625)
		(width 0.148)
		(layer "In6.Cu")
		(net 112)
	)
	(segment
		(start 185.025 135.025)
		(end 186.5 136.5)
		(width 0.148)
		(layer "In6.Cu")
		(net 112)
	)
	(segment
		(start 161.012624 124.262623)
		(end 161.012623 124.262623)
		(width 0.148)
		(layer "In6.Cu")
		(net 112)
	)
	(segment
		(start 161.012574 125.162574)
		(end 161.012575 125.162574)
		(width 0.148)
		(layer "In6.Cu")
		(net 112)
	)
	(segment
		(start 161.450149 125.600148)
		(end 161.450149 125.625)
		(width 0.148)
		(layer "In6.Cu")
		(net 112)
	)
	(segment
		(start 160.575 130.6)
		(end 165.8 135.825)
		(width 0.148)
		(layer "In6.Cu")
		(net 112)
	)
	(segment
		(start 160.575 124.700246)
		(end 160.575 124.725)
		(width 0.148)
		(layer "In6.Cu")
		(net 112)
	)
	(segment
		(start 186.5 136.5)
		(end 186.5 139.5)
		(width 0.148)
		(layer "In6.Cu")
		(net 112)
	)
	(segment
		(start 161.012575 126.062574)
		(end 161.012574 126.062574)
		(width 0.148)
		(layer "In6.Cu")
		(net 112)
	)
	(segment
		(start 161.450247 123.800246)
		(end 161.450247 123.825)
		(width 0.148)
		(layer "In6.Cu")
		(net 112)
	)
	(segment
		(start 161.012623 123.362623)
		(end 161.012624 123.362623)
		(width 0.148)
		(layer "In6.Cu")
		(net 112)
	)
	(segment
		(start 161.5 106.75)
		(end 161.5 110.075)
		(width 0.148)
		(layer "In6.Cu")
		(net 112)
	)
	(segment
		(start 160.575 128.325)
		(end 160.575 130.6)
		(width 0.148)
		(layer "In6.Cu")
		(net 112)
	)
	(segment
		(start 160.575 126.500148)
		(end 160.575 126.525)
		(width 0.148)
		(layer "In6.Cu")
		(net 112)
	)
	(segment
		(start 160.575 111)
		(end 160.575 122.925)
		(width 0.148)
		(layer "In6.Cu")
		(net 112)
	)
	(segment
		(start 161.450251 127.40025)
		(end 161.450251 127.425)
		(width 0.148)
		(layer "In6.Cu")
		(net 112)
	)
	(segment
		(start 170.275 135.025)
		(end 185.025 135.025)
		(width 0.148)
		(layer "In6.Cu")
		(net 112)
	)
	(segment
		(start 169.475 135.825)
		(end 170.275 135.025)
		(width 0.148)
		(layer "In6.Cu")
		(net 112)
	)
	(segment
		(start 153.625 105.95)
		(end 160.7 105.95)
		(width 0.148)
		(layer "In6.Cu")
		(net 112)
	)
	(segment
		(start 160.7 105.95)
		(end 161.5 106.75)
		(width 0.148)
		(layer "In6.Cu")
		(net 112)
	)
	(segment
		(start 153.05 107.152)
		(end 153.05 106.525)
		(width 0.148)
		(layer "In6.Cu")
		(net 112)
	)
	(segment
		(start 153.05 106.525)
		(end 153.625 105.95)
		(width 0.148)
		(layer "In6.Cu")
		(net 112)
	)
	(segment
		(start 161.012626 127.862625)
		(end 161.012625 127.862625)
		(width 0.148)
		(layer "In6.Cu")
		(net 112)
	)
	(segment
		(start 160.575 128.30025)
		(end 160.575 128.325)
		(width 0.148)
		(layer "In6.Cu")
		(net 112)
	)
	(segment
		(start 161.5 110.075)
		(end 160.575 111)
		(width 0.148)
		(layer "In6.Cu")
		(net 112)
	)
	(arc
		(start 160.575 124.725)
		(mid 160.703162 125.034412)
		(end 161.012574 125.162574)
		(width 0.148)
		(layer "In6.Cu")
		(net 112)
	)
	(arc
		(start 160.575 126.525)
		(mid 160.703177 126.834448)
		(end 161.012625 126.962625)
		(width 0.148)
		(layer "In6.Cu")
		(net 112)
	)
	(arc
		(start 161.012623 124.262623)
		(mid 160.703177 124.3908)
		(end 160.575 124.700246)
		(width 0.148)
		(layer "In6.Cu")
		(net 112)
	)
	(arc
		(start 161.012624 123.362623)
		(mid 161.32207 123.4908)
		(end 161.450247 123.800246)
		(width 0.148)
		(layer "In6.Cu")
		(net 112)
	)
	(arc
		(start 161.450247 123.825)
		(mid 161.32207 124.134446)
		(end 161.012624 124.262623)
		(width 0.148)
		(layer "In6.Cu")
		(net 112)
	)
	(arc
		(start 161.012575 125.162574)
		(mid 161.321987 125.290736)
		(end 161.450149 125.600148)
		(width 0.148)
		(layer "In6.Cu")
		(net 112)
	)
	(arc
		(start 161.012625 127.862625)
		(mid 160.703177 127.990802)
		(end 160.575 128.30025)
		(width 0.148)
		(layer "In6.Cu")
		(net 112)
	)
	(arc
		(start 160.575 122.925)
		(mid 160.703177 123.234446)
		(end 161.012623 123.362623)
		(width 0.148)
		(layer "In6.Cu")
		(net 112)
	)
	(arc
		(start 161.450251 127.425)
		(mid 161.322074 127.734448)
		(end 161.012626 127.862625)
		(width 0.148)
		(layer "In6.Cu")
		(net 112)
	)
	(arc
		(start 161.012626 126.962625)
		(mid 161.322074 127.090802)
		(end 161.450251 127.40025)
		(width 0.148)
		(layer "In6.Cu")
		(net 112)
	)
	(arc
		(start 161.012574 126.062574)
		(mid 160.703162 126.190736)
		(end 160.575 126.500148)
		(width 0.148)
		(layer "In6.Cu")
		(net 112)
	)
	(arc
		(start 161.450149 125.625)
		(mid 161.321987 125.934412)
		(end 161.012575 126.062574)
		(width 0.148)
		(layer "In6.Cu")
		(net 112)
	)
	(segment
		(start 151.35 106)
		(end 151.35 107.152)
		(width 0.38)
		(layer "F.Cu")
		(net 113)
	)
	(segment
		(start 186.9995 140.9995)
		(end 186.5 140.5)
		(width 0.256)
		(layer "F.Cu")
		(net 113)
	)
	(via
		(at 151.35 107.152)
		(size 0.45)
		(drill 0.1)
		(layers "F.Cu" "B.Cu")
		(remove_unused_layers yes)
		(keep_end_layers yes)
		(zone_layer_connections)
		(net 113)
	)
	(via
		(at 186.5 140.5)
		(size 0.45)
		(drill 0.1)
		(layers "F.Cu" "B.Cu")
		(remove_unused_layers yes)
		(keep_end_layers yes)
		(zone_layer_connections)
		(net 113)
	)
	(segment
		(start 158.414751 126.860248)
		(end 158.414751 127.35)
		(width 0.148)
		(layer "In6.Cu")
		(net 113)
	)
	(segment
		(start 158.414849 116.06015)
		(end 158.414849 116.55)
		(width 0.148)
		(layer "In6.Cu")
		(net 113)
	)
	(segment
		(start 159.275 128.210248)
		(end 159.275 130.725)
		(width 0.148)
		(layer "In6.Cu")
		(net 113)
	)
	(segment
		(start 165.275 136.725)
		(end 170.5 136.725)
		(width 0.148)
		(layer "In6.Cu")
		(net 113)
	)
	(segment
		(start 158.414751 124.160248)
		(end 158.414751 124.65)
		(width 0.148)
		(layer "In6.Cu")
		(net 113)
	)
	(segment
		(start 152.55 108.35)
		(end 156.74 108.35)
		(width 0.148)
		(layer "In6.Cu")
		(net 113)
	)
	(segment
		(start 170.5 136.725)
		(end 171.325 135.9)
		(width 0.148)
		(layer "In6.Cu")
		(net 113)
	)
	(segment
		(start 158.844924 116.980075)
		(end 158.844925 116.980075)
		(width 0.148)
		(layer "In6.Cu")
		(net 113)
	)
	(segment
		(start 158.844875 127.780124)
		(end 158.844876 127.780124)
		(width 0.148)
		(layer "In6.Cu")
		(net 113)
	)
	(segment
		(start 158.844925 121.030075)
		(end 158.844924 121.030075)
		(width 0.148)
		(layer "In6.Cu")
		(net 113)
	)
	(segment
		(start 158.414849 121.46015)
		(end 158.414849 121.95)
		(width 0.148)
		(layer "In6.Cu")
		(net 113)
	)
	(segment
		(start 158.414849 118.76015)
		(end 158.414849 119.25)
		(width 0.148)
		(layer "In6.Cu")
		(net 113)
	)
	(segment
		(start 184.75 135.9)
		(end 186 137.15)
		(width 0.148)
		(layer "In6.Cu")
		(net 113)
	)
	(segment
		(start 158.844925 118.330075)
		(end 158.844924 118.330075)
		(width 0.148)
		(layer "In6.Cu")
		(net 113)
	)
	(segment
		(start 158.844876 126.430124)
		(end 158.844875 126.430124)
		(width 0.148)
		(layer "In6.Cu")
		(net 113)
	)
	(segment
		(start 151.35 107.15)
		(end 152.55 108.35)
		(width 0.148)
		(layer "In6.Cu")
		(net 113)
	)
	(segment
		(start 158.414849 113.36015)
		(end 158.414849 113.85)
		(width 0.148)
		(layer "In6.Cu")
		(net 113)
	)
	(segment
		(start 159.275 125.510248)
		(end 159.275 126)
		(width 0.148)
		(layer "In6.Cu")
		(net 113)
	)
	(segment
		(start 186 137.15)
		(end 186 139.6)
		(width 0.148)
		(layer "In6.Cu")
		(net 113)
	)
	(segment
		(start 159.275 122.81015)
		(end 159.275 123.3)
		(width 0.148)
		(layer "In6.Cu")
		(net 113)
	)
	(segment
		(start 158.844925 112.930075)
		(end 158.844924 112.930075)
		(width 0.148)
		(layer "In6.Cu")
		(net 113)
	)
	(segment
		(start 159.275 110.885)
		(end 159.275 112.5)
		(width 0.148)
		(layer "In6.Cu")
		(net 113)
	)
	(segment
		(start 186 139.6)
		(end 186.5 140.1)
		(width 0.148)
		(layer "In6.Cu")
		(net 113)
	)
	(segment
		(start 158.844924 122.380075)
		(end 158.844925 122.380075)
		(width 0.148)
		(layer "In6.Cu")
		(net 113)
	)
	(segment
		(start 158.844875 125.080124)
		(end 158.844876 125.080124)
		(width 0.148)
		(layer "In6.Cu")
		(net 113)
	)
	(segment
		(start 159.275 120.11015)
		(end 159.275 120.6)
		(width 0.148)
		(layer "In6.Cu")
		(net 113)
	)
	(segment
		(start 171.325 135.9)
		(end 184.75 135.9)
		(width 0.148)
		(layer "In6.Cu")
		(net 113)
	)
	(segment
		(start 186.5 140.1)
		(end 186.5 140.5)
		(width 0.148)
		(layer "In6.Cu")
		(net 113)
	)
	(segment
		(start 158.844876 123.730124)
		(end 158.844875 123.730124)
		(width 0.148)
		(layer "In6.Cu")
		(net 113)
	)
	(segment
		(start 159.275 117.41015)
		(end 159.275 117.9)
		(width 0.148)
		(layer "In6.Cu")
		(net 113)
	)
	(segment
		(start 158.844924 119.680075)
		(end 158.844925 119.680075)
		(width 0.148)
		(layer "In6.Cu")
		(net 113)
	)
	(segment
		(start 158.844925 115.630075)
		(end 158.844924 115.630075)
		(width 0.148)
		(layer "In6.Cu")
		(net 113)
	)
	(segment
		(start 159.275 130.725)
		(end 165.275 136.725)
		(width 0.148)
		(layer "In6.Cu")
		(net 113)
	)
	(segment
		(start 159.275 114.71015)
		(end 159.275 115.2)
		(width 0.148)
		(layer "In6.Cu")
		(net 113)
	)
	(segment
		(start 156.74 108.35)
		(end 159.275 110.885)
		(width 0.148)
		(layer "In6.Cu")
		(net 113)
	)
	(segment
		(start 158.844924 114.280075)
		(end 158.844925 114.280075)
		(width 0.148)
		(layer "In6.Cu")
		(net 113)
	)
	(arc
		(start 158.414849 113.85)
		(mid 158.540815 114.154109)
		(end 158.844924 114.280075)
		(width 0.148)
		(layer "In6.Cu")
		(net 113)
	)
	(arc
		(start 158.844924 118.330075)
		(mid 158.540815 118.456041)
		(end 158.414849 118.76015)
		(width 0.148)
		(layer "In6.Cu")
		(net 113)
	)
	(arc
		(start 159.275 112.5)
		(mid 159.149034 112.804109)
		(end 158.844925 112.930075)
		(width 0.148)
		(layer "In6.Cu")
		(net 113)
	)
	(arc
		(start 158.844924 115.630075)
		(mid 158.540815 115.756041)
		(end 158.414849 116.06015)
		(width 0.148)
		(layer "In6.Cu")
		(net 113)
	)
	(arc
		(start 158.414849 116.55)
		(mid 158.540815 116.854109)
		(end 158.844924 116.980075)
		(width 0.148)
		(layer "In6.Cu")
		(net 113)
	)
	(arc
		(start 159.275 126)
		(mid 159.14902 126.304144)
		(end 158.844876 126.430124)
		(width 0.148)
		(layer "In6.Cu")
		(net 113)
	)
	(arc
		(start 158.844875 126.430124)
		(mid 158.540731 126.556104)
		(end 158.414751 126.860248)
		(width 0.148)
		(layer "In6.Cu")
		(net 113)
	)
	(arc
		(start 158.844925 122.380075)
		(mid 159.149034 122.506041)
		(end 159.275 122.81015)
		(width 0.148)
		(layer "In6.Cu")
		(net 113)
	)
	(arc
		(start 159.275 120.6)
		(mid 159.149034 120.904109)
		(end 158.844925 121.030075)
		(width 0.148)
		(layer "In6.Cu")
		(net 113)
	)
	(arc
		(start 158.844876 125.080124)
		(mid 159.14902 125.206104)
		(end 159.275 125.510248)
		(width 0.148)
		(layer "In6.Cu")
		(net 113)
	)
	(arc
		(start 158.844925 116.980075)
		(mid 159.149034 117.106041)
		(end 159.275 117.41015)
		(width 0.148)
		(layer "In6.Cu")
		(net 113)
	)
	(arc
		(start 158.844925 114.280075)
		(mid 159.149034 114.406041)
		(end 159.275 114.71015)
		(width 0.148)
		(layer "In6.Cu")
		(net 113)
	)
	(arc
		(start 159.275 117.9)
		(mid 159.149034 118.204109)
		(end 158.844925 118.330075)
		(width 0.148)
		(layer "In6.Cu")
		(net 113)
	)
	(arc
		(start 158.844925 119.680075)
		(mid 159.149034 119.806041)
		(end 159.275 120.11015)
		(width 0.148)
		(layer "In6.Cu")
		(net 113)
	)
	(arc
		(start 158.414751 127.35)
		(mid 158.540731 127.654144)
		(end 158.844875 127.780124)
		(width 0.148)
		(layer "In6.Cu")
		(net 113)
	)
	(arc
		(start 158.414751 124.65)
		(mid 158.540731 124.954144)
		(end 158.844875 125.080124)
		(width 0.148)
		(layer "In6.Cu")
		(net 113)
	)
	(arc
		(start 158.844924 112.930075)
		(mid 158.540815 113.056041)
		(end 158.414849 113.36015)
		(width 0.148)
		(layer "In6.Cu")
		(net 113)
	)
	(arc
		(start 159.275 123.3)
		(mid 159.14902 123.604144)
		(end 158.844876 123.730124)
		(width 0.148)
		(layer "In6.Cu")
		(net 113)
	)
	(arc
		(start 158.844924 121.030075)
		(mid 158.540815 121.156041)
		(end 158.414849 121.46015)
		(width 0.148)
		(layer "In6.Cu")
		(net 113)
	)
	(arc
		(start 158.414849 121.95)
		(mid 158.540815 122.254109)
		(end 158.844924 122.380075)
		(width 0.148)
		(layer "In6.Cu")
		(net 113)
	)
	(arc
		(start 158.844876 127.780124)
		(mid 159.14902 127.906104)
		(end 159.275 128.210248)
		(width 0.148)
		(layer "In6.Cu")
		(net 113)
	)
	(arc
		(start 158.414849 119.25)
		(mid 158.540815 119.554109)
		(end 158.844924 119.680075)
		(width 0.148)
		(layer "In6.Cu")
		(net 113)
	)
	(arc
		(start 158.844875 123.730124)
		(mid 158.540731 123.856104)
		(end 158.414751 124.160248)
		(width 0.148)
		(layer "In6.Cu")
		(net 113)
	)
	(arc
		(start 159.275 115.2)
		(mid 159.149034 115.504109)
		(end 158.844925 115.630075)
		(width 0.148)
		(layer "In6.Cu")
		(net 113)
	)
	(segment
		(start 200.0005 140.9995)
		(end 200.500001 140.5)
		(width 0.256)
		(layer "F.Cu")
		(net 114)
	)
	(segment
		(start 215.1 106)
		(end 215.1 107.152)
		(width 0.38)
		(layer "F.Cu")
		(net 114)
	)
	(via
		(at 215.1 107.152)
		(size 0.45)
		(drill 0.1)
		(layers "F.Cu" "B.Cu")
		(remove_unused_layers yes)
		(keep_end_layers yes)
		(zone_layer_connections)
		(net 114)
	)
	(via
		(at 200.500001 140.5)
		(size 0.45)
		(drill 0.1)
		(layers "F.Cu" "B.Cu")
		(remove_unused_layers yes)
		(keep_end_layers yes)
		(zone_layer_connections)
		(net 114)
	)
	(segment
		(start 215.47 112.300294)
		(end 215.97 112.800294)
		(width 0.13)
		(layer "In6.Cu")
		(net 114)
	)
	(segment
		(start 201.1 139.281567)
		(end 201.37195 139.009617)
		(width 0.1)
		(layer "In6.Cu")
		(net 114)
	)
	(segment
		(start 212.997845 122.296856)
		(end 212.997846 122.296858)
		(width 0.13)
		(layer "In6.Cu")
		(net 114)
	)
	(segment
		(start 202.995 127.774706)
		(end 202.995 137.428024)
		(width 0.13)
		(layer "In6.Cu")
		(net 114)
	)
	(segment
		(start 215.1 107.152)
		(end 214.795 107.457)
		(width 0.13)
		(layer "In6.Cu")
		(net 114)
	)
	(segment
		(start 212.824704 122.47)
		(end 208.299706 122.47)
		(width 0.13)
		(layer "In6.Cu")
		(net 114)
	)
	(segment
		(start 213.499893 120.953355)
		(end 213.499892 120.953355)
		(width 0.13)
		(layer "In6.Cu")
		(net 114)
	)
	(segment
		(start 211.974487 120.432041)
		(end 212.997845 121.455399)
		(width 0.13)
		(layer "In6.Cu")
		(net 114)
	)
	(segment
		(start 214.341347 120.953353)
		(end 214.341348 120.953353)
		(width 0.13)
		(layer "In6.Cu")
		(net 114)
	)
	(segment
		(start 214.843396 119.609852)
		(end 214.843395 119.609852)
		(width 0.13)
		(layer "In6.Cu")
		(net 114)
	)
	(segment
		(start 214.795 108.125294)
		(end 215.92 109.250294)
		(width 0.13)
		(layer "In6.Cu")
		(net 114)
	)
	(segment
		(start 200.55 140.1)
		(end 200.741422 140.1)
		(width 0.1)
		(layer "In6.Cu")
		(net 114)
	)
	(segment
		(start 215.97 112.800294)
		(end 215.97 119.324706)
		(width 0.13)
		(layer "In6.Cu")
		(net 114)
	)
	(segment
		(start 213.318005 119.088552)
		(end 213.318005 119.088553)
		(width 0.13)
		(layer "In6.Cu")
		(net 114)
	)
	(segment
		(start 214.843395 119.609852)
		(end 213.820051 118.586508)
		(width 0.13)
		(layer "In6.Cu")
		(net 114)
	)
	(segment
		(start 215.92 109.250294)
		(end 215.92 110.649706)
		(width 0.13)
		(layer "In6.Cu")
		(net 114)
	)
	(segment
		(start 208.299706 122.47)
		(end 202.995 127.774706)
		(width 0.13)
		(layer "In6.Cu")
		(net 114)
	)
	(segment
		(start 211.974487 120.43204)
		(end 211.974487 120.432041)
		(width 0.13)
		(layer "In6.Cu")
		(net 114)
	)
	(segment
		(start 213.318005 119.088553)
		(end 214.341348 120.111896)
		(width 0.13)
		(layer "In6.Cu")
		(net 114)
	)
	(segment
		(start 200.500001 140.149999)
		(end 200.55 140.1)
		(width 0.1)
		(layer "In6.Cu")
		(net 114)
	)
	(segment
		(start 212.997846 122.296858)
		(end 212.824704 122.47)
		(width 0.13)
		(layer "In6.Cu")
		(net 114)
	)
	(segment
		(start 215.92 110.649706)
		(end 215.47 111.099706)
		(width 0.13)
		(layer "In6.Cu")
		(net 114)
	)
	(segment
		(start 215.47 111.099706)
		(end 215.47 112.300294)
		(width 0.13)
		(layer "In6.Cu")
		(net 114)
	)
	(segment
		(start 200.741422 140.1)
		(end 201.1 139.741422)
		(width 0.1)
		(layer "In6.Cu")
		(net 114)
	)
	(segment
		(start 215.97 119.324706)
		(end 215.684852 119.609852)
		(width 0.13)
		(layer "In6.Cu")
		(net 114)
	)
	(segment
		(start 200.500001 140.5)
		(end 200.500001 140.149999)
		(width 0.1)
		(layer "In6.Cu")
		(net 114)
	)
	(segment
		(start 214.341348 120.953353)
		(end 214.341349 120.953355)
		(width 0.13)
		(layer "In6.Cu")
		(net 114)
	)
	(segment
		(start 212.997846 122.296856)
		(end 212.997845 122.296856)
		(width 0.13)
		(layer "In6.Cu")
		(net 114)
	)
	(segment
		(start 201.37195 139.009617)
		(end 201.413407 139.009617)
		(width 0.1)
		(layer "In6.Cu")
		(net 114)
	)
	(segment
		(start 201.1 139.741422)
		(end 201.1 139.281567)
		(width 0.1)
		(layer "In6.Cu")
		(net 114)
	)
	(segment
		(start 202.995 137.428024)
		(end 201.413407 139.009617)
		(width 0.13)
		(layer "In6.Cu")
		(net 114)
	)
	(segment
		(start 214.795 107.457)
		(end 214.795 108.125294)
		(width 0.13)
		(layer "In6.Cu")
		(net 114)
	)
	(segment
		(start 213.499892 120.953355)
		(end 212.476533 119.929996)
		(width 0.13)
		(layer "In6.Cu")
		(net 114)
	)
	(arc
		(start 212.997845 121.455399)
		(mid 213.172117 121.876127)
		(end 212.997846 122.296856)
		(width 0.13)
		(layer "In6.Cu")
		(net 114)
	)
	(arc
		(start 214.341348 120.111896)
		(mid 214.515619 120.532625)
		(end 214.341347 120.953353)
		(width 0.13)
		(layer "In6.Cu")
		(net 114)
	)
	(arc
		(start 213.318005 118.586508)
		(mid 213.214028 118.83753)
		(end 213.318005 119.088552)
		(width 0.13)
		(layer "In6.Cu")
		(net 114)
	)
	(arc
		(start 215.684852 119.609852)
		(mid 215.264124 119.784123)
		(end 214.843396 119.609852)
		(width 0.13)
		(layer "In6.Cu")
		(net 114)
	)
	(arc
		(start 211.974487 119.929996)
		(mid 211.87051 120.181018)
		(end 211.974487 120.43204)
		(width 0.13)
		(layer "In6.Cu")
		(net 114)
	)
	(arc
		(start 213.820051 118.586508)
		(mid 213.569028 118.482531)
		(end 213.318005 118.586508)
		(width 0.13)
		(layer "In6.Cu")
		(net 114)
	)
	(arc
		(start 214.341349 120.953355)
		(mid 213.920621 121.127626)
		(end 213.499893 120.953355)
		(width 0.13)
		(layer "In6.Cu")
		(net 114)
	)
	(arc
		(start 212.476533 119.929996)
		(mid 212.22551 119.826019)
		(end 211.974487 119.929996)
		(width 0.13)
		(layer "In6.Cu")
		(net 114)
	)
	(segment
		(start 214.25 106)
		(end 214.25 107.152)
		(width 0.38)
		(layer "F.Cu")
		(net 115)
	)
	(segment
		(start 200.0005 139.9995)
		(end 200.5 139.5)
		(width 0.256)
		(layer "F.Cu")
		(net 115)
	)
	(via
		(at 200.5 139.5)
		(size 0.45)
		(drill 0.1)
		(layers "F.Cu" "B.Cu")
		(remove_unused_layers yes)
		(keep_end_layers yes)
		(zone_layer_connections)
		(net 115)
	)
	(via
		(at 214.25 107.152)
		(size 0.45)
		(drill 0.1)
		(layers "F.Cu" "B.Cu")
		(remove_unused_layers yes)
		(keep_end_layers yes)
		(zone_layer_connections)
		(net 115)
	)
	(segment
		(start 200.55 139.9)
		(end 200.658578 139.9)
		(width 0.1)
		(layer "In6.Cu")
		(net 115)
	)
	(segment
		(start 215.23 111.000294)
		(end 215.23 112.399706)
		(width 0.13)
		(layer "In6.Cu")
		(net 115)
	)
	(segment
		(start 200.5 139.5)
		(end 200.5 139.85)
		(width 0.1)
		(layer "In6.Cu")
		(net 115)
	)
	(segment
		(start 211.804782 120.601748)
		(end 212.82814 121.625106)
		(width 0.13)
		(layer "In6.Cu")
		(net 115)
	)
	(segment
		(start 213.1483 118.416804)
		(end 213.1483 118.416803)
		(width 0.13)
		(layer "In6.Cu")
		(net 115)
	)
	(segment
		(start 213.1483 119.25826)
		(end 214.171643 120.281603)
		(width 0.13)
		(layer "In6.Cu")
		(net 115)
	)
	(segment
		(start 201.429307 138.469592)
		(end 201.429306 138.469594)
		(width 0.13)
		(layer "In6.Cu")
		(net 115)
	)
	(segment
		(start 201.429306 138.28488)
		(end 201.429306 138.284879)
		(width 0.13)
		(layer "In6.Cu")
		(net 115)
	)
	(segment
		(start 212.82814 122.127152)
		(end 212.828141 122.127153)
		(width 0.13)
		(layer "In6.Cu")
		(net 115)
	)
	(segment
		(start 211.804782 119.76029)
		(end 211.804782 119.760291)
		(width 0.13)
		(layer "In6.Cu")
		(net 115)
	)
	(segment
		(start 200.9 139.198723)
		(end 201.313995 138.784728)
		(width 0.1)
		(layer "In6.Cu")
		(net 115)
	)
	(segment
		(start 214.555 108.224706)
		(end 215.68 109.349706)
		(width 0.13)
		(layer "In6.Cu")
		(net 115)
	)
	(segment
		(start 215.013101 119.440147)
		(end 213.989757 118.416803)
		(width 0.13)
		(layer "In6.Cu")
		(net 115)
	)
	(segment
		(start 213.1483 119.258259)
		(end 213.1483 119.25826)
		(width 0.13)
		(layer "In6.Cu")
		(net 115)
	)
	(segment
		(start 201.313995 138.784728)
		(end 201.313995 138.769617)
		(width 0.1)
		(layer "In6.Cu")
		(net 115)
	)
	(segment
		(start 214.171643 120.783649)
		(end 214.171644 120.78365)
		(width 0.13)
		(layer "In6.Cu")
		(net 115)
	)
	(segment
		(start 214.555 107.457)
		(end 214.555 108.224706)
		(width 0.13)
		(layer "In6.Cu")
		(net 115)
	)
	(segment
		(start 201.429306 138.654306)
		(end 201.313995 138.769617)
		(width 0.13)
		(layer "In6.Cu")
		(net 115)
	)
	(segment
		(start 202.755 127.675294)
		(end 202.755 137.328612)
		(width 0.13)
		(layer "In6.Cu")
		(net 115)
	)
	(segment
		(start 215.23 112.399706)
		(end 215.73 112.899706)
		(width 0.13)
		(layer "In6.Cu")
		(net 115)
	)
	(segment
		(start 215.73 119.225294)
		(end 215.515147 119.440147)
		(width 0.13)
		(layer "In6.Cu")
		(net 115)
	)
	(segment
		(start 215.68 109.349706)
		(end 215.68 110.550294)
		(width 0.13)
		(layer "In6.Cu")
		(net 115)
	)
	(segment
		(start 215.68 110.550294)
		(end 215.23 111.000294)
		(width 0.13)
		(layer "In6.Cu")
		(net 115)
	)
	(segment
		(start 202.755 137.328612)
		(end 201.896864 138.186752)
		(width 0.13)
		(layer "In6.Cu")
		(net 115)
	)
	(segment
		(start 212.725294 122.23)
		(end 208.200294 122.23)
		(width 0.13)
		(layer "In6.Cu")
		(net 115)
	)
	(segment
		(start 208.200294 122.23)
		(end 202.755 127.675294)
		(width 0.13)
		(layer "In6.Cu")
		(net 115)
	)
	(segment
		(start 200.658578 139.9)
		(end 200.9 139.658578)
		(width 0.1)
		(layer "In6.Cu")
		(net 115)
	)
	(segment
		(start 212.828141 122.127153)
		(end 212.725294 122.23)
		(width 0.13)
		(layer "In6.Cu")
		(net 115)
	)
	(segment
		(start 201.527438 138.186749)
		(end 201.429306 138.28488)
		(width 0.13)
		(layer "In6.Cu")
		(net 115)
	)
	(segment
		(start 213.669598 120.78365)
		(end 212.646239 119.760291)
		(width 0.13)
		(layer "In6.Cu")
		(net 115)
	)
	(segment
		(start 211.804782 120.601747)
		(end 211.804782 120.601748)
		(width 0.13)
		(layer "In6.Cu")
		(net 115)
	)
	(segment
		(start 215.73 112.899706)
		(end 215.73 119.225294)
		(width 0.13)
		(layer "In6.Cu")
		(net 115)
	)
	(segment
		(start 200.9 139.658578)
		(end 200.9 139.198723)
		(width 0.1)
		(layer "In6.Cu")
		(net 115)
	)
	(segment
		(start 200.5 139.85)
		(end 200.55 139.9)
		(width 0.1)
		(layer "In6.Cu")
		(net 115)
	)
	(segment
		(start 201.712151 138.186751)
		(end 201.712151 138.18675)
		(width 0.13)
		(layer "In6.Cu")
		(net 115)
	)
	(segment
		(start 214.25 107.152)
		(end 214.555 107.457)
		(width 0.13)
		(layer "In6.Cu")
		(net 115)
	)
	(arc
		(start 201.896864 138.186752)
		(mid 201.804507 138.225007)
		(end 201.712151 138.186751)
		(width 0.13)
		(layer "In6.Cu")
		(net 115)
	)
	(arc
		(start 213.1483 118.416803)
		(mid 212.974029 118.837531)
		(end 213.1483 119.258259)
		(width 0.13)
		(layer "In6.Cu")
		(net 115)
	)
	(arc
		(start 201.712151 138.18675)
		(mid 201.619795 138.148494)
		(end 201.527438 138.186749)
		(width 0.13)
		(layer "In6.Cu")
		(net 115)
	)
	(arc
		(start 214.171644 120.78365)
		(mid 213.920621 120.887627)
		(end 213.669598 120.78365)
		(width 0.13)
		(layer "In6.Cu")
		(net 115)
	)
	(arc
		(start 212.646239 119.760291)
		(mid 212.225511 119.586019)
		(end 211.804782 119.76029)
		(width 0.13)
		(layer "In6.Cu")
		(net 115)
	)
	(arc
		(start 215.515147 119.440147)
		(mid 215.264124 119.544124)
		(end 215.013101 119.440147)
		(width 0.13)
		(layer "In6.Cu")
		(net 115)
	)
	(arc
		(start 213.989757 118.416803)
		(mid 213.569028 118.242532)
		(end 213.1483 118.416804)
		(width 0.13)
		(layer "In6.Cu")
		(net 115)
	)
	(arc
		(start 214.171643 120.281603)
		(mid 214.27562 120.532626)
		(end 214.171643 120.783649)
		(width 0.13)
		(layer "In6.Cu")
		(net 115)
	)
	(arc
		(start 201.429306 138.469594)
		(mid 201.467562 138.561949)
		(end 201.429306 138.654306)
		(width 0.13)
		(layer "In6.Cu")
		(net 115)
	)
	(arc
		(start 211.804782 119.760291)
		(mid 211.630511 120.181019)
		(end 211.804782 120.601747)
		(width 0.13)
		(layer "In6.Cu")
		(net 115)
	)
	(arc
		(start 201.429306 138.284879)
		(mid 201.391051 138.377236)
		(end 201.429307 138.469592)
		(width 0.13)
		(layer "In6.Cu")
		(net 115)
	)
	(arc
		(start 212.82814 121.625106)
		(mid 212.932117 121.876129)
		(end 212.82814 122.127152)
		(width 0.13)
		(layer "In6.Cu")
		(net 115)
	)
	(segment
		(start 183.9995 141.9995)
		(end 183.5 141.5)
		(width 0.256)
		(layer "F.Cu")
		(net 116)
	)
	(segment
		(start 147.1 106)
		(end 147.1 107.152)
		(width 0.38)
		(layer "F.Cu")
		(net 116)
	)
	(via
		(at 147.1 107.152)
		(size 0.45)
		(drill 0.1)
		(layers "F.Cu" "B.Cu")
		(remove_unused_layers yes)
		(keep_end_layers yes)
		(zone_layer_connections)
		(net 116)
	)
	(via
		(at 183.5 141.5)
		(size 0.45)
		(drill 0.1)
		(layers "F.Cu" "B.Cu")
		(remove_unused_layers yes)
		(keep_end_layers yes)
		(zone_layer_connections)
		(net 116)
	)
	(segment
		(start 147.635 125.475)
		(end 147.622744 125.475)
		(width 0.148)
		(layer "In6.Cu")
		(net 116)
	)
	(segment
		(start 147.635 118.675)
		(end 147.622744 118.675)
		(width 0.148)
		(layer "In6.Cu")
		(net 116)
	)
	(segment
		(start 148.06 126.12)
		(end 148.06 125.9)
		(width 0.148)
		(layer "In6.Cu")
		(net 116)
	)
	(segment
		(start 147.622744 116.125)
		(end 147.635 116.125)
		(width 0.148)
		(layer "In6.Cu")
		(net 116)
	)
	(segment
		(start 147.635 123.775)
		(end 147.622744 123.775)
		(width 0.148)
		(layer "In6.Cu")
		(net 116)
	)
	(segment
		(start 148.06 115.335)
		(end 147.1 114.375)
		(width 0.148)
		(layer "In6.Cu")
		(net 116)
	)
	(segment
		(start 147.1 107.925)
		(end 147.1 107.15)
		(width 0.148)
		(layer "In6.Cu")
		(net 116)
	)
	(segment
		(start 147.635 120.375)
		(end 147.622744 120.375)
		(width 0.148)
		(layer "In6.Cu")
		(net 116)
	)
	(segment
		(start 148.06 115.7)
		(end 148.06 115.335)
		(width 0.148)
		(layer "In6.Cu")
		(net 116)
	)
	(segment
		(start 147.1 114.375)
		(end 147.1 110.925)
		(width 0.148)
		(layer "In6.Cu")
		(net 116)
	)
	(segment
		(start 147.622744 119.525)
		(end 147.635 119.525)
		(width 0.148)
		(layer "In6.Cu")
		(net 116)
	)
	(segment
		(start 147.1 110.925)
		(end 147.85 110.175)
		(width 0.148)
		(layer "In6.Cu")
		(net 116)
	)
	(segment
		(start 147.85 110.175)
		(end 147.85 108.675)
		(width 0.148)
		(layer "In6.Cu")
		(net 116)
	)
	(segment
		(start 150.23 131.455)
		(end 150.23 128.29)
		(width 0.148)
		(layer "In6.Cu")
		(net 116)
	)
	(segment
		(start 160.775 142)
		(end 150.23 131.455)
		(width 0.148)
		(layer "In6.Cu")
		(net 116)
	)
	(segment
		(start 147.635 116.975)
		(end 147.622744 116.975)
		(width 0.148)
		(layer "In6.Cu")
		(net 116)
	)
	(segment
		(start 147.622744 122.925)
		(end 147.635 122.925)
		(width 0.148)
		(layer "In6.Cu")
		(net 116)
	)
	(segment
		(start 150.23 128.29)
		(end 148.06 126.12)
		(width 0.148)
		(layer "In6.Cu")
		(net 116)
	)
	(segment
		(start 147.635 122.075)
		(end 147.622744 122.075)
		(width 0.148)
		(layer "In6.Cu")
		(net 116)
	)
	(segment
		(start 183.5 141.5)
		(end 183 142)
		(width 0.148)
		(layer "In6.Cu")
		(net 116)
	)
	(segment
		(start 147.622744 121.225)
		(end 147.635 121.225)
		(width 0.148)
		(layer "In6.Cu")
		(net 116)
	)
	(segment
		(start 147.85 108.675)
		(end 147.1 107.925)
		(width 0.148)
		(layer "In6.Cu")
		(net 116)
	)
	(segment
		(start 183 142)
		(end 160.775 142)
		(width 0.148)
		(layer "In6.Cu")
		(net 116)
	)
	(segment
		(start 147.622744 124.625)
		(end 147.635 124.625)
		(width 0.148)
		(layer "In6.Cu")
		(net 116)
	)
	(segment
		(start 147.622744 117.825)
		(end 147.635 117.825)
		(width 0.148)
		(layer "In6.Cu")
		(net 116)
	)
	(arc
		(start 147.635 119.525)
		(mid 147.93552 119.40052)
		(end 148.06 119.1)
		(width 0.148)
		(layer "In6.Cu")
		(net 116)
	)
	(arc
		(start 147.635 117.825)
		(mid 147.93552 117.70052)
		(end 148.06 117.4)
		(width 0.148)
		(layer "In6.Cu")
		(net 116)
	)
	(arc
		(start 147.635 121.225)
		(mid 147.93552 121.10052)
		(end 148.06 120.8)
		(width 0.148)
		(layer "In6.Cu")
		(net 116)
	)
	(arc
		(start 147.197744 119.95)
		(mid 147.322224 119.64948)
		(end 147.622744 119.525)
		(width 0.148)
		(layer "In6.Cu")
		(net 116)
	)
	(arc
		(start 147.622744 122.075)
		(mid 147.322224 121.95052)
		(end 147.197744 121.65)
		(width 0.148)
		(layer "In6.Cu")
		(net 116)
	)
	(arc
		(start 147.635 122.925)
		(mid 147.93552 122.80052)
		(end 148.06 122.5)
		(width 0.148)
		(layer "In6.Cu")
		(net 116)
	)
	(arc
		(start 148.06 125.9)
		(mid 147.93552 125.59948)
		(end 147.635 125.475)
		(width 0.148)
		(layer "In6.Cu")
		(net 116)
	)
	(arc
		(start 147.622744 118.675)
		(mid 147.322224 118.55052)
		(end 147.197744 118.25)
		(width 0.148)
		(layer "In6.Cu")
		(net 116)
	)
	(arc
		(start 147.197744 118.25)
		(mid 147.322224 117.94948)
		(end 147.622744 117.825)
		(width 0.148)
		(layer "In6.Cu")
		(net 116)
	)
	(arc
		(start 147.197744 121.65)
		(mid 147.322224 121.34948)
		(end 147.622744 121.225)
		(width 0.148)
		(layer "In6.Cu")
		(net 116)
	)
	(arc
		(start 148.06 124.2)
		(mid 147.93552 123.89948)
		(end 147.635 123.775)
		(width 0.148)
		(layer "In6.Cu")
		(net 116)
	)
	(arc
		(start 148.06 117.4)
		(mid 147.93552 117.09948)
		(end 147.635 116.975)
		(width 0.148)
		(layer "In6.Cu")
		(net 116)
	)
	(arc
		(start 147.197744 125.05)
		(mid 147.322224 124.74948)
		(end 147.622744 124.625)
		(width 0.148)
		(layer "In6.Cu")
		(net 116)
	)
	(arc
		(start 147.197744 123.35)
		(mid 147.322224 123.04948)
		(end 147.622744 122.925)
		(width 0.148)
		(layer "In6.Cu")
		(net 116)
	)
	(arc
		(start 148.06 120.8)
		(mid 147.93552 120.49948)
		(end 147.635 120.375)
		(width 0.148)
		(layer "In6.Cu")
		(net 116)
	)
	(arc
		(start 147.635 124.625)
		(mid 147.93552 124.50052)
		(end 148.06 124.2)
		(width 0.148)
		(layer "In6.Cu")
		(net 116)
	)
	(arc
		(start 148.06 122.5)
		(mid 147.93552 122.19948)
		(end 147.635 122.075)
		(width 0.148)
		(layer "In6.Cu")
		(net 116)
	)
	(arc
		(start 147.197744 116.55)
		(mid 147.322224 116.24948)
		(end 147.622744 116.125)
		(width 0.148)
		(layer "In6.Cu")
		(net 116)
	)
	(arc
		(start 147.622744 123.775)
		(mid 147.322224 123.65052)
		(end 147.197744 123.35)
		(width 0.148)
		(layer "In6.Cu")
		(net 116)
	)
	(arc
		(start 147.635 116.125)
		(mid 147.93552 116.00052)
		(end 148.06 115.7)
		(width 0.148)
		(layer "In6.Cu")
		(net 116)
	)
	(arc
		(start 147.622744 120.375)
		(mid 147.322224 120.25052)
		(end 147.197744 119.95)
		(width 0.148)
		(layer "In6.Cu")
		(net 116)
	)
	(arc
		(start 147.622744 125.475)
		(mid 147.322224 125.35052)
		(end 147.197744 125.05)
		(width 0.148)
		(layer "In6.Cu")
		(net 116)
	)
	(arc
		(start 148.06 119.1)
		(mid 147.93552 118.79948)
		(end 147.635 118.675)
		(width 0.148)
		(layer "In6.Cu")
		(net 116)
	)
	(arc
		(start 147.622744 116.975)
		(mid 147.322224 116.85052)
		(end 147.197744 116.55)
		(width 0.148)
		(layer "In6.Cu")
		(net 116)
	)
	(segment
		(start 184.999501 142.9995)
		(end 184.5 142.5)
		(width 0.256)
		(layer "F.Cu")
		(net 117)
	)
	(segment
		(start 145.4 106)
		(end 145.4 107.152)
		(width 0.38)
		(layer "F.Cu")
		(net 117)
	)
	(via
		(at 145.4 107.152)
		(size 0.45)
		(drill 0.1)
		(layers "F.Cu" "B.Cu")
		(remove_unused_layers yes)
		(keep_end_layers yes)
		(zone_layer_connections)
		(net 117)
	)
	(via
		(at 184.5 142.5)
		(size 0.45)
		(drill 0.1)
		(layers "F.Cu" "B.Cu")
		(remove_unused_layers yes)
		(keep_end_layers yes)
		(zone_layer_connections)
		(net 117)
	)
	(segment
		(start 159.175 144)
		(end 183.564272 144)
		(width 0.148)
		(layer "In6.Cu")
		(net 117)
	)
	(segment
		(start 183.899 143.101)
		(end 184.5 142.5)
		(width 0.148)
		(layer "In6.Cu")
		(net 117)
	)
	(segment
		(start 144.55 110.325)
		(end 145.35 111.125)
		(width 0.148)
		(layer "In6.Cu")
		(net 117)
	)
	(segment
		(start 144.95 129.775)
		(end 159.175 144)
		(width 0.148)
		(layer "In6.Cu")
		(net 117)
	)
	(segment
		(start 183.899 143.665272)
		(end 183.899 143.101)
		(width 0.148)
		(layer "In6.Cu")
		(net 117)
	)
	(segment
		(start 145.35 111.125)
		(end 145.35 112.5)
		(width 0.148)
		(layer "In6.Cu")
		(net 117)
	)
	(segment
		(start 145.35 112.5)
		(end 144.95 112.9)
		(width 0.148)
		(layer "In6.Cu")
		(net 117)
	)
	(segment
		(start 145.4 108.025)
		(end 144.55 108.875)
		(width 0.148)
		(layer "In6.Cu")
		(net 117)
	)
	(segment
		(start 144.55 108.875)
		(end 144.55 110.325)
		(width 0.148)
		(layer "In6.Cu")
		(net 117)
	)
	(segment
		(start 145.4 107.15)
		(end 145.4 108.025)
		(width 0.148)
		(layer "In6.Cu")
		(net 117)
	)
	(segment
		(start 144.95 112.9)
		(end 144.95 129.775)
		(width 0.148)
		(layer "In6.Cu")
		(net 117)
	)
	(segment
		(start 183.564272 144)
		(end 183.899 143.665272)
		(width 0.148)
		(layer "In6.Cu")
		(net 117)
	)
	(segment
		(start 182.9995 142.9995)
		(end 182.5 142.5)
		(width 0.256)
		(layer "F.Cu")
		(net 118)
	)
	(segment
		(start 143.7 106)
		(end 143.7 107.152)
		(width 0.38)
		(layer "F.Cu")
		(net 118)
	)
	(via
		(at 182.5 142.5)
		(size 0.45)
		(drill 0.1)
		(layers "F.Cu" "B.Cu")
		(remove_unused_layers yes)
		(keep_end_layers yes)
		(zone_layer_connections)
		(net 118)
	)
	(via
		(at 143.7 107.152)
		(size 0.45)
		(drill 0.1)
		(layers "F.Cu" "B.Cu")
		(remove_unused_layers yes)
		(keep_end_layers yes)
		(zone_layer_connections)
		(net 118)
	)
	(segment
		(start 183 142)
		(end 185.75 142)
		(width 0.148)
		(layer "In4.Cu")
		(net 118)
	)
	(segment
		(start 185.75 142)
		(end 186 141.75)
		(width 0.148)
		(layer "In4.Cu")
		(net 118)
	)
	(segment
		(start 174.59 113.35)
		(end 146.32 113.35)
		(width 0.148)
		(layer "In4.Cu")
		(net 118)
	)
	(segment
		(start 146.32 113.35)
		(end 145.47 112.5)
		(width 0.148)
		(layer "In4.Cu")
		(net 118)
	)
	(segment
		(start 144.6865 110.0615)
		(end 144.6865 108.1385)
		(width 0.148)
		(layer "In4.Cu")
		(net 118)
	)
	(segment
		(start 186 141.75)
		(end 186 124.76)
		(width 0.148)
		(layer "In4.Cu")
		(net 118)
	)
	(segment
		(start 144.6865 108.1385)
		(end 143.7 107.152)
		(width 0.148)
		(layer "In4.Cu")
		(net 118)
	)
	(segment
		(start 145.47 112.5)
		(end 145.47 110.845)
		(width 0.148)
		(layer "In4.Cu")
		(net 118)
	)
	(segment
		(start 145.47 110.845)
		(end 144.6865 110.0615)
		(width 0.148)
		(layer "In4.Cu")
		(net 118)
	)
	(segment
		(start 182.5 142.5)
		(end 183 142)
		(width 0.148)
		(layer "In4.Cu")
		(net 118)
	)
	(segment
		(start 186 124.76)
		(end 174.59 113.35)
		(width 0.148)
		(layer "In4.Cu")
		(net 118)
	)
	(segment
		(start 142 106)
		(end 142 107.152)
		(width 0.38)
		(layer "F.Cu")
		(net 119)
	)
	(segment
		(start 183.9995 140.9995)
		(end 183.5 140.499999)
		(width 0.256)
		(layer "F.Cu")
		(net 119)
	)
	(via
		(at 183.5 140.499999)
		(size 0.45)
		(drill 0.1)
		(layers "F.Cu" "B.Cu")
		(remove_unused_layers yes)
		(keep_end_layers yes)
		(zone_layer_connections)
		(net 119)
	)
	(via
		(at 142 107.152)
		(size 0.45)
		(drill 0.1)
		(layers "F.Cu" "B.Cu")
		(remove_unused_layers yes)
		(keep_end_layers yes)
		(zone_layer_connections)
		(net 119)
	)
	(segment
		(start 157.850276 115.930275)
		(end 157.850276 115.930276)
		(width 0.148)
		(layer "In4.Cu")
		(net 119)
	)
	(segment
		(start 159.800276 115.930276)
		(end 159.800276 115.930275)
		(width 0.148)
		(layer "In4.Cu")
		(net 119)
	)
	(segment
		(start 161.2 116.17)
		(end 160.04 116.17)
		(width 0.148)
		(layer "In4.Cu")
		(net 119)
	)
	(segment
		(start 159.560552 115.690551)
		(end 158.09 115.690551)
		(width 0.148)
		(layer "In4.Cu")
		(net 119)
	)
	(segment
		(start 161.77 115.6)
		(end 161.2 116.17)
		(width 0.148)
		(layer "In4.Cu")
		(net 119)
	)
	(segment
		(start 172.43 115.6)
		(end 161.77 115.6)
		(width 0.148)
		(layer "In4.Cu")
		(net 119)
	)
	(segment
		(start 142.575 107.727)
		(end 142 107.152)
		(width 0.148)
		(layer "In4.Cu")
		(net 119)
	)
	(segment
		(start 184.05 140.15)
		(end 184.05 127.22)
		(width 0.148)
		(layer "In4.Cu")
		(net 119)
	)
	(segment
		(start 184.05 127.22)
		(end 172.43 115.6)
		(width 0.148)
		(layer "In4.Cu")
		(net 119)
	)
	(segment
		(start 142 111.075)
		(end 142.575 110.5)
		(width 0.148)
		(layer "In4.Cu")
		(net 119)
	)
	(segment
		(start 142.575 110.5)
		(end 142.575 107.727)
		(width 0.148)
		(layer "In4.Cu")
		(net 119)
	)
	(segment
		(start 157.610552 116.17)
		(end 145.87 116.17)
		(width 0.148)
		(layer "In4.Cu")
		(net 119)
	)
	(segment
		(start 145.87 116.17)
		(end 142 112.3)
		(width 0.148)
		(layer "In4.Cu")
		(net 119)
	)
	(segment
		(start 183.700001 140.499999)
		(end 184.05 140.15)
		(width 0.148)
		(layer "In4.Cu")
		(net 119)
	)
	(segment
		(start 183.5 140.499999)
		(end 183.700001 140.499999)
		(width 0.148)
		(layer "In4.Cu")
		(net 119)
	)
	(segment
		(start 142 112.3)
		(end 142 111.075)
		(width 0.148)
		(layer "In4.Cu")
		(net 119)
	)
	(arc
		(start 159.800276 115.930275)
		(mid 159.730062 115.760765)
		(end 159.560552 115.690551)
		(width 0.148)
		(layer "In4.Cu")
		(net 119)
	)
	(arc
		(start 157.850276 115.930276)
		(mid 157.780062 116.099786)
		(end 157.610552 116.17)
		(width 0.148)
		(layer "In4.Cu")
		(net 119)
	)
	(arc
		(start 158.09 115.690551)
		(mid 157.92049 115.760765)
		(end 157.850276 115.930275)
		(width 0.148)
		(layer "In4.Cu")
		(net 119)
	)
	(arc
		(start 160.04 116.17)
		(mid 159.87049 116.099786)
		(end 159.800276 115.930276)
		(width 0.148)
		(layer "In4.Cu")
		(net 119)
	)
	(segment
		(start 205.75 106)
		(end 205.75 107.152)
		(width 0.38)
		(layer "F.Cu")
		(net 120)
	)
	(segment
		(start 192.0005 146.9995)
		(end 192.5 146.5)
		(width 0.256)
		(layer "F.Cu")
		(net 120)
	)
	(via
		(at 192.5 146.5)
		(size 0.45)
		(drill 0.1)
		(layers "F.Cu" "B.Cu")
		(remove_unused_layers yes)
		(keep_end_layers yes)
		(zone_layer_connections)
		(net 120)
	)
	(via
		(at 205.75 107.152)
		(size 0.45)
		(drill 0.1)
		(layers "F.Cu" "B.Cu")
		(remove_unused_layers yes)
		(keep_end_layers yes)
		(zone_layer_connections)
		(net 120)
	)
	(segment
		(start 213.28 108.949706)
		(end 213.28 106.199706)
		(width 0.13)
		(layer "In4.Cu")
		(net 120)
	)
	(segment
		(start 205.739008 106.165701)
		(end 205.846655 106.273347)
		(width 0.13)
		(layer "In4.Cu")
		(net 120)
	)
	(segment
		(start 194.709078 145.8995)
		(end 194.9 145.708578)
		(width 0.1)
		(layer "In4.Cu")
		(net 120)
	)
	(segment
		(start 193.209078 145.8995)
		(end 194.709078 145.8995)
		(width 0.1)
		(layer "In4.Cu")
		(net 120)
	)
	(segment
		(start 205.972353 105.930699)
		(end 205.972353 105.932353)
		(width 0.13)
		(layer "In4.Cu")
		(net 120)
	)
	(segment
		(start 194.881011 137.949283)
		(end 214.88 117.950294)
		(width 0.13)
		(layer "In4.Cu")
		(net 120)
	)
	(segment
		(start 214.88 117.950294)
		(end 214.88 110.549706)
		(width 0.13)
		(layer "In4.Cu")
		(net 120)
	)
	(segment
		(start 192.8205 146.4995)
		(end 192.9305 146.3895)
		(width 0.1)
		(layer "In4.Cu")
		(net 120)
	)
	(segment
		(start 205.75 107.152)
		(end 205.445 106.847)
		(width 0.13)
		(layer "In4.Cu")
		(net 120)
	)
	(segment
		(start 192.9305 146.178078)
		(end 193.209078 145.8995)
		(width 0.1)
		(layer "In4.Cu")
		(net 120)
	)
	(segment
		(start 206.08 106.273346)
		(end 206.080001 106.273345)
		(width 0.13)
		(layer "In4.Cu")
		(net 120)
	)
	(segment
		(start 212.700294 105.62)
		(end 206.049727 105.62)
		(width 0.13)
		(layer "In4.Cu")
		(net 120)
	)
	(segment
		(start 192.56473 146.5)
		(end 192.56523 146.4995)
		(width 0.1)
		(layer "In4.Cu")
		(net 120)
	)
	(segment
		(start 205.972353 105.697353)
		(end 205.945376 105.72433)
		(width 0.13)
		(layer "In4.Cu")
		(net 120)
	)
	(segment
		(start 192.9305 146.3895)
		(end 192.9305 146.178078)
		(width 0.1)
		(layer "In4.Cu")
		(net 120)
	)
	(segment
		(start 214.88 110.549706)
		(end 213.28 108.949706)
		(width 0.13)
		(layer "In4.Cu")
		(net 120)
	)
	(segment
		(start 205.972353 105.930699)
		(end 205.945396 105.903754)
		(width 0.13)
		(layer "In4.Cu")
		(net 120)
	)
	(segment
		(start 194.9 145.708578)
		(end 194.9 138.215573)
		(width 0.1)
		(layer "In4.Cu")
		(net 120)
	)
	(segment
		(start 205.991127 105.678579)
		(end 205.972353 105.697353)
		(width 0.13)
		(layer "In4.Cu")
		(net 120)
	)
	(segment
		(start 192.5 146.5)
		(end 192.56473 146.5)
		(width 0.1)
		(layer "In4.Cu")
		(net 120)
	)
	(segment
		(start 205.50358 106.166127)
		(end 205.505662 106.164045)
		(width 0.13)
		(layer "In4.Cu")
		(net 120)
	)
	(segment
		(start 194.881011 138.196584)
		(end 194.881011 137.949283)
		(width 0.13)
		(layer "In4.Cu")
		(net 120)
	)
	(segment
		(start 194.9 138.215573)
		(end 194.881011 138.196584)
		(width 0.1)
		(layer "In4.Cu")
		(net 120)
	)
	(segment
		(start 205.505662 106.164045)
		(end 205.505663 106.164046)
		(width 0.13)
		(layer "In4.Cu")
		(net 120)
	)
	(segment
		(start 213.28 106.199706)
		(end 212.700294 105.62)
		(width 0.13)
		(layer "In4.Cu")
		(net 120)
	)
	(segment
		(start 192.56523 146.4995)
		(end 192.8205 146.4995)
		(width 0.1)
		(layer "In4.Cu")
		(net 120)
	)
	(segment
		(start 205.445 106.847)
		(end 205.445 106.30755)
		(width 0.13)
		(layer "In4.Cu")
		(net 120)
	)
	(segment
		(start 205.991127 105.678579)
		(end 206.049727 105.62)
		(width 0.13)
		(layer "In4.Cu")
		(net 120)
	)
	(segment
		(start 205.972353 105.932353)
		(end 206.08 106.04)
		(width 0.13)
		(layer "In4.Cu")
		(net 120)
	)
	(segment
		(start 205.739008 106.164047)
		(end 205.739008 106.165701)
		(width 0.13)
		(layer "In4.Cu")
		(net 120)
	)
	(arc
		(start 205.846655 106.273347)
		(mid 205.963328 106.321674)
		(end 206.08 106.273346)
		(width 0.13)
		(layer "In4.Cu")
		(net 120)
	)
	(arc
		(start 205.445 106.30755)
		(mid 205.460224 106.231012)
		(end 205.50358 106.166127)
		(width 0.13)
		(layer "In4.Cu")
		(net 120)
	)
	(arc
		(start 205.945376 105.72433)
		(mid 205.90822 105.814046)
		(end 205.945396 105.903754)
		(width 0.13)
		(layer "In4.Cu")
		(net 120)
	)
	(arc
		(start 206.080001 106.273345)
		(mid 206.128328 106.156672)
		(end 206.08 106.04)
		(width 0.13)
		(layer "In4.Cu")
		(net 120)
	)
	(arc
		(start 205.505663 106.164046)
		(mid 205.622336 106.115719)
		(end 205.739008 106.164047)
		(width 0.13)
		(layer "In4.Cu")
		(net 120)
	)
	(segment
		(start 193.0005 146.9995)
		(end 193.5 146.5)
		(width 0.256)
		(layer "F.Cu")
		(net 121)
	)
	(segment
		(start 204.9 106)
		(end 204.9 107.152)
		(width 0.38)
		(layer "F.Cu")
		(net 121)
	)
	(via
		(at 193.5 146.5)
		(size 0.45)
		(drill 0.1)
		(layers "F.Cu" "B.Cu")
		(remove_unused_layers yes)
		(keep_end_layers yes)
		(zone_layer_connections)
		(net 121)
	)
	(via
		(at 204.9 107.152)
		(size 0.45)
		(drill 0.1)
		(layers "F.Cu" "B.Cu")
		(remove_unused_layers yes)
		(keep_end_layers yes)
		(zone_layer_connections)
		(net 121)
	)
	(segment
		(start 215.12 118.049706)
		(end 195.121011 138.048695)
		(width 0.13)
		(layer "In4.Cu")
		(net 121)
	)
	(segment
		(start 205.205 106.125294)
		(end 205.950294 105.38)
		(width 0.13)
		(layer "In4.Cu")
		(net 121)
	)
	(segment
		(start 193.1605 146.230922)
		(end 193.291922 146.0995)
		(width 0.1)
		(layer "In4.Cu")
		(net 121)
	)
	(segment
		(start 205.950294 105.38)
		(end 212.799706 105.38)
		(width 0.13)
		(layer "In4.Cu")
		(net 121)
	)
	(segment
		(start 194.791922 146.0995)
		(end 195.1 145.791422)
		(width 0.1)
		(layer "In4.Cu")
		(net 121)
	)
	(segment
		(start 195.1 145.791422)
		(end 195.1 138.217595)
		(width 0.1)
		(layer "In4.Cu")
		(net 121)
	)
	(segment
		(start 215.12 110.450294)
		(end 215.12 118.049706)
		(width 0.13)
		(layer "In4.Cu")
		(net 121)
	)
	(segment
		(start 193.271 146.5)
		(end 193.1605 146.3895)
		(width 0.1)
		(layer "In4.Cu")
		(net 121)
	)
	(segment
		(start 195.121011 138.048695)
		(end 195.121011 138.196584)
		(width 0.13)
		(layer "In4.Cu")
		(net 121)
	)
	(segment
		(start 193.291922 146.0995)
		(end 194.791922 146.0995)
		(width 0.1)
		(layer "In4.Cu")
		(net 121)
	)
	(segment
		(start 205.205 106.847)
		(end 205.205 106.125294)
		(width 0.13)
		(layer "In4.Cu")
		(net 121)
	)
	(segment
		(start 213.52 106.100294)
		(end 213.52 108.850294)
		(width 0.13)
		(layer "In4.Cu")
		(net 121)
	)
	(segment
		(start 193.1605 146.3895)
		(end 193.1605 146.230922)
		(width 0.1)
		(layer "In4.Cu")
		(net 121)
	)
	(segment
		(start 195.1 138.217595)
		(end 195.121011 138.196584)
		(width 0.1)
		(layer "In4.Cu")
		(net 121)
	)
	(segment
		(start 213.52 108.850294)
		(end 215.12 110.450294)
		(width 0.13)
		(layer "In4.Cu")
		(net 121)
	)
	(segment
		(start 204.9 107.152)
		(end 205.205 106.847)
		(width 0.13)
		(layer "In4.Cu")
		(net 121)
	)
	(segment
		(start 193.5 146.5)
		(end 193.271 146.5)
		(width 0.1)
		(layer "In4.Cu")
		(net 121)
	)
	(segment
		(start 212.799706 105.38)
		(end 213.52 106.100294)
		(width 0.13)
		(layer "In4.Cu")
		(net 121)
	)
	(segment
		(start 137.75 106)
		(end 137.75 107.152)
		(width 0.38)
		(layer "F.Cu")
		(net 122)
	)
	(segment
		(start 181.9995 139.9995)
		(end 181.499999 139.500001)
		(width 0.256)
		(layer "F.Cu")
		(net 122)
	)
	(via
		(at 181.499999 139.500001)
		(size 0.45)
		(drill 0.1)
		(layers "F.Cu" "B.Cu")
		(remove_unused_layers yes)
		(keep_end_layers yes)
		(zone_layer_connections)
		(net 122)
	)
	(via
		(at 137.75 107.152)
		(size 0.45)
		(drill 0.1)
		(layers "F.Cu" "B.Cu")
		(remove_unused_layers yes)
		(keep_end_layers yes)
		(zone_layer_connections)
		(net 122)
	)
	(segment
		(start 149.75 121.211045)
		(end 149.75 121.25)
		(width 0.148)
		(layer "In4.Cu")
		(net 122)
	)
	(segment
		(start 181.21 131.98)
		(end 181.21 139.210002)
		(width 0.148)
		(layer "In4.Cu")
		(net 122)
	)
	(segment
		(start 137.75 108.775)
		(end 139.95 110.975)
		(width 0.148)
		(layer "In4.Cu")
		(net 122)
	)
	(segment
		(start 154.925 121.825)
		(end 156.125 121.825)
		(width 0.148)
		(layer "In4.Cu")
		(net 122)
	)
	(segment
		(start 169.95 120.72)
		(end 181.21 131.98)
		(width 0.148)
		(layer "In4.Cu")
		(net 122)
	)
	(segment
		(start 147.525 121.825)
		(end 148.025 121.825)
		(width 0.148)
		(layer "In4.Cu")
		(net 122)
	)
	(segment
		(start 153.2 121.25)
		(end 153.2 121.211029)
		(width 0.148)
		(layer "In4.Cu")
		(net 122)
	)
	(segment
		(start 137.75 107.15)
		(end 137.75 108.775)
		(width 0.148)
		(layer "In4.Cu")
		(net 122)
	)
	(segment
		(start 150.9 121.25)
		(end 150.9 121.211045)
		(width 0.148)
		(layer "In4.Cu")
		(net 122)
	)
	(segment
		(start 148.6 121.25)
		(end 148.6 121.211045)
		(width 0.148)
		(layer "In4.Cu")
		(net 122)
	)
	(segment
		(start 154.35 121.211029)
		(end 154.35 121.25)
		(width 0.148)
		(layer "In4.Cu")
		(net 122)
	)
	(segment
		(start 139.95 114.25)
		(end 147.525 121.825)
		(width 0.148)
		(layer "In4.Cu")
		(net 122)
	)
	(segment
		(start 159.72 121.825)
		(end 160.825 120.72)
		(width 0.148)
		(layer "In4.Cu")
		(net 122)
	)
	(segment
		(start 139.95 110.975)
		(end 139.95 114.25)
		(width 0.148)
		(layer "In4.Cu")
		(net 122)
	)
	(segment
		(start 156.125 121.825)
		(end 159.72 121.825)
		(width 0.148)
		(layer "In4.Cu")
		(net 122)
	)
	(segment
		(start 152.05 121.211045)
		(end 152.05 121.25)
		(width 0.148)
		(layer "In4.Cu")
		(net 122)
	)
	(segment
		(start 181.21 139.210002)
		(end 181.499999 139.500001)
		(width 0.148)
		(layer "In4.Cu")
		(net 122)
	)
	(segment
		(start 160.825 120.72)
		(end 169.95 120.72)
		(width 0.148)
		(layer "In4.Cu")
		(net 122)
	)
	(arc
		(start 151.475 120.636045)
		(mid 151.881586 120.804459)
		(end 152.05 121.211045)
		(width 0.148)
		(layer "In4.Cu")
		(net 122)
	)
	(arc
		(start 152.625 121.825)
		(mid 153.031586 121.656586)
		(end 153.2 121.25)
		(width 0.148)
		(layer "In4.Cu")
		(net 122)
	)
	(arc
		(start 153.775 120.636029)
		(mid 154.181586 120.804443)
		(end 154.35 121.211029)
		(width 0.148)
		(layer "In4.Cu")
		(net 122)
	)
	(arc
		(start 148.6 121.211045)
		(mid 148.768414 120.804459)
		(end 149.175 120.636045)
		(width 0.148)
		(layer "In4.Cu")
		(net 122)
	)
	(arc
		(start 149.175 120.636045)
		(mid 149.581586 120.804459)
		(end 149.75 121.211045)
		(width 0.148)
		(layer "In4.Cu")
		(net 122)
	)
	(arc
		(start 152.05 121.25)
		(mid 152.218414 121.656586)
		(end 152.625 121.825)
		(width 0.148)
		(layer "In4.Cu")
		(net 122)
	)
	(arc
		(start 153.2 121.211029)
		(mid 153.368414 120.804443)
		(end 153.775 120.636029)
		(width 0.148)
		(layer "In4.Cu")
		(net 122)
	)
	(arc
		(start 150.9 121.211045)
		(mid 151.068414 120.804459)
		(end 151.475 120.636045)
		(width 0.148)
		(layer "In4.Cu")
		(net 122)
	)
	(arc
		(start 154.35 121.25)
		(mid 154.518414 121.656586)
		(end 154.925 121.825)
		(width 0.148)
		(layer "In4.Cu")
		(net 122)
	)
	(arc
		(start 149.75 121.25)
		(mid 149.918414 121.656586)
		(end 150.325 121.825)
		(width 0.148)
		(layer "In4.Cu")
		(net 122)
	)
	(arc
		(start 148.025 121.825)
		(mid 148.431586 121.656586)
		(end 148.6 121.25)
		(width 0.148)
		(layer "In4.Cu")
		(net 122)
	)
	(arc
		(start 150.325 121.825)
		(mid 150.731586 121.656586)
		(end 150.9 121.25)
		(width 0.148)
		(layer "In4.Cu")
		(net 122)
	)
	(segment
		(start 182.9995 143.9995)
		(end 182.5 143.5)
		(width 0.256)
		(layer "F.Cu")
		(net 123)
	)
	(segment
		(start 136.05 106)
		(end 136.05 107.152)
		(width 0.38)
		(layer "F.Cu")
		(net 123)
	)
	(via
		(at 182.5 143.5)
		(size 0.45)
		(drill 0.1)
		(layers "F.Cu" "B.Cu")
		(remove_unused_layers yes)
		(keep_end_layers yes)
		(zone_layer_connections)
		(net 123)
	)
	(via
		(at 136.05 107.152)
		(size 0.45)
		(drill 0.1)
		(layers "F.Cu" "B.Cu")
		(remove_unused_layers yes)
		(keep_end_layers yes)
		(zone_layer_connections)
		(net 123)
	)
	(segment
		(start 182 143)
		(end 182.5 143.5)
		(width 0.148)
		(layer "In4.Cu")
		(net 123)
	)
	(segment
		(start 160.78 126.95)
		(end 161.97 125.76)
		(width 0.148)
		(layer "In4.Cu")
		(net 123)
	)
	(segment
		(start 136.05 110.775)
		(end 136.05 116.45)
		(width 0.148)
		(layer "In4.Cu")
		(net 123)
	)
	(segment
		(start 178.35 143)
		(end 182 143)
		(width 0.148)
		(layer "In4.Cu")
		(net 123)
	)
	(segment
		(start 136.8 108.225)
		(end 136.8 110.025)
		(width 0.148)
		(layer "In4.Cu")
		(net 123)
	)
	(segment
		(start 136.8 110.025)
		(end 136.05 110.775)
		(width 0.148)
		(layer "In4.Cu")
		(net 123)
	)
	(segment
		(start 146.55 126.95)
		(end 160.78 126.95)
		(width 0.148)
		(layer "In4.Cu")
		(net 123)
	)
	(segment
		(start 136.05 116.45)
		(end 146.55 126.95)
		(width 0.148)
		(layer "In4.Cu")
		(net 123)
	)
	(segment
		(start 161.97 125.76)
		(end 167.85 125.76)
		(width 0.148)
		(layer "In4.Cu")
		(net 123)
	)
	(segment
		(start 178 135.91)
		(end 178 142.65)
		(width 0.148)
		(layer "In4.Cu")
		(net 123)
	)
	(segment
		(start 136.05 107.475)
		(end 136.8 108.225)
		(width 0.148)
		(layer "In4.Cu")
		(net 123)
	)
	(segment
		(start 136.05 107.152)
		(end 136.05 107.475)
		(width 0.148)
		(layer "In4.Cu")
		(net 123)
	)
	(segment
		(start 167.85 125.76)
		(end 178 135.91)
		(width 0.148)
		(layer "In4.Cu")
		(net 123)
	)
	(segment
		(start 178 142.65)
		(end 178.35 143)
		(width 0.148)
		(layer "In4.Cu")
		(net 123)
	)
	(segment
		(start 134.35 106)
		(end 134.35 107.152)
		(width 0.38)
		(layer "F.Cu")
		(net 124)
	)
	(segment
		(start 180.9995 142.999499)
		(end 180.5 142.5)
		(width 0.256)
		(layer "F.Cu")
		(net 124)
	)
	(via
		(at 134.35 107.152)
		(size 0.45)
		(drill 0.1)
		(layers "F.Cu" "B.Cu")
		(remove_unused_layers yes)
		(keep_end_layers yes)
		(zone_layer_connections)
		(net 124)
	)
	(via
		(at 180.5 142.5)
		(size 0.45)
		(drill 0.1)
		(layers "F.Cu" "B.Cu")
		(remove_unused_layers yes)
		(keep_end_layers yes)
		(zone_layer_connections)
		(net 124)
	)
	(segment
		(start 159.75 133.75)
		(end 158.25 132.25)
		(width 0.148)
		(layer "In2.Cu")
		(net 124)
	)
	(segment
		(start 183.05 140.25)
		(end 183.325 139.975)
		(width 0.148)
		(layer "In2.Cu")
		(net 124)
	)
	(segment
		(start 180.45 133.75)
		(end 159.75 133.75)
		(width 0.148)
		(layer "In2.Cu")
		(net 124)
	)
	(segment
		(start 141.597915 113.047916)
		(end 141.597917 113.047917)
		(width 0.148)
		(layer "In2.Cu")
		(net 124)
	)
	(segment
		(start 142.198959 114.249999)
		(end 142.198958 114.249999)
		(width 0.148)
		(layer "In2.Cu")
		(net 124)
	)
	(segment
		(start 148.45 121.25)
		(end 148.45 119.9)
		(width 0.148)
		(layer "In2.Cu")
		(net 124)
	)
	(segment
		(start 140.395835 111.845835)
		(end 139.05 110.5)
		(width 0.148)
		(layer "In2.Cu")
		(net 124)
	)
	(segment
		(start 141.597917 113.047917)
		(end 141.597918 113.047918)
		(width 0.148)
		(layer "In2.Cu")
		(net 124)
	)
	(segment
		(start 183.7 139.975)
		(end 184 139.675)
		(width 0.148)
		(layer "In2.Cu")
		(net 124)
	)
	(segment
		(start 183.05 140.725)
		(end 183.05 140.25)
		(width 0.148)
		(layer "In2.Cu")
		(net 124)
	)
	(segment
		(start 140.996876 113.047917)
		(end 140.823971 113.220823)
		(width 0.148)
		(layer "In2.Cu")
		(net 124)
	)
	(segment
		(start 184 139.675)
		(end 184 137.3)
		(width 0.148)
		(layer "In2.Cu")
		(net 124)
	)
	(segment
		(start 181.325 142.025)
		(end 181.675 142.025)
		(width 0.148)
		(layer "In2.Cu")
		(net 124)
	)
	(segment
		(start 184 137.3)
		(end 180.45 133.75)
		(width 0.148)
		(layer "In2.Cu")
		(net 124)
	)
	(segment
		(start 142.198958 114.249999)
		(end 142.026046 114.422912)
		(width 0.148)
		(layer "In2.Cu")
		(net 124)
	)
	(segment
		(start 140.996877 113.047917)
		(end 140.996876 113.047917)
		(width 0.148)
		(layer "In2.Cu")
		(net 124)
	)
	(segment
		(start 180.85 142.5)
		(end 181.325 142.025)
		(width 0.148)
		(layer "In2.Cu")
		(net 124)
	)
	(segment
		(start 141.425005 114.422911)
		(end 141.425004 114.422911)
		(width 0.148)
		(layer "In2.Cu")
		(net 124)
	)
	(segment
		(start 135.275 109.925)
		(end 135.275 108.077)
		(width 0.148)
		(layer "In2.Cu")
		(net 124)
	)
	(segment
		(start 140.395833 111.845834)
		(end 140.395835 111.845835)
		(width 0.148)
		(layer "In2.Cu")
		(net 124)
	)
	(segment
		(start 148.45 119.9)
		(end 142.8 114.25)
		(width 0.148)
		(layer "In2.Cu")
		(net 124)
	)
	(segment
		(start 180.5 142.5)
		(end 180.85 142.5)
		(width 0.148)
		(layer "In2.Cu")
		(net 124)
	)
	(segment
		(start 140.222928 112.619781)
		(end 140.22293 112.619782)
		(width 0.148)
		(layer "In2.Cu")
		(net 124)
	)
	(segment
		(start 141.425003 113.82187)
		(end 141.425005 113.821871)
		(width 0.148)
		(layer "In2.Cu")
		(net 124)
	)
	(segment
		(start 141.425005 113.821871)
		(end 141.597916 113.648957)
		(width 0.148)
		(layer "In2.Cu")
		(net 124)
	)
	(segment
		(start 158.25 132.25)
		(end 158.25 131.05)
		(width 0.148)
		(layer "In2.Cu")
		(net 124)
	)
	(segment
		(start 183.325 139.975)
		(end 183.7 139.975)
		(width 0.148)
		(layer "In2.Cu")
		(net 124)
	)
	(segment
		(start 135.275 108.077)
		(end 134.35 107.152)
		(width 0.148)
		(layer "In2.Cu")
		(net 124)
	)
	(segment
		(start 182.875 140.9)
		(end 183.05 140.725)
		(width 0.148)
		(layer "In2.Cu")
		(net 124)
	)
	(segment
		(start 158.25 131.05)
		(end 148.45 121.25)
		(width 0.148)
		(layer "In2.Cu")
		(net 124)
	)
	(segment
		(start 140.22293 112.619782)
		(end 140.395834 112.446875)
		(width 0.148)
		(layer "In2.Cu")
		(net 124)
	)
	(segment
		(start 139.05 110.5)
		(end 135.85 110.5)
		(width 0.148)
		(layer "In2.Cu")
		(net 124)
	)
	(segment
		(start 182.025 141.374)
		(end 182.499 140.9)
		(width 0.148)
		(layer "In2.Cu")
		(net 124)
	)
	(segment
		(start 135.85 110.5)
		(end 135.275 109.925)
		(width 0.148)
		(layer "In2.Cu")
		(net 124)
	)
	(segment
		(start 140.22293 113.220822)
		(end 140.222929 113.220822)
		(width 0.148)
		(layer "In2.Cu")
		(net 124)
	)
	(segment
		(start 182.499 140.9)
		(end 182.875 140.9)
		(width 0.148)
		(layer "In2.Cu")
		(net 124)
	)
	(segment
		(start 181.675 142.025)
		(end 182.025 141.675)
		(width 0.148)
		(layer "In2.Cu")
		(net 124)
	)
	(segment
		(start 182.025 141.675)
		(end 182.025 141.374)
		(width 0.148)
		(layer "In2.Cu")
		(net 124)
	)
	(arc
		(start 141.597916 113.648957)
		(mid 141.722395 113.348436)
		(end 141.597915 113.047916)
		(width 0.148)
		(layer "In2.Cu")
		(net 124)
	)
	(arc
		(start 142.026046 114.422912)
		(mid 141.725525 114.547391)
		(end 141.425005 114.422911)
		(width 0.148)
		(layer "In2.Cu")
		(net 124)
	)
	(arc
		(start 141.425004 114.422911)
		(mid 141.300524 114.122391)
		(end 141.425003 113.82187)
		(width 0.148)
		(layer "In2.Cu")
		(net 124)
	)
	(arc
		(start 140.823971 113.220823)
		(mid 140.52345 113.345302)
		(end 140.22293 113.220822)
		(width 0.148)
		(layer "In2.Cu")
		(net 124)
	)
	(arc
		(start 140.222929 113.220822)
		(mid 140.098449 112.920302)
		(end 140.222928 112.619781)
		(width 0.148)
		(layer "In2.Cu")
		(net 124)
	)
	(arc
		(start 140.395834 112.446875)
		(mid 140.520313 112.146354)
		(end 140.395833 111.845834)
		(width 0.148)
		(layer "In2.Cu")
		(net 124)
	)
	(arc
		(start 141.597918 113.047918)
		(mid 141.297398 112.923438)
		(end 140.996877 113.047917)
		(width 0.148)
		(layer "In2.Cu")
		(net 124)
	)
	(arc
		(start 142.8 114.25)
		(mid 142.49948 114.12552)
		(end 142.198959 114.249999)
		(width 0.148)
		(layer "In2.Cu")
		(net 124)
	)
	(segment
		(start 178.9995 141.9995)
		(end 178.5 141.5)
		(width 0.256)
		(layer "F.Cu")
		(net 125)
	)
	(segment
		(start 132.65 106)
		(end 132.65 107.152)
		(width 0.38)
		(layer "F.Cu")
		(net 125)
	)
	(via
		(at 178.5 141.5)
		(size 0.45)
		(drill 0.1)
		(layers "F.Cu" "B.Cu")
		(remove_unused_layers yes)
		(keep_end_layers yes)
		(zone_layer_connections)
		(net 125)
	)
	(via
		(at 132.65 107.152)
		(size 0.45)
		(drill 0.1)
		(layers "F.Cu" "B.Cu")
		(remove_unused_layers yes)
		(keep_end_layers yes)
		(zone_layer_connections)
		(net 125)
	)
	(segment
		(start 179 142)
		(end 178.5 141.5)
		(width 0.148)
		(layer "In2.Cu")
		(net 125)
	)
	(segment
		(start 155.975 132.525)
		(end 155.975 133.775)
		(width 0.148)
		(layer "In2.Cu")
		(net 125)
	)
	(segment
		(start 157.65 135.45)
		(end 179.95 135.45)
		(width 0.148)
		(layer "In2.Cu")
		(net 125)
	)
	(segment
		(start 180.775 140.95)
		(end 180.375 140.95)
		(width 0.148)
		(layer "In2.Cu")
		(net 125)
	)
	(segment
		(start 181 140.725)
		(end 180.775 140.95)
		(width 0.148)
		(layer "In2.Cu")
		(net 125)
	)
	(segment
		(start 180.025 141.3)
		(end 180.025 141.6)
		(width 0.148)
		(layer "In2.Cu")
		(net 125)
	)
	(segment
		(start 134.55 114.1)
		(end 137.55 114.1)
		(width 0.148)
		(layer "In2.Cu")
		(net 125)
	)
	(segment
		(start 180.025 141.6)
		(end 179.625 142)
		(width 0.148)
		(layer "In2.Cu")
		(net 125)
	)
	(segment
		(start 181 140.325)
		(end 181 140.725)
		(width 0.148)
		(layer "In2.Cu")
		(net 125)
	)
	(segment
		(start 179.625 142)
		(end 179 142)
		(width 0.148)
		(layer "In2.Cu")
		(net 125)
	)
	(segment
		(start 179.95 135.45)
		(end 181.975 137.475)
		(width 0.148)
		(layer "In2.Cu")
		(net 125)
	)
	(segment
		(start 181.975 137.475)
		(end 181.975 139.707136)
		(width 0.148)
		(layer "In2.Cu")
		(net 125)
	)
	(segment
		(start 133.25 107.752)
		(end 133.25 111.025)
		(width 0.148)
		(layer "In2.Cu")
		(net 125)
	)
	(segment
		(start 181.975 139.707136)
		(end 181.732136 139.95)
		(width 0.148)
		(layer "In2.Cu")
		(net 125)
	)
	(segment
		(start 133 112.55)
		(end 134.55 114.1)
		(width 0.148)
		(layer "In2.Cu")
		(net 125)
	)
	(segment
		(start 180.375 140.95)
		(end 180.025 141.3)
		(width 0.148)
		(layer "In2.Cu")
		(net 125)
	)
	(segment
		(start 133.25 111.025)
		(end 133 111.275)
		(width 0.148)
		(layer "In2.Cu")
		(net 125)
	)
	(segment
		(start 155.975 133.775)
		(end 157.65 135.45)
		(width 0.148)
		(layer "In2.Cu")
		(net 125)
	)
	(segment
		(start 137.55 114.1)
		(end 155.975 132.525)
		(width 0.148)
		(layer "In2.Cu")
		(net 125)
	)
	(segment
		(start 181.732136 139.95)
		(end 181.375 139.95)
		(width 0.148)
		(layer "In2.Cu")
		(net 125)
	)
	(segment
		(start 132.65 107.152)
		(end 133.25 107.752)
		(width 0.148)
		(layer "In2.Cu")
		(net 125)
	)
	(segment
		(start 181.375 139.95)
		(end 181 140.325)
		(width 0.148)
		(layer "In2.Cu")
		(net 125)
	)
	(segment
		(start 133 111.275)
		(end 133 112.55)
		(width 0.148)
		(layer "In2.Cu")
		(net 125)
	)
	(segment
		(start 168.35 106)
		(end 168.35 107.152)
		(width 0.38)
		(layer "F.Cu")
		(net 126)
	)
	(segment
		(start 190.0005 143.9995)
		(end 190.5 143.5)
		(width 0.256)
		(layer "F.Cu")
		(net 126)
	)
	(via
		(at 168.35 107.152)
		(size 0.45)
		(drill 0.1)
		(layers "F.Cu" "B.Cu")
		(remove_unused_layers yes)
		(keep_end_layers yes)
		(zone_layer_connections)
		(net 126)
	)
	(via
		(at 190.5 143.5)
		(size 0.45)
		(drill 0.1)
		(layers "F.Cu" "B.Cu")
		(remove_unused_layers yes)
		(keep_end_layers yes)
		(zone_layer_connections)
		(net 126)
	)
	(segment
		(start 171.674706 118.305)
		(end 172.05 118.305)
		(width 0.13)
		(layer "In6.Cu")
		(net 126)
	)
	(segment
		(start 180.925821 122.961628)
		(end 181.303927 122.583521)
		(width 0.13)
		(layer "In6.Cu")
		(net 126)
	)
	(segment
		(start 177.45 118.305)
		(end 177.85 118.305)
		(width 0.13)
		(layer "In6.Cu")
		(net 126)
	)
	(segment
		(start 168.045 107.457)
		(end 168.045 108.049706)
		(width 0.13)
		(layer "In6.Cu")
		(net 126)
	)
	(segment
		(start 190.5 143.5)
		(end 190.5 143.2)
		(width 0.1)
		(layer "In6.Cu")
		(net 126)
	)
	(segment
		(start 172.695 118.95)
		(end 172.695 119.07)
		(width 0.13)
		(layer "In6.Cu")
		(net 126)
	)
	(segment
		(start 180.925822 122.961627)
		(end 180.925821 122.961628)
		(width 0.13)
		(layer "In6.Cu")
		(net 126)
	)
	(segment
		(start 178.609852 119.889446)
		(end 178.231734 120.267563)
		(width 0.13)
		(layer "In6.Cu")
		(net 126)
	)
	(segment
		(start 168.045 108.049706)
		(end 167.795 108.299706)
		(width 0.13)
		(layer "In6.Cu")
		(net 126)
	)
	(segment
		(start 173.1 119.475)
		(end 173.5 119.475)
		(width 0.13)
		(layer "In6.Cu")
		(net 126)
	)
	(segment
		(start 190.5 143.2)
		(end 190.55 143.15)
		(width 0.1)
		(layer "In6.Cu")
		(net 126)
	)
	(segment
		(start 180.519039 120.674334)
		(end 180.519041 120.674335)
		(width 0.13)
		(layer "In6.Cu")
		(net 126)
	)
	(segment
		(start 176.805 119.07)
		(end 176.805 118.95)
		(width 0.13)
		(layer "In6.Cu")
		(net 126)
	)
	(segment
		(start 168.3775 115.007794)
		(end 171.674706 118.305)
		(width 0.13)
		(layer "In6.Cu")
		(net 126)
	)
	(segment
		(start 179.016622 121.052452)
		(end 179.394739 120.674334)
		(width 0.13)
		(layer "In6.Cu")
		(net 126)
	)
	(segment
		(start 180.51904 121.798635)
		(end 180.51904 121.798634)
		(width 0.13)
		(layer "In6.Cu")
		(net 126)
	)
	(segment
		(start 182.428229 122.583523)
		(end 191.12 131.275294)
		(width 0.13)
		(layer "In6.Cu")
		(net 126)
	)
	(segment
		(start 180.140934 122.961629)
		(end 180.140933 122.961628)
		(width 0.13)
		(layer "In6.Cu")
		(net 126)
	)
	(segment
		(start 191.1 138.02)
		(end 191.12 138)
		(width 0.1)
		(layer "In6.Cu")
		(net 126)
	)
	(segment
		(start 179.016623 121.052451)
		(end 179.016622 121.052452)
		(width 0.13)
		(layer "In6.Cu")
		(net 126)
	)
	(segment
		(start 173.905 119.07)
		(end 173.905 118.95)
		(width 0.13)
		(layer "In6.Cu")
		(net 126)
	)
	(segment
		(start 178.231734 121.052451)
		(end 178.231734 121.052452)
		(width 0.13)
		(layer "In6.Cu")
		(net 126)
	)
	(segment
		(start 176 119.475)
		(end 176.4 119.475)
		(width 0.13)
		(layer "In6.Cu")
		(net 126)
	)
	(segment
		(start 190.55 143.15)
		(end 190.791422 143.15)
		(width 0.1)
		(layer "In6.Cu")
		(net 126)
	)
	(segment
		(start 191.1 142.841422)
		(end 191.1 138.02)
		(width 0.1)
		(layer "In6.Cu")
		(net 126)
	)
	(segment
		(start 190.791422 143.15)
		(end 191.1 142.841422)
		(width 0.1)
		(layer "In6.Cu")
		(net 126)
	)
	(segment
		(start 174.55 118.305)
		(end 174.95 118.305)
		(width 0.13)
		(layer "In6.Cu")
		(net 126)
	)
	(segment
		(start 167.795 108.299706)
		(end 167.795 110.180294)
		(width 0.13)
		(layer "In6.Cu")
		(net 126)
	)
	(segment
		(start 182.428227 122.583521)
		(end 182.428229 122.583523)
		(width 0.13)
		(layer "In6.Cu")
		(net 126)
	)
	(segment
		(start 180.519041 120.674335)
		(end 180.51904 120.674335)
		(width 0.13)
		(layer "In6.Cu")
		(net 126)
	)
	(segment
		(start 177.85 118.305)
		(end 178.149706 118.305)
		(width 0.13)
		(layer "In6.Cu")
		(net 126)
	)
	(segment
		(start 180.51904 121.798634)
		(end 180.140933 122.17674)
		(width 0.13)
		(layer "In6.Cu")
		(net 126)
	)
	(segment
		(start 178.149706 118.305)
		(end 178.609852 118.765147)
		(width 0.13)
		(layer "In6.Cu")
		(net 126)
	)
	(segment
		(start 178.609852 119.889447)
		(end 178.609852 119.889446)
		(width 0.13)
		(layer "In6.Cu")
		(net 126)
	)
	(segment
		(start 175.595 118.95)
		(end 175.595 119.07)
		(width 0.13)
		(layer "In6.Cu")
		(net 126)
	)
	(segment
		(start 191.12 131.275294)
		(end 191.12 138)
		(width 0.13)
		(layer "In6.Cu")
		(net 126)
	)
	(segment
		(start 168.35 107.152)
		(end 168.045 107.457)
		(width 0.13)
		(layer "In6.Cu")
		(net 126)
	)
	(segment
		(start 167.795 110.180294)
		(end 168.3775 110.762794)
		(width 0.13)
		(layer "In6.Cu")
		(net 126)
	)
	(segment
		(start 168.3775 110.762794)
		(end 168.3775 115.007794)
		(width 0.13)
		(layer "In6.Cu")
		(net 126)
	)
	(arc
		(start 176.4 119.475)
		(mid 176.686378 119.356378)
		(end 176.805 119.07)
		(width 0.13)
		(layer "In6.Cu")
		(net 126)
	)
	(arc
		(start 180.140933 122.961628)
		(mid 180.533378 123.124183)
		(end 180.925822 122.961627)
		(width 0.13)
		(layer "In6.Cu")
		(net 126)
	)
	(arc
		(start 178.609852 118.765147)
		(mid 178.842702 119.327297)
		(end 178.609852 119.889447)
		(width 0.13)
		(layer "In6.Cu")
		(net 126)
	)
	(arc
		(start 178.231734 121.052452)
		(mid 178.624179 121.215007)
		(end 179.016623 121.052451)
		(width 0.13)
		(layer "In6.Cu")
		(net 126)
	)
	(arc
		(start 178.231734 120.267563)
		(mid 178.069178 120.660007)
		(end 178.231734 121.052451)
		(width 0.13)
		(layer "In6.Cu")
		(net 126)
	)
	(arc
		(start 181.303927 122.583521)
		(mid 181.866077 122.350671)
		(end 182.428227 122.583521)
		(width 0.13)
		(layer "In6.Cu")
		(net 126)
	)
	(arc
		(start 172.05 118.305)
		(mid 172.506084 118.493916)
		(end 172.695 118.95)
		(width 0.13)
		(layer "In6.Cu")
		(net 126)
	)
	(arc
		(start 176.805 118.95)
		(mid 176.993916 118.493916)
		(end 177.45 118.305)
		(width 0.13)
		(layer "In6.Cu")
		(net 126)
	)
	(arc
		(start 180.51904 120.674335)
		(mid 180.75189 121.236485)
		(end 180.51904 121.798635)
		(width 0.13)
		(layer "In6.Cu")
		(net 126)
	)
	(arc
		(start 173.905 118.95)
		(mid 174.093916 118.493916)
		(end 174.55 118.305)
		(width 0.13)
		(layer "In6.Cu")
		(net 126)
	)
	(arc
		(start 175.595 119.07)
		(mid 175.713622 119.356378)
		(end 176 119.475)
		(width 0.13)
		(layer "In6.Cu")
		(net 126)
	)
	(arc
		(start 172.695 119.07)
		(mid 172.813622 119.356378)
		(end 173.1 119.475)
		(width 0.13)
		(layer "In6.Cu")
		(net 126)
	)
	(arc
		(start 173.5 119.475)
		(mid 173.786378 119.356378)
		(end 173.905 119.07)
		(width 0.13)
		(layer "In6.Cu")
		(net 126)
	)
	(arc
		(start 179.394739 120.674334)
		(mid 179.956889 120.441484)
		(end 180.519039 120.674334)
		(width 0.13)
		(layer "In6.Cu")
		(net 126)
	)
	(arc
		(start 180.140933 122.17674)
		(mid 179.978378 122.569185)
		(end 180.140934 122.961629)
		(width 0.13)
		(layer "In6.Cu")
		(net 126)
	)
	(arc
		(start 174.95 118.305)
		(mid 175.406084 118.493916)
		(end 175.595 118.95)
		(width 0.13)
		(layer "In6.Cu")
		(net 126)
	)
	(segment
		(start 167.5 106)
		(end 167.5 107.152)
		(width 0.38)
		(layer "F.Cu")
		(net 127)
	)
	(segment
		(start 190.0005 142.999499)
		(end 190.5 142.5)
		(width 0.256)
		(layer "F.Cu")
		(net 127)
	)
	(via
		(at 190.5 142.5)
		(size 0.45)
		(drill 0.1)
		(layers "F.Cu" "B.Cu")
		(remove_unused_layers yes)
		(keep_end_layers yes)
		(zone_layer_connections)
		(net 127)
	)
	(via
		(at 167.5 107.152)
		(size 0.45)
		(drill 0.1)
		(layers "F.Cu" "B.Cu")
		(remove_unused_layers yes)
		(keep_end_layers yes)
		(zone_layer_connections)
		(net 127)
	)
	(segment
		(start 190.9 142.31461)
		(end 190.9 142.4)
		(width 0.1)
		(layer "In6.Cu")
		(net 127)
	)
	(segment
		(start 180.349335 121.628929)
		(end 179.971228 122.007035)
		(width 0.13)
		(layer "In6.Cu")
		(net 127)
	)
	(segment
		(start 179.186328 121.222157)
		(end 179.186328 121.222158)
		(width 0.13)
		(layer "In6.Cu")
		(net 127)
	)
	(segment
		(start 190.9 142.758578)
		(end 190.758578 142.9)
		(width 0.1)
		(layer "In6.Cu")
		(net 127)
	)
	(segment
		(start 182.258522 122.753229)
		(end 182.258521 122.753228)
		(width 0.13)
		(layer "In6.Cu")
		(net 127)
	)
	(segment
		(start 168.1375 110.862206)
		(end 168.1375 115.107206)
		(width 0.13)
		(layer "In6.Cu")
		(net 127)
	)
	(segment
		(start 167.555 108.200294)
		(end 167.555 110.279706)
		(width 0.13)
		(layer "In6.Cu")
		(net 127)
	)
	(segment
		(start 176 119.715)
		(end 176.4 119.715)
		(width 0.13)
		(layer "In6.Cu")
		(net 127)
	)
	(segment
		(start 174.145 119.07)
		(end 174.145 118.95)
		(width 0.13)
		(layer "In6.Cu")
		(net 127)
	)
	(segment
		(start 167.805 107.405)
		(end 167.805 107.950294)
		(width 0.13)
		(layer "In6.Cu")
		(net 127)
	)
	(segment
		(start 182.258521 122.753228)
		(end 190.88 131.374706)
		(width 0.13)
		(layer "In6.Cu")
		(net 127)
	)
	(segment
		(start 190.767695 141.832305)
		(end 190.767694 141.832305)
		(width 0.1)
		(layer "In6.Cu")
		(net 127)
	)
	(segment
		(start 179.186328 121.222158)
		(end 179.564445 120.84404)
		(width 0.13)
		(layer "In6.Cu")
		(net 127)
	)
	(segment
		(start 178.050294 118.545)
		(end 178.440147 118.934852)
		(width 0.13)
		(layer "In6.Cu")
		(net 127)
	)
	(segment
		(start 190.88 138)
		(end 190.9 138.02)
		(width 0.1)
		(layer "In6.Cu")
		(net 127)
	)
	(segment
		(start 178.440147 119.719741)
		(end 178.062029 120.097858)
		(width 0.13)
		(layer "In6.Cu")
		(net 127)
	)
	(segment
		(start 177.045 119.07)
		(end 177.045 118.95)
		(width 0.13)
		(layer "In6.Cu")
		(net 127)
	)
	(segment
		(start 190.88 131.374706)
		(end 190.88 138)
		(width 0.13)
		(layer "In6.Cu")
		(net 127)
	)
	(segment
		(start 190.758578 142.9)
		(end 190.55 142.9)
		(width 0.1)
		(layer "In6.Cu")
		(net 127)
	)
	(segment
		(start 167.555 110.279706)
		(end 168.1375 110.862206)
		(width 0.13)
		(layer "In6.Cu")
		(net 127)
	)
	(segment
		(start 190.55 142.9)
		(end 190.5 142.85)
		(width 0.1)
		(layer "In6.Cu")
		(net 127)
	)
	(segment
		(start 180.349335 121.62893)
		(end 180.349335 121.628929)
		(width 0.13)
		(layer "In6.Cu")
		(net 127)
	)
	(segment
		(start 181.095527 123.131334)
		(end 181.095527 123.131335)
		(width 0.13)
		(layer "In6.Cu")
		(net 127)
	)
	(segment
		(start 177.45 118.545)
		(end 177.85 118.545)
		(width 0.13)
		(layer "In6.Cu")
		(net 127)
	)
	(segment
		(start 190.635389 141.96461)
		(end 190.635389 142.05)
		(width 0.1)
		(layer "In6.Cu")
		(net 127)
	)
	(segment
		(start 167.805 107.950294)
		(end 167.555 108.200294)
		(width 0.13)
		(layer "In6.Cu")
		(net 127)
	)
	(segment
		(start 190.767694 142.182305)
		(end 190.767695 142.182305)
		(width 0.1)
		(layer "In6.Cu")
		(net 127)
	)
	(segment
		(start 181.095527 123.131335)
		(end 181.473633 122.753228)
		(width 0.13)
		(layer "In6.Cu")
		(net 127)
	)
	(segment
		(start 168.1375 115.107206)
		(end 171.575294 118.545)
		(width 0.13)
		(layer "In6.Cu")
		(net 127)
	)
	(segment
		(start 175.355 118.95)
		(end 175.355 119.07)
		(width 0.13)
		(layer "In6.Cu")
		(net 127)
	)
	(segment
		(start 173.1 119.715)
		(end 173.5 119.715)
		(width 0.13)
		(layer "In6.Cu")
		(net 127)
	)
	(segment
		(start 167.5 107.152)
		(end 167.552 107.152)
		(width 0.13)
		(layer "In6.Cu")
		(net 127)
	)
	(segment
		(start 167.552 107.152)
		(end 167.805 107.405)
		(width 0.13)
		(layer "In6.Cu")
		(net 127)
	)
	(segment
		(start 174.55 118.545)
		(end 174.95 118.545)
		(width 0.13)
		(layer "In6.Cu")
		(net 127)
	)
	(segment
		(start 177.85 118.545)
		(end 178.050294 118.545)
		(width 0.13)
		(layer "In6.Cu")
		(net 127)
	)
	(segment
		(start 190.5 142.85)
		(end 190.5 142.5)
		(width 0.1)
		(layer "In6.Cu")
		(net 127)
	)
	(segment
		(start 171.575294 118.545)
		(end 172.05 118.545)
		(width 0.13)
		(layer "In6.Cu")
		(net 127)
	)
	(segment
		(start 178.440147 119.719742)
		(end 178.440147 119.719741)
		(width 0.13)
		(layer "In6.Cu")
		(net 127)
	)
	(segment
		(start 190.9 142.4)
		(end 190.9 142.758578)
		(width 0.1)
		(layer "In6.Cu")
		(net 127)
	)
	(segment
		(start 172.455 118.95)
		(end 172.455 119.07)
		(width 0.13)
		(layer "In6.Cu")
		(net 127)
	)
	(segment
		(start 190.9 138.02)
		(end 190.9 141.7)
		(width 0.1)
		(layer "In6.Cu")
		(net 127)
	)
	(arc
		(start 178.062029 121.222158)
		(mid 178.624179 121.455007)
		(end 179.186328 121.222157)
		(width 0.13)
		(layer "In6.Cu")
		(net 127)
	)
	(arc
		(start 190.767694 141.832305)
		(mid 190.67414 141.871056)
		(end 190.635389 141.96461)
		(width 0.1)
		(layer "In6.Cu")
		(net 127)
	)
	(arc
		(start 173.5 119.715)
		(mid 173.956084 119.526084)
		(end 174.145 119.07)
		(width 0.13)
		(layer "In6.Cu")
		(net 127)
	)
	(arc
		(start 172.05 118.545)
		(mid 172.336378 118.663622)
		(end 172.455 118.95)
		(width 0.13)
		(layer "In6.Cu")
		(net 127)
	)
	(arc
		(start 180.349335 120.84404)
		(mid 180.511891 121.236485)
		(end 180.349335 121.62893)
		(width 0.13)
		(layer "In6.Cu")
		(net 127)
	)
	(arc
		(start 190.767695 142.182305)
		(mid 190.861249 142.221056)
		(end 190.9 142.31461)
		(width 0.1)
		(layer "In6.Cu")
		(net 127)
	)
	(arc
		(start 190.635389 142.05)
		(mid 190.67414 142.143554)
		(end 190.767694 142.182305)
		(width 0.1)
		(layer "In6.Cu")
		(net 127)
	)
	(arc
		(start 179.971228 122.007035)
		(mid 179.738378 122.569185)
		(end 179.971228 123.131335)
		(width 0.13)
		(layer "In6.Cu")
		(net 127)
	)
	(arc
		(start 181.473633 122.753228)
		(mid 181.866078 122.590673)
		(end 182.258522 122.753229)
		(width 0.13)
		(layer "In6.Cu")
		(net 127)
	)
	(arc
		(start 178.440147 118.934852)
		(mid 178.602703 119.327297)
		(end 178.440147 119.719742)
		(width 0.13)
		(layer "In6.Cu")
		(net 127)
	)
	(arc
		(start 174.145 118.95)
		(mid 174.263622 118.663622)
		(end 174.55 118.545)
		(width 0.13)
		(layer "In6.Cu")
		(net 127)
	)
	(arc
		(start 172.455 119.07)
		(mid 172.643916 119.526084)
		(end 173.1 119.715)
		(width 0.13)
		(layer "In6.Cu")
		(net 127)
	)
	(arc
		(start 175.355 119.07)
		(mid 175.543916 119.526084)
		(end 176 119.715)
		(width 0.13)
		(layer "In6.Cu")
		(net 127)
	)
	(arc
		(start 178.062029 120.097858)
		(mid 177.829179 120.660008)
		(end 178.062029 121.222158)
		(width 0.13)
		(layer "In6.Cu")
		(net 127)
	)
	(arc
		(start 190.9 141.7)
		(mid 190.861249 141.793554)
		(end 190.767695 141.832305)
		(width 0.1)
		(layer "In6.Cu")
		(net 127)
	)
	(arc
		(start 177.045 118.95)
		(mid 177.163622 118.663622)
		(end 177.45 118.545)
		(width 0.13)
		(layer "In6.Cu")
		(net 127)
	)
	(arc
		(start 179.564445 120.84404)
		(mid 179.956889 120.681484)
		(end 180.349333 120.84404)
		(width 0.13)
		(layer "In6.Cu")
		(net 127)
	)
	(arc
		(start 176.4 119.715)
		(mid 176.856084 119.526084)
		(end 177.045 119.07)
		(width 0.13)
		(layer "In6.Cu")
		(net 127)
	)
	(arc
		(start 174.95 118.545)
		(mid 175.236378 118.663622)
		(end 175.355 118.95)
		(width 0.13)
		(layer "In6.Cu")
		(net 127)
	)
	(arc
		(start 179.971228 123.131335)
		(mid 180.533378 123.364184)
		(end 181.095527 123.131334)
		(width 0.13)
		(layer "In6.Cu")
		(net 127)
	)
	(segment
		(start 128.4 106)
		(end 128.4 107.152)
		(width 0.38)
		(layer "F.Cu")
		(net 128)
	)
	(segment
		(start 176.9995 139.9995)
		(end 176.5 139.5)
		(width 0.256)
		(layer "F.Cu")
		(net 128)
	)
	(via
		(at 128.4 107.152)
		(size 0.45)
		(drill 0.1)
		(layers "F.Cu" "B.Cu")
		(remove_unused_layers yes)
		(keep_end_layers yes)
		(zone_layer_connections)
		(net 128)
	)
	(via
		(at 176.5 139.5)
		(size 0.45)
		(drill 0.1)
		(layers "F.Cu" "B.Cu")
		(remove_unused_layers yes)
		(keep_end_layers yes)
		(zone_layer_connections)
		(net 128)
	)
	(segment
		(start 133.25 118.75)
		(end 154.5 140)
		(width 0.148)
		(layer "In2.Cu")
		(net 128)
	)
	(segment
		(start 129.65 113.2)
		(end 129.65 115.6)
		(width 0.148)
		(layer "In2.Cu")
		(net 128)
	)
	(segment
		(start 127.85 106)
		(end 127.65 106.2)
		(width 0.148)
		(layer "In2.Cu")
		(net 128)
	)
	(segment
		(start 128.4 106.2)
		(end 128.2 106)
		(width 0.148)
		(layer "In2.Cu")
		(net 128)
	)
	(segment
		(start 175.6 140)
		(end 176.1 139.5)
		(width 0.148)
		(layer "In2.Cu")
		(net 128)
	)
	(segment
		(start 127.65 109.05)
		(end 127.65 109.85)
		(width 0.148)
		(layer "In2.Cu")
		(net 128)
	)
	(segment
		(start 176.1 139.5)
		(end 176.5 139.5)
		(width 0.148)
		(layer "In2.Cu")
		(net 128)
	)
	(segment
		(start 128.736106 108.625)
		(end 128.075 108.625)
		(width 0.148)
		(layer "In2.Cu")
		(net 128)
	)
	(segment
		(start 128.4 107.152)
		(end 128.4 106.2)
		(width 0.148)
		(layer "In2.Cu")
		(net 128)
	)
	(segment
		(start 129.65 115.6)
		(end 132.8 118.75)
		(width 0.148)
		(layer "In2.Cu")
		(net 128)
	)
	(segment
		(start 128.4 111.95)
		(end 129.65 113.2)
		(width 0.148)
		(layer "In2.Cu")
		(net 128)
	)
	(segment
		(start 132.8 118.75)
		(end 133.25 118.75)
		(width 0.148)
		(layer "In2.Cu")
		(net 128)
	)
	(segment
		(start 154.5 140)
		(end 175.6 140)
		(width 0.148)
		(layer "In2.Cu")
		(net 128)
	)
	(segment
		(start 128.075 107.775)
		(end 128.736106 107.775)
		(width 0.148)
		(layer "In2.Cu")
		(net 128)
	)
	(segment
		(start 128.4 110.6)
		(end 128.4 111.95)
		(width 0.148)
		(layer "In2.Cu")
		(net 128)
	)
	(segment
		(start 127.65 106.2)
		(end 127.65 107.35)
		(width 0.148)
		(layer "In2.Cu")
		(net 128)
	)
	(segment
		(start 127.65 109.85)
		(end 128.4 110.6)
		(width 0.148)
		(layer "In2.Cu")
		(net 128)
	)
	(segment
		(start 128.2 106)
		(end 127.85 106)
		(width 0.148)
		(layer "In2.Cu")
		(net 128)
	)
	(arc
		(start 128.736106 107.775)
		(mid 129.036626 107.89948)
		(end 129.161106 108.2)
		(width 0.148)
		(layer "In2.Cu")
		(net 128)
	)
	(arc
		(start 127.65 107.35)
		(mid 127.77448 107.65052)
		(end 128.075 107.775)
		(width 0.148)
		(layer "In2.Cu")
		(net 128)
	)
	(arc
		(start 129.161106 108.2)
		(mid 129.036626 108.50052)
		(end 128.736106 108.625)
		(width 0.148)
		(layer "In2.Cu")
		(net 128)
	)
	(arc
		(start 128.075 108.625)
		(mid 127.77448 108.74948)
		(end 127.65 109.05)
		(width 0.148)
		(layer "In2.Cu")
		(net 128)
	)
	(segment
		(start 126.7 106)
		(end 126.7 107.152)
		(width 0.38)
		(layer "F.Cu")
		(net 129)
	)
	(segment
		(start 176.9995 140.9995)
		(end 176.5 140.5)
		(width 0.256)
		(layer "F.Cu")
		(net 129)
	)
	(via
		(at 126.7 107.152)
		(size 0.45)
		(drill 0.1)
		(layers "F.Cu" "B.Cu")
		(remove_unused_layers yes)
		(keep_end_layers yes)
		(zone_layer_connections)
		(net 129)
	)
	(via
		(at 176.5 140.5)
		(size 0.45)
		(drill 0.1)
		(layers "F.Cu" "B.Cu")
		(remove_unused_layers yes)
		(keep_end_layers yes)
		(zone_layer_connections)
		(net 129)
	)
	(segment
		(start 176.5 140.825)
		(end 176.05 141.275)
		(width 0.148)
		(layer "In2.Cu")
		(net 129)
	)
	(segment
		(start 176.05 141.275)
		(end 176.05 141.65)
		(width 0.148)
		(layer "In2.Cu")
		(net 129)
	)
	(segment
		(start 152.75 142)
		(end 126.7 115.95)
		(width 0.148)
		(layer "In2.Cu")
		(net 129)
	)
	(segment
		(start 125.8 110.225)
		(end 125.8 107.35)
		(width 0.148)
		(layer "In2.Cu")
		(net 129)
	)
	(segment
		(start 175.7 142)
		(end 152.75 142)
		(width 0.148)
		(layer "In2.Cu")
		(net 129)
	)
	(segment
		(start 125.998 107.152)
		(end 126.7 107.152)
		(width 0.148)
		(layer "In2.Cu")
		(net 129)
	)
	(segment
		(start 176.05 141.65)
		(end 175.7 142)
		(width 0.148)
		(layer "In2.Cu")
		(net 129)
	)
	(segment
		(start 126.7 111.125)
		(end 125.8 110.225)
		(width 0.148)
		(layer "In2.Cu")
		(net 129)
	)
	(segment
		(start 126.7 115.95)
		(end 126.7 111.125)
		(width 0.148)
		(layer "In2.Cu")
		(net 129)
	)
	(segment
		(start 125.8 107.35)
		(end 125.998 107.152)
		(width 0.148)
		(layer "In2.Cu")
		(net 129)
	)
	(segment
		(start 176.5 140.5)
		(end 176.5 140.825)
		(width 0.148)
		(layer "In2.Cu")
		(net 129)
	)
	(segment
		(start 197.0005 146.9995)
		(end 197.5 146.5)
		(width 0.256)
		(layer "F.Cu")
		(net 130)
	)
	(segment
		(start 245.7 110.598)
		(end 245.7 111.75)
		(width 0.38)
		(layer "F.Cu")
		(net 130)
	)
	(via
		(at 197.5 146.5)
		(size 0.45)
		(drill 0.1)
		(layers "F.Cu" "B.Cu")
		(remove_unused_layers yes)
		(keep_end_layers yes)
		(zone_layer_connections)
		(net 130)
	)
	(via
		(at 245.7 111.75)
		(size 0.45)
		(drill 0.1)
		(layers "F.Cu" "B.Cu")
		(remove_unused_layers yes)
		(keep_end_layers yes)
		(zone_layer_connections)
		(net 130)
	)
	(segment
		(start 198.2505 146.949499)
		(end 197.801 146.499999)
		(width 0.148)
		(layer "In2.Cu")
		(net 130)
	)
	(segment
		(start 215.525 128.175)
		(end 215.525 129.775)
		(width 0.148)
		(layer "In2.Cu")
		(net 130)
	)
	(segment
		(start 214.775 129.775)
		(end 214.775 128.175)
		(width 0.148)
		(layer "In2.Cu")
		(net 130)
	)
	(segment
		(start 197.801 146.499999)
		(end 197.5 146.499999)
		(width 0.148)
		(layer "In2.Cu")
		(net 130)
	)
	(segment
		(start 237.91855 113.04687)
		(end 237.91855 113.046869)
		(width 0.148)
		(layer "In2.Cu")
		(net 130)
	)
	(segment
		(start 234.610185 114.410696)
		(end 234.610185 114.410695)
		(width 0.148)
		(layer "In2.Cu")
		(net 130)
	)
	(segment
		(start 237.473966 113.491454)
		(end 237.91855 113.04687)
		(width 0.148)
		(layer "In2.Cu")
		(net 130)
	)
	(segment
		(start 235.953688 113.067193)
		(end 235.953688 113.067192)
		(width 0.148)
		(layer "In2.Cu")
		(net 130)
	)
	(segment
		(start 217.025 128.175)
		(end 217.025 128.275)
		(width 0.148)
		(layer "In2.Cu")
		(net 130)
	)
	(segment
		(start 206.8 142.95)
		(end 202.800501 146.949499)
		(width 0.148)
		(layer "In2.Cu")
		(net 130)
	)
	(segment
		(start 212.5 135.1)
		(end 207.2 135.1)
		(width 0.148)
		(layer "In2.Cu")
		(net 130)
	)
	(segment
		(start 216.275 128.275)
		(end 216.275 128.175)
		(width 0.148)
		(layer "In2.Cu")
		(net 130)
	)
	(segment
		(start 207.225 136.025)
		(end 209.225 136.025)
		(width 0.148)
		(layer "In2.Cu")
		(net 130)
	)
	(segment
		(start 209.125 127.8)
		(end 206.8 130.125)
		(width 0.148)
		(layer "In2.Cu")
		(net 130)
	)
	(segment
		(start 224.402864 127.8)
		(end 217.4 127.8)
		(width 0.148)
		(layer "In2.Cu")
		(net 130)
	)
	(segment
		(start 207.6 131.35)
		(end 207.6 131.4)
		(width 0.148)
		(layer "In2.Cu")
		(net 130)
	)
	(segment
		(start 245.7005 111.8445)
		(end 243.745 113.8)
		(width 0.148)
		(layer "In2.Cu")
		(net 130)
	)
	(segment
		(start 245.7005 111.749499)
		(end 245.7005 111.8445)
		(width 0.148)
		(layer "In2.Cu")
		(net 130)
	)
	(segment
		(start 213.275 129.325)
		(end 213.275 128.175)
		(width 0.148)
		(layer "In2.Cu")
		(net 130)
	)
	(segment
		(start 238.7 113.8)
		(end 238.402861 113.8)
		(width 0.148)
		(layer "In2.Cu")
		(net 130)
	)
	(segment
		(start 237.59184 114.033592)
		(end 237.473966 113.915718)
		(width 0.148)
		(layer "In2.Cu")
		(net 130)
	)
	(segment
		(start 234.610185 115.082446)
		(end 235.563679 116.03594)
		(width 0.148)
		(layer "In2.Cu")
		(net 130)
	)
	(segment
		(start 207.2 134.3)
		(end 212.5 134.3)
		(width 0.148)
		(layer "In2.Cu")
		(net 130)
	)
	(segment
		(start 207.225 132.625)
		(end 208.225 132.625)
		(width 0.148)
		(layer "In2.Cu")
		(net 130)
	)
	(segment
		(start 238.402861 113.8)
		(end 238.169271 114.033592)
		(width 0.148)
		(layer "In2.Cu")
		(net 130)
	)
	(segment
		(start 236.872927 115.329933)
		(end 236.872928 115.329934)
		(width 0.148)
		(layer "In2.Cu")
		(net 130)
	)
	(segment
		(start 207.525 138.575)
		(end 207.225 138.575)
		(width 0.148)
		(layer "In2.Cu")
		(net 130)
	)
	(segment
		(start 235.563679 116.639182)
		(end 224.402864 127.8)
		(width 0.148)
		(layer "In2.Cu")
		(net 130)
	)
	(segment
		(start 202.800501 146.949499)
		(end 198.2505 146.949499)
		(width 0.148)
		(layer "In2.Cu")
		(net 130)
	)
	(segment
		(start 237.494288 112.622607)
		(end 237.049703 113.067192)
		(width 0.148)
		(layer "In2.Cu")
		(net 130)
	)
	(segment
		(start 209.225 136.875)
		(end 207.225 136.875)
		(width 0.148)
		(layer "In2.Cu")
		(net 130)
	)
	(segment
		(start 234.610185 115.082445)
		(end 234.610185 115.082446)
		(width 0.148)
		(layer "In2.Cu")
		(net 130)
	)
	(segment
		(start 206.8 130.125)
		(end 206.8 130.55)
		(width 0.148)
		(layer "In2.Cu")
		(net 130)
	)
	(segment
		(start 235.953688 113.738942)
		(end 235.953688 113.738943)
		(width 0.148)
		(layer "In2.Cu")
		(net 130)
	)
	(segment
		(start 207.225 137.725)
		(end 207.525 137.725)
		(width 0.148)
		(layer "In2.Cu")
		(net 130)
	)
	(segment
		(start 236.201176 115.329934)
		(end 235.281936 114.410695)
		(width 0.148)
		(layer "In2.Cu")
		(net 130)
	)
	(segment
		(start 212.9 127.8)
		(end 209.125 127.8)
		(width 0.148)
		(layer "In2.Cu")
		(net 130)
	)
	(segment
		(start 208.225 133.475)
		(end 207.225 133.475)
		(width 0.148)
		(layer "In2.Cu")
		(net 130)
	)
	(segment
		(start 214.025 128.175)
		(end 214.025 129.325)
		(width 0.148)
		(layer "In2.Cu")
		(net 130)
	)
	(segment
		(start 235.953688 113.738943)
		(end 236.872927 114.658181)
		(width 0.148)
		(layer "In2.Cu")
		(net 130)
	)
	(segment
		(start 243.745 113.8)
		(end 240 113.8)
		(width 0.148)
		(layer "In2.Cu")
		(net 130)
	)
	(segment
		(start 206.8 139)
		(end 206.8 142.95)
		(width 0.148)
		(layer "In2.Cu")
		(net 130)
	)
	(segment
		(start 206.8 135.5)
		(end 206.8 135.6)
		(width 0.148)
		(layer "In2.Cu")
		(net 130)
	)
	(arc
		(start 237.91855 113.046869)
		(mid 238.006418 112.834738)
		(end 237.918552 112.622605)
		(width 0.148)
		(layer "In2.Cu")
		(net 130)
	)
	(arc
		(start 207.6 131.4)
		(mid 207.482843 131.682843)
		(end 207.2 131.8)
		(width 0.148)
		(layer "In2.Cu")
		(net 130)
	)
	(arc
		(start 240 113.8)
		(mid 239.77019 113.70481)
		(end 239.675 113.475)
		(width 0.148)
		(layer "In2.Cu")
		(net 130)
	)
	(arc
		(start 239.675 113.475)
		(mid 239.57981 113.24519)
		(end 239.35 113.15)
		(width 0.148)
		(layer "In2.Cu")
		(net 130)
	)
	(arc
		(start 216.65 128.65)
		(mid 216.384835 128.540165)
		(end 216.275 128.275)
		(width 0.148)
		(layer "In2.Cu")
		(net 130)
	)
	(arc
		(start 235.953688 113.067192)
		(mid 235.814564 113.403067)
		(end 235.953688 113.738942)
		(width 0.148)
		(layer "In2.Cu")
		(net 130)
	)
	(arc
		(start 216.275 128.175)
		(mid 216.165165 127.909835)
		(end 215.9 127.8)
		(width 0.148)
		(layer "In2.Cu")
		(net 130)
	)
	(arc
		(start 207.2 130.95)
		(mid 207.482843 131.067157)
		(end 207.6 131.35)
		(width 0.148)
		(layer "In2.Cu")
		(net 130)
	)
	(arc
		(start 217.4 127.8)
		(mid 217.134835 127.909835)
		(end 217.025 128.175)
		(width 0.148)
		(layer "In2.Cu")
		(net 130)
	)
	(arc
		(start 206.8 132.2)
		(mid 206.92448 132.50052)
		(end 207.225 132.625)
		(width 0.148)
		(layer "In2.Cu")
		(net 130)
	)
	(arc
		(start 237.049703 113.067192)
		(mid 236.837571 113.15506)
		(end 236.625439 113.067192)
		(width 0.148)
		(layer "In2.Cu")
		(net 130)
	)
	(arc
		(start 207.2 131.8)
		(mid 206.917157 131.917157)
		(end 206.8 132.2)
		(width 0.148)
		(layer "In2.Cu")
		(net 130)
	)
	(arc
		(start 212.9 134.7)
		(mid 212.782843 134.982843)
		(end 212.5 135.1)
		(width 0.148)
		(layer "In2.Cu")
		(net 130)
	)
	(arc
		(start 215.525 129.775)
		(mid 215.415165 130.040165)
		(end 215.15 130.15)
		(width 0.148)
		(layer "In2.Cu")
		(net 130)
	)
	(arc
		(start 207.95 138.15)
		(mid 207.82552 138.45052)
		(end 207.525 138.575)
		(width 0.148)
		(layer "In2.Cu")
		(net 130)
	)
	(arc
		(start 214.4 127.8)
		(mid 214.134835 127.909835)
		(end 214.025 128.175)
		(width 0.148)
		(layer "In2.Cu")
		(net 130)
	)
	(arc
		(start 206.8 133.9)
		(mid 206.917157 134.182843)
		(end 207.2 134.3)
		(width 0.148)
		(layer "In2.Cu")
		(net 130)
	)
	(arc
		(start 209.65 136.45)
		(mid 209.52552 136.75052)
		(end 209.225 136.875)
		(width 0.148)
		(layer "In2.Cu")
		(net 130)
	)
	(arc
		(start 239.025 113.475)
		(mid 238.92981 113.70481)
		(end 238.7 113.8)
		(width 0.148)
		(layer "In2.Cu")
		(net 130)
	)
	(arc
		(start 214.025 129.325)
		(mid 213.915165 129.590165)
		(end 213.65 129.7)
		(width 0.148)
		(layer "In2.Cu")
		(net 130)
	)
	(arc
		(start 235.563679 116.03594)
		(mid 235.688614 116.337561)
		(end 235.563679 116.639182)
		(width 0.148)
		(layer "In2.Cu")
		(net 130)
	)
	(arc
		(start 239.35 113.15)
		(mid 239.12019 113.24519)
		(end 239.025 113.475)
		(width 0.148)
		(layer "In2.Cu")
		(net 130)
	)
	(arc
		(start 207.225 138.575)
		(mid 206.92448 138.69948)
		(end 206.8 139)
		(width 0.148)
		(layer "In2.Cu")
		(net 130)
	)
	(arc
		(start 217.025 128.275)
		(mid 216.915165 128.540165)
		(end 216.65 128.65)
		(width 0.148)
		(layer "In2.Cu")
		(net 130)
	)
	(arc
		(start 207.225 133.475)
		(mid 206.92448 133.59948)
		(end 206.8 133.9)
		(width 0.148)
		(layer "In2.Cu")
		(net 130)
	)
	(arc
		(start 214.775 128.175)
		(mid 214.665165 127.909835)
		(end 214.4 127.8)
		(width 0.148)
		(layer "In2.Cu")
		(net 130)
	)
	(arc
		(start 238.169271 114.033592)
		(mid 237.880555 114.153182)
		(end 237.59184 114.033592)
		(width 0.148)
		(layer "In2.Cu")
		(net 130)
	)
	(arc
		(start 236.872927 114.658181)
		(mid 237.012051 114.994057)
		(end 236.872927 115.329933)
		(width 0.148)
		(layer "In2.Cu")
		(net 130)
	)
	(arc
		(start 234.610185 114.410695)
		(mid 234.471061 114.74657)
		(end 234.610185 115.082445)
		(width 0.148)
		(layer "In2.Cu")
		(net 130)
	)
	(arc
		(start 207.225 136.875)
		(mid 206.92448 136.99948)
		(end 206.8 137.3)
		(width 0.148)
		(layer "In2.Cu")
		(net 130)
	)
	(arc
		(start 206.8 130.55)
		(mid 206.917157 130.832843)
		(end 207.2 130.95)
		(width 0.148)
		(layer "In2.Cu")
		(net 130)
	)
	(arc
		(start 212.5 134.3)
		(mid 212.782843 134.417157)
		(end 212.9 134.7)
		(width 0.148)
		(layer "In2.Cu")
		(net 130)
	)
	(arc
		(start 207.2 135.1)
		(mid 206.917157 135.217157)
		(end 206.8 135.5)
		(width 0.148)
		(layer "In2.Cu")
		(net 130)
	)
	(arc
		(start 209.225 136.025)
		(mid 209.52552 136.14948)
		(end 209.65 136.45)
		(width 0.148)
		(layer "In2.Cu")
		(net 130)
	)
	(arc
		(start 207.525 137.725)
		(mid 207.82552 137.84948)
		(end 207.95 138.15)
		(width 0.148)
		(layer "In2.Cu")
		(net 130)
	)
	(arc
		(start 236.625439 113.067192)
		(mid 236.289563 112.928068)
		(end 235.953688 113.067193)
		(width 0.148)
		(layer "In2.Cu")
		(net 130)
	)
	(arc
		(start 206.8 137.3)
		(mid 206.92448 137.60052)
		(end 207.225 137.725)
		(width 0.148)
		(layer "In2.Cu")
		(net 130)
	)
	(arc
		(start 215.9 127.8)
		(mid 215.634835 127.909835)
		(end 215.525 128.175)
		(width 0.148)
		(layer "In2.Cu")
		(net 130)
	)
	(arc
		(start 237.918552 112.622605)
		(mid 237.70642 112.534737)
		(end 237.494288 112.622607)
		(width 0.148)
		(layer "In2.Cu")
		(net 130)
	)
	(arc
		(start 236.872928 115.329934)
		(mid 236.537052 115.469058)
		(end 236.201176 115.329934)
		(width 0.148)
		(layer "In2.Cu")
		(net 130)
	)
	(arc
		(start 215.15 130.15)
		(mid 214.884835 130.040165)
		(end 214.775 129.775)
		(width 0.148)
		(layer "In2.Cu")
		(net 130)
	)
	(arc
		(start 208.65 133.05)
		(mid 208.52552 133.35052)
		(end 208.225 133.475)
		(width 0.148)
		(layer "In2.Cu")
		(net 130)
	)
	(arc
		(start 235.281936 114.410695)
		(mid 234.94606 114.271571)
		(end 234.610185 114.410696)
		(width 0.148)
		(layer "In2.Cu")
		(net 130)
	)
	(arc
		(start 213.65 129.7)
		(mid 213.384835 129.590165)
		(end 213.275 129.325)
		(width 0.148)
		(layer "In2.Cu")
		(net 130)
	)
	(arc
		(start 206.8 135.6)
		(mid 206.92448 135.90052)
		(end 207.225 136.025)
		(width 0.148)
		(layer "In2.Cu")
		(net 130)
	)
	(arc
		(start 213.275 128.175)
		(mid 213.165165 127.909835)
		(end 212.9 127.8)
		(width 0.148)
		(layer "In2.Cu")
		(net 130)
	)
	(arc
		(start 237.473966 113.915718)
		(mid 237.386098 113.703586)
		(end 237.473966 113.491454)
		(width 0.148)
		(layer "In2.Cu")
		(net 130)
	)
	(arc
		(start 208.225 132.625)
		(mid 208.52552 132.74948)
		(end 208.65 133.05)
		(width 0.148)
		(layer "In2.Cu")
		(net 130)
	)
	(segment
		(start 197.0005 145.9995)
		(end 197.5 145.5)
		(width 0.256)
		(layer "F.Cu")
		(net 131)
	)
	(segment
		(start 244 110.598)
		(end 244 111.75)
		(width 0.38)
		(layer "F.Cu")
		(net 131)
	)
	(via
		(at 244 111.75)
		(size 0.45)
		(drill 0.1)
		(layers "F.Cu" "B.Cu")
		(remove_unused_layers yes)
		(keep_end_layers yes)
		(zone_layer_connections)
		(net 131)
	)
	(via
		(at 197.5 145.5)
		(size 0.45)
		(drill 0.1)
		(layers "F.Cu" "B.Cu")
		(remove_unused_layers yes)
		(keep_end_layers yes)
		(zone_layer_connections)
		(net 131)
	)
	(segment
		(start 223.1 126.1)
		(end 232.55 116.65)
		(width 0.148)
		(layer "In2.Cu")
		(net 131)
	)
	(segment
		(start 234.36561 102.27061)
		(end 234.59 102.27061)
		(width 0.148)
		(layer "In2.Cu")
		(net 131)
	)
	(segment
		(start 237.25 110.4)
		(end 239.15 110.4)
		(width 0.148)
		(layer "In2.Cu")
		(net 131)
	)
	(segment
		(start 237.1 108.35)
		(end 236.6 108.85)
		(width 0.148)
		(layer "In2.Cu")
		(net 131)
	)
	(segment
		(start 239.95 102.57)
		(end 239.95 103.85)
		(width 0.148)
		(layer "In2.Cu")
		(net 131)
	)
	(segment
		(start 230.455636 106.055636)
		(end 229.3 104.9)
		(width 0.148)
		(layer "In2.Cu")
		(net 131)
	)
	(segment
		(start 238.36555 101.695)
		(end 239.075 101.695)
		(width 0.148)
		(layer "In2.Cu")
		(net 131)
	)
	(segment
		(start 232.4 107.411272)
		(end 231.044364 106.055636)
		(width 0.148)
		(layer "In2.Cu")
		(net 131)
	)
	(segment
		(start 237.56555 102.270551)
		(end 237.79 102.270551)
		(width 0.148)
		(layer "In2.Cu")
		(net 131)
	)
	(segment
		(start 208.35 126.1)
		(end 223.1 126.1)
		(width 0.148)
		(layer "In2.Cu")
		(net 131)
	)
	(segment
		(start 231.677775 101.982776)
		(end 231.677775 101.982775)
		(width 0.148)
		(layer "In2.Cu")
		(net 131)
	)
	(segment
		(start 235.16561 101.695)
		(end 235.39 101.695)
		(width 0.148)
		(layer "In2.Cu")
		(net 131)
	)
	(segment
		(start 241.25 112.5)
		(end 243.25 112.5)
		(width 0.148)
		(layer "In2.Cu")
		(net 131)
	)
	(segment
		(start 197.800001 145.499999)
		(end 198.199002 145.100998)
		(width 0.148)
		(layer "In2.Cu")
		(net 131)
	)
	(segment
		(start 232.55 113.26)
		(end 233.6 112.21)
		(width 0.148)
		(layer "In2.Cu")
		(net 131)
	)
	(segment
		(start 204.975 142.475)
		(end 204.975 129.475)
		(width 0.148)
		(layer "In2.Cu")
		(net 131)
	)
	(segment
		(start 238.077775 101.982776)
		(end 238.077775 101.982775)
		(width 0.148)
		(layer "In2.Cu")
		(net 131)
	)
	(segment
		(start 238.1 108.2)
		(end 237.95 108.35)
		(width 0.148)
		(layer "In2.Cu")
		(net 131)
	)
	(segment
		(start 236.6 108.85)
		(end 236.6 109.75)
		(width 0.148)
		(layer "In2.Cu")
		(net 131)
	)
	(segment
		(start 239.075 101.695)
		(end 239.95 102.57)
		(width 0.148)
		(layer "In2.Cu")
		(net 131)
	)
	(segment
		(start 243.25 112.5)
		(end 244 111.75)
		(width 0.148)
		(layer "In2.Cu")
		(net 131)
	)
	(segment
		(start 233.6 111.45)
		(end 232.4 110.25)
		(width 0.148)
		(layer "In2.Cu")
		(net 131)
	)
	(segment
		(start 235.965552 102.270552)
		(end 236.19 102.270552)
		(width 0.148)
		(layer "In2.Cu")
		(net 131)
	)
	(segment
		(start 230.877775 101.982775)
		(end 230.877775 101.982776)
		(width 0.148)
		(layer "In2.Cu")
		(net 131)
	)
	(segment
		(start 197.500001 145.499999)
		(end 197.800001 145.499999)
		(width 0.148)
		(layer "In2.Cu")
		(net 131)
	)
	(segment
		(start 233.56561 101.695)
		(end 233.79 101.695)
		(width 0.148)
		(layer "In2.Cu")
		(net 131)
	)
	(segment
		(start 232.4 107.58)
		(end 232.4 107.411272)
		(width 0.148)
		(layer "In2.Cu")
		(net 131)
	)
	(segment
		(start 236.765552 101.695)
		(end 236.99 101.695)
		(width 0.148)
		(layer "In2.Cu")
		(net 131)
	)
	(segment
		(start 229.3 103.09)
		(end 229.3 102.75)
		(width 0.148)
		(layer "In2.Cu")
		(net 131)
	)
	(segment
		(start 236.6 109.75)
		(end 237.25 110.4)
		(width 0.148)
		(layer "In2.Cu")
		(net 131)
	)
	(segment
		(start 240.809925 110.999264)
		(end 240.597791 111.211395)
		(width 0.148)
		(layer "In2.Cu")
		(net 131)
	)
	(segment
		(start 240.809924 110.999265)
		(end 240.809925 110.999264)
		(width 0.148)
		(layer "In2.Cu")
		(net 131)
	)
	(segment
		(start 233.35 107.93)
		(end 232.75 107.93)
		(width 0.148)
		(layer "In2.Cu")
		(net 131)
	)
	(segment
		(start 237.95 108.35)
		(end 237.1 108.35)
		(width 0.148)
		(layer "In2.Cu")
		(net 131)
	)
	(segment
		(start 231.044364 106.055636)
		(end 230.455636 106.055636)
		(width 0.148)
		(layer "In2.Cu")
		(net 131)
	)
	(segment
		(start 229.675 104.215)
		(end 229.825 104.215)
		(width 0.148)
		(layer "In2.Cu")
		(net 131)
	)
	(segment
		(start 232.4 110.25)
		(end 232.4 108.98)
		(width 0.148)
		(layer "In2.Cu")
		(net 131)
	)
	(segment
		(start 238.1 105.7)
		(end 238.1 108.2)
		(width 0.148)
		(layer "In2.Cu")
		(net 131)
	)
	(segment
		(start 229.3 104.9)
		(end 229.3 104.59)
		(width 0.148)
		(layer "In2.Cu")
		(net 131)
	)
	(segment
		(start 237.277775 101.982775)
		(end 237.277775 101.982776)
		(width 0.148)
		(layer "In2.Cu")
		(net 131)
	)
	(segment
		(start 240.597792 111.847792)
		(end 241.25 112.5)
		(width 0.148)
		(layer "In2.Cu")
		(net 131)
	)
	(segment
		(start 230.355 101.695)
		(end 230.59 101.695)
		(width 0.148)
		(layer "In2.Cu")
		(net 131)
	)
	(segment
		(start 232.75 108.63)
		(end 233.35 108.63)
		(width 0.148)
		(layer "In2.Cu")
		(net 131)
	)
	(segment
		(start 229.825 103.465)
		(end 229.675 103.465)
		(width 0.148)
		(layer "In2.Cu")
		(net 131)
	)
	(segment
		(start 229.3 102.75)
		(end 230.355 101.695)
		(width 0.148)
		(layer "In2.Cu")
		(net 131)
	)
	(segment
		(start 202.349002 145.100998)
		(end 204.975 142.475)
		(width 0.148)
		(layer "In2.Cu")
		(net 131)
	)
	(segment
		(start 232.76561 102.27061)
		(end 232.99 102.27061)
		(width 0.148)
		(layer "In2.Cu")
		(net 131)
	)
	(segment
		(start 204.975 129.475)
		(end 208.35 126.1)
		(width 0.148)
		(layer "In2.Cu")
		(net 131)
	)
	(segment
		(start 239.961397 110.574999)
		(end 240.173529 110.362868)
		(width 0.148)
		(layer "In2.Cu")
		(net 131)
	)
	(segment
		(start 233.6 112.21)
		(end 233.6 111.45)
		(width 0.148)
		(layer "In2.Cu")
		(net 131)
	)
	(segment
		(start 240.809926 110.362869)
		(end 240.809925 110.362868)
		(width 0.148)
		(layer "In2.Cu")
		(net 131)
	)
	(segment
		(start 198.199002 145.100998)
		(end 202.349002 145.100998)
		(width 0.148)
		(layer "In2.Cu")
		(net 131)
	)
	(segment
		(start 239.95 103.85)
		(end 238.1 105.7)
		(width 0.148)
		(layer "In2.Cu")
		(net 131)
	)
	(segment
		(start 231.16555 102.270551)
		(end 231.39 102.270551)
		(width 0.148)
		(layer "In2.Cu")
		(net 131)
	)
	(segment
		(start 232.55 116.65)
		(end 232.55 113.26)
		(width 0.148)
		(layer "In2.Cu")
		(net 131)
	)
	(segment
		(start 231.96555 101.695)
		(end 232.19 101.695)
		(width 0.148)
		(layer "In2.Cu")
		(net 131)
	)
	(segment
		(start 239.15 110.4)
		(end 239.325 110.575)
		(width 0.148)
		(layer "In2.Cu")
		(net 131)
	)
	(arc
		(start 229.675 103.465)
		(mid 229.409835 103.355165)
		(end 229.3 103.09)
		(width 0.148)
		(layer "In2.Cu")
		(net 131)
	)
	(arc
		(start 234.877805 101.982805)
		(mid 234.962101 101.779296)
		(end 235.16561 101.695)
		(width 0.148)
		(layer "In2.Cu")
		(net 131)
	)
	(arc
		(start 236.477776 101.982776)
		(mid 236.562064 101.779288)
		(end 236.765552 101.695)
		(width 0.148)
		(layer "In2.Cu")
		(net 131)
	)
	(arc
		(start 235.677776 101.982776)
		(mid 235.762064 102.186264)
		(end 235.965552 102.270552)
		(width 0.148)
		(layer "In2.Cu")
		(net 131)
	)
	(arc
		(start 240.809925 110.362868)
		(mid 240.941726 110.681066)
		(end 240.809924 110.999265)
		(width 0.148)
		(layer "In2.Cu")
		(net 131)
	)
	(arc
		(start 232.477805 101.982805)
		(mid 232.562101 102.186314)
		(end 232.76561 102.27061)
		(width 0.148)
		(layer "In2.Cu")
		(net 131)
	)
	(arc
		(start 237.79 102.270551)
		(mid 237.993488 102.186264)
		(end 238.077775 101.982776)
		(width 0.148)
		(layer "In2.Cu")
		(net 131)
	)
	(arc
		(start 240.173529 110.362868)
		(mid 240.491727 110.231065)
		(end 240.809926 110.362869)
		(width 0.148)
		(layer "In2.Cu")
		(net 131)
	)
	(arc
		(start 236.99 101.695)
		(mid 237.193488 101.779287)
		(end 237.277775 101.982775)
		(width 0.148)
		(layer "In2.Cu")
		(net 131)
	)
	(arc
		(start 235.39 101.695)
		(mid 235.593488 101.779288)
		(end 235.677776 101.982776)
		(width 0.148)
		(layer "In2.Cu")
		(net 131)
	)
	(arc
		(start 233.7 108.28)
		(mid 233.597487 108.032513)
		(end 233.35 107.93)
		(width 0.148)
		(layer "In2.Cu")
		(net 131)
	)
	(arc
		(start 230.59 101.695)
		(mid 230.793488 101.779287)
		(end 230.877775 101.982775)
		(width 0.148)
		(layer "In2.Cu")
		(net 131)
	)
	(arc
		(start 233.277805 101.982805)
		(mid 233.362101 101.779296)
		(end 233.56561 101.695)
		(width 0.148)
		(layer "In2.Cu")
		(net 131)
	)
	(arc
		(start 232.99 102.27061)
		(mid 233.193509 102.186314)
		(end 233.277805 101.982805)
		(width 0.148)
		(layer "In2.Cu")
		(net 131)
	)
	(arc
		(start 231.677775 101.982775)
		(mid 231.762062 101.779287)
		(end 231.96555 101.695)
		(width 0.148)
		(layer "In2.Cu")
		(net 131)
	)
	(arc
		(start 231.39 102.270551)
		(mid 231.593488 102.186264)
		(end 231.677775 101.982776)
		(width 0.148)
		(layer "In2.Cu")
		(net 131)
	)
	(arc
		(start 233.35 108.63)
		(mid 233.597487 108.527487)
		(end 233.7 108.28)
		(width 0.148)
		(layer "In2.Cu")
		(net 131)
	)
	(arc
		(start 234.59 102.27061)
		(mid 234.793509 102.186314)
		(end 234.877805 101.982805)
		(width 0.148)
		(layer "In2.Cu")
		(net 131)
	)
	(arc
		(start 239.325 110.575)
		(mid 239.6432 110.706803)
		(end 239.961397 110.574999)
		(width 0.148)
		(layer "In2.Cu")
		(net 131)
	)
	(arc
		(start 229.825 104.215)
		(mid 230.090165 104.105165)
		(end 230.2 103.84)
		(width 0.148)
		(layer "In2.Cu")
		(net 131)
	)
	(arc
		(start 237.277775 101.982776)
		(mid 237.362062 102.186264)
		(end 237.56555 102.270551)
		(width 0.148)
		(layer "In2.Cu")
		(net 131)
	)
	(arc
		(start 232.75 107.93)
		(mid 232.502513 107.827487)
		(end 232.4 107.58)
		(width 0.148)
		(layer "In2.Cu")
		(net 131)
	)
	(arc
		(start 230.2 103.84)
		(mid 230.090165 103.574835)
		(end 229.825 103.465)
		(width 0.148)
		(layer "In2.Cu")
		(net 131)
	)
	(arc
		(start 230.877775 101.982776)
		(mid 230.962062 102.186264)
		(end 231.16555 102.270551)
		(width 0.148)
		(layer "In2.Cu")
		(net 131)
	)
	(arc
		(start 240.597791 111.211395)
		(mid 240.46599 111.529595)
		(end 240.597792 111.847792)
		(width 0.148)
		(layer "In2.Cu")
		(net 131)
	)
	(arc
		(start 233.79 101.695)
		(mid 233.993509 101.779296)
		(end 234.077805 101.982805)
		(width 0.148)
		(layer "In2.Cu")
		(net 131)
	)
	(arc
		(start 232.19 101.695)
		(mid 232.393509 101.779296)
		(end 232.477805 101.982805)
		(width 0.148)
		(layer "In2.Cu")
		(net 131)
	)
	(arc
		(start 234.077805 101.982805)
		(mid 234.162101 102.186314)
		(end 234.36561 102.27061)
		(width 0.148)
		(layer "In2.Cu")
		(net 131)
	)
	(arc
		(start 236.19 102.270552)
		(mid 236.393488 102.186264)
		(end 236.477776 101.982776)
		(width 0.148)
		(layer "In2.Cu")
		(net 131)
	)
	(arc
		(start 238.077775 101.982775)
		(mid 238.162062 101.779287)
		(end 238.36555 101.695)
		(width 0.148)
		(layer "In2.Cu")
		(net 131)
	)
	(arc
		(start 229.3 104.59)
		(mid 229.409835 104.324835)
		(end 229.675 104.215)
		(width 0.148)
		(layer "In2.Cu")
		(net 131)
	)
	(arc
		(start 232.4 108.98)
		(mid 232.502513 108.732513)
		(end 232.75 108.63)
		(width 0.148)
		(layer "In2.Cu")
		(net 131)
	)
	(segment
		(start 185.9995 147.9995)
		(end 185.500001 147.5)
		(width 0.256)
		(layer "F.Cu")
		(net 132)
	)
	(segment
		(start 159 106)
		(end 159 107.152)
		(width 0.38)
		(layer "F.Cu")
		(net 132)
	)
	(via
		(at 185.500001 147.5)
		(size 0.45)
		(drill 0.1)
		(layers "F.Cu" "B.Cu")
		(remove_unused_layers yes)
		(keep_end_layers yes)
		(zone_layer_connections)
		(net 132)
	)
	(via
		(at 159 107.152)
		(size 0.45)
		(drill 0.1)
		(layers "F.Cu" "B.Cu")
		(remove_unused_layers yes)
		(keep_end_layers yes)
		(zone_layer_connections)
		(net 132)
	)
	(segment
		(start 158.695 107.457)
		(end 159 107.152)
		(width 0.13)
		(layer "In2.Cu")
		(net 132)
	)
	(segment
		(start 182.07 123.832364)
		(end 182.07 120.810955)
		(width 0.13)
		(layer "In2.Cu")
		(net 132)
	)
	(segment
		(start 181.850329 120.280624)
		(end 181.747352 120.177647)
		(width 0.13)
		(layer "In2.Cu")
		(net 132)
	)
	(segment
		(start 190.1 145.841422)
		(end 190.1 143.291422)
		(width 0.1)
		(layer "In2.Cu")
		(net 132)
	)
	(segment
		(start 185.225 147.5)
		(end 185.113113 147.388113)
		(width 0.1)
		(layer "In2.Cu")
		(net 132)
	)
	(segment
		(start 189.841422 146.1)
		(end 190.1 145.841422)
		(width 0.1)
		(layer "In2.Cu")
		(net 132)
	)
	(segment
		(start 185.113113 147.388113)
		(end 185.113113 147.20873)
		(width 0.1)
		(layer "In2.Cu")
		(net 132)
	)
	(segment
		(start 181.832204 118.656329)
		(end 181.312999 118.137124)
		(width 0.13)
		(layer "In2.Cu")
		(net 132)
	)
	(segment
		(start 159.87 111.175294)
		(end 158.42 109.725294)
		(width 0.13)
		(layer "In2.Cu")
		(net 132)
	)
	(segment
		(start 185.221843 147.1)
		(end 188.141422 147.1)
		(width 0.1)
		(layer "In2.Cu")
		(net 132)
	)
	(segment
		(start 159.87 114.000294)
		(end 159.87 111.175294)
		(width 0.13)
		(layer "In2.Cu")
		(net 132)
	)
	(segment
		(start 179.791681 118.221976)
		(end 177.649706 116.08)
		(width 0.13)
		(layer "In2.Cu")
		(net 132)
	)
	(segment
		(start 181.747352 119.629119)
		(end 181.747352 119.62912)
		(width 0.13)
		(layer "In2.Cu")
		(net 132)
	)
	(segment
		(start 191.122374 142.719048)
		(end 191.122374 138.598301)
		(width 0.1)
		(layer "In2.Cu")
		(net 132)
	)
	(segment
		(start 191.13315 138.587525)
		(end 191.13315 132.895514)
		(width 0.13)
		(layer "In2.Cu")
		(net 132)
	)
	(segment
		(start 190.741422 143.1)
		(end 191.122374 142.719048)
		(width 0.1)
		(layer "In2.Cu")
		(net 132)
	)
	(segment
		(start 180.425061 118.137124)
		(end 180.340208 118.221976)
		(width 0.13)
		(layer "In2.Cu")
		(net 132)
	)
	(segment
		(start 189.141422 146.1)
		(end 189.841422 146.1)
		(width 0.1)
		(layer "In2.Cu")
		(net 132)
	)
	(segment
		(start 177.649706 116.08)
		(end 161.949706 116.08)
		(width 0.13)
		(layer "In2.Cu")
		(net 132)
	)
	(segment
		(start 179.791681 118.221977)
		(end 179.791681 118.221976)
		(width 0.13)
		(layer "In2.Cu")
		(net 132)
	)
	(segment
		(start 185.113113 147.20873)
		(end 185.221843 147.1)
		(width 0.1)
		(layer "In2.Cu")
		(net 132)
	)
	(segment
		(start 191.122374 138.598301)
		(end 191.13315 138.587525)
		(width 0.1)
		(layer "In2.Cu")
		(net 132)
	)
	(segment
		(start 161.949706 116.08)
		(end 159.87 114.000294)
		(width 0.13)
		(layer "In2.Cu")
		(net 132)
	)
	(segment
		(start 191.13315 132.895514)
		(end 182.07 123.832364)
		(width 0.13)
		(layer "In2.Cu")
		(net 132)
	)
	(segment
		(start 188.141422 147.1)
		(end 189.141422 146.1)
		(width 0.1)
		(layer "In2.Cu")
		(net 132)
	)
	(segment
		(start 158.695 108.649706)
		(end 158.695 107.457)
		(width 0.13)
		(layer "In2.Cu")
		(net 132)
	)
	(segment
		(start 190.1 143.291422)
		(end 190.291422 143.1)
		(width 0.1)
		(layer "In2.Cu")
		(net 132)
	)
	(segment
		(start 158.42 108.924706)
		(end 158.695 108.649706)
		(width 0.13)
		(layer "In2.Cu")
		(net 132)
	)
	(segment
		(start 158.42 109.725294)
		(end 158.42 108.924706)
		(width 0.13)
		(layer "In2.Cu")
		(net 132)
	)
	(segment
		(start 181.747352 119.62912)
		(end 181.832204 119.544267)
		(width 0.13)
		(layer "In2.Cu")
		(net 132)
	)
	(segment
		(start 190.291422 143.1)
		(end 190.741422 143.1)
		(width 0.1)
		(layer "In2.Cu")
		(net 132)
	)
	(segment
		(start 185.500001 147.5)
		(end 185.225 147.5)
		(width 0.1)
		(layer "In2.Cu")
		(net 132)
	)
	(arc
		(start 181.312999 118.137124)
		(mid 180.86903 117.953226)
		(end 180.425061 118.137124)
		(width 0.13)
		(layer "In2.Cu")
		(net 132)
	)
	(arc
		(start 181.850329 120.280624)
		(mid 182.012909 120.523942)
		(end 182.07 120.810955)
		(width 0.13)
		(layer "In2.Cu")
		(net 132)
	)
	(arc
		(start 181.747352 120.177647)
		(mid 181.633748 119.903383)
		(end 181.747352 119.629119)
		(width 0.13)
		(layer "In2.Cu")
		(net 132)
	)
	(arc
		(start 181.832204 119.544267)
		(mid 182.016102 119.100298)
		(end 181.832204 118.656329)
		(width 0.13)
		(layer "In2.Cu")
		(net 132)
	)
	(arc
		(start 180.340208 118.221976)
		(mid 180.065945 118.33558)
		(end 179.791681 118.221977)
		(width 0.13)
		(layer "In2.Cu")
		(net 132)
	)
	(segment
		(start 184.9995 147.9995)
		(end 184.5 147.5)
		(width 0.256)
		(layer "F.Cu")
		(net 133)
	)
	(segment
		(start 158.15 106)
		(end 158.15 107.152)
		(width 0.38)
		(layer "F.Cu")
		(net 133)
	)
	(via
		(at 184.5 147.5)
		(size 0.45)
		(drill 0.1)
		(layers "F.Cu" "B.Cu")
		(remove_unused_layers yes)
		(keep_end_layers yes)
		(zone_layer_connections)
		(net 133)
	)
	(via
		(at 158.15 107.152)
		(size 0.45)
		(drill 0.1)
		(layers "F.Cu" "B.Cu")
		(remove_unused_layers yes)
		(keep_end_layers yes)
		(zone_layer_connections)
		(net 133)
	)
	(segment
		(start 158.18 109.824706)
		(end 158.18 108.825294)
		(width 0.13)
		(layer "In2.Cu")
		(net 133)
	)
	(segment
		(start 188.058578 146.9)
		(end 189.058578 145.9)
		(width 0.1)
		(layer "In2.Cu")
		(net 133)
	)
	(segment
		(start 190.208578 142.9)
		(end 190.658578 142.9)
		(width 0.1)
		(layer "In2.Cu")
		(net 133)
	)
	(segment
		(start 180.594767 118.306829)
		(end 180.509914 118.391681)
		(width 0.13)
		(layer "In2.Cu")
		(net 133)
	)
	(segment
		(start 187.2 146.9)
		(end 187.25 146.9)
		(width 0.1)
		(layer "In2.Cu")
		(net 133)
	)
	(segment
		(start 190.658578 142.9)
		(end 190.922374 142.636204)
		(width 0.1)
		(layer "In2.Cu")
		(net 133)
	)
	(segment
		(start 159.63 114.099706)
		(end 159.63 111.274706)
		(width 0.13)
		(layer "In2.Cu")
		(net 133)
	)
	(segment
		(start 190.922374 142.636204)
		(end 190.922374 138.647374)
		(width 0.1)
		(layer "In2.Cu")
		(net 133)
	)
	(segment
		(start 180.594768 118.306829)
		(end 180.594767 118.306829)
		(width 0.13)
		(layer "In2.Cu")
		(net 133)
	)
	(segment
		(start 179.621976 118.391681)
		(end 177.550294 116.32)
		(width 0.13)
		(layer "In2.Cu")
		(net 133)
	)
	(segment
		(start 190.89315 132.980786)
		(end 181.83 123.917636)
		(width 0.13)
		(layer "In2.Cu")
		(net 133)
	)
	(segment
		(start 184.913113 147.361887)
		(end 184.913113 147.125887)
		(width 0.1)
		(layer "In2.Cu")
		(net 133)
	)
	(segment
		(start 161.850294 116.32)
		(end 159.63 114.099706)
		(width 0.13)
		(layer "In2.Cu")
		(net 133)
	)
	(segment
		(start 184.775 147.5)
		(end 184.913113 147.361887)
		(width 0.1)
		(layer "In2.Cu")
		(net 133)
	)
	(segment
		(start 190.922374 138.647374)
		(end 190.89315 138.61815)
		(width 0.1)
		(layer "In2.Cu")
		(net 133)
	)
	(segment
		(start 181.6625 118.826034)
		(end 181.662499 118.826034)
		(width 0.13)
		(layer "In2.Cu")
		(net 133)
	)
	(segment
		(start 189.758578 145.9)
		(end 189.9 145.758578)
		(width 0.1)
		(layer "In2.Cu")
		(net 133)
	)
	(segment
		(start 158.455 107.455)
		(end 158.152 107.152)
		(width 0.13)
		(layer "In2.Cu")
		(net 133)
	)
	(segment
		(start 181.83 123.917636)
		(end 181.83 120.862658)
		(width 0.13)
		(layer "In2.Cu")
		(net 133)
	)
	(segment
		(start 158.18 108.825294)
		(end 158.455 108.550294)
		(width 0.13)
		(layer "In2.Cu")
		(net 133)
	)
	(segment
		(start 190.89315 138.61815)
		(end 190.89315 132.980786)
		(width 0.13)
		(layer "In2.Cu")
		(net 133)
	)
	(segment
		(start 187.25 146.9)
		(end 188.058578 146.9)
		(width 0.1)
		(layer "In2.Cu")
		(net 133)
	)
	(segment
		(start 189.9 145.758578)
		(end 189.9 143.208578)
		(width 0.1)
		(layer "In2.Cu")
		(net 133)
	)
	(segment
		(start 189.9 143.208578)
		(end 190.208578 142.9)
		(width 0.1)
		(layer "In2.Cu")
		(net 133)
	)
	(segment
		(start 187 146.75)
		(end 187.05 146.75)
		(width 0.1)
		(layer "In2.Cu")
		(net 133)
	)
	(segment
		(start 181.662499 118.826034)
		(end 181.143294 118.306829)
		(width 0.13)
		(layer "In2.Cu")
		(net 133)
	)
	(segment
		(start 158.152 107.152)
		(end 158.15 107.152)
		(width 0.13)
		(layer "In2.Cu")
		(net 133)
	)
	(segment
		(start 181.644064 120.413769)
		(end 181.577647 120.347352)
		(width 0.13)
		(layer "In2.Cu")
		(net 133)
	)
	(segment
		(start 181.577647 119.459414)
		(end 181.662499 119.374561)
		(width 0.13)
		(layer "In2.Cu")
		(net 133)
	)
	(segment
		(start 159.63 111.274706)
		(end 158.18 109.824706)
		(width 0.13)
		(layer "In2.Cu")
		(net 133)
	)
	(segment
		(start 177.550294 116.32)
		(end 161.850294 116.32)
		(width 0.13)
		(layer "In2.Cu")
		(net 133)
	)
	(segment
		(start 158.455 108.550294)
		(end 158.455 107.455)
		(width 0.13)
		(layer "In2.Cu")
		(net 133)
	)
	(segment
		(start 189.058578 145.9)
		(end 189.758578 145.9)
		(width 0.1)
		(layer "In2.Cu")
		(net 133)
	)
	(segment
		(start 185.139001 146.9)
		(end 186.85 146.9)
		(width 0.1)
		(layer "In2.Cu")
		(net 133)
	)
	(segment
		(start 184.500001 147.5)
		(end 184.775 147.5)
		(width 0.1)
		(layer "In2.Cu")
		(net 133)
	)
	(segment
		(start 184.913113 147.125887)
		(end 185.139001 146.9)
		(width 0.1)
		(layer "In2.Cu")
		(net 133)
	)
	(arc
		(start 181.662499 119.374561)
		(mid 181.776103 119.100298)
		(end 181.6625 118.826034)
		(width 0.13)
		(layer "In2.Cu")
		(net 133)
	)
	(arc
		(start 181.83 120.862658)
		(mid 181.781677 120.619721)
		(end 181.644064 120.413769)
		(width 0.13)
		(layer "In2.Cu")
		(net 133)
	)
	(arc
		(start 181.577647 120.347352)
		(mid 181.393749 119.903383)
		(end 181.577647 119.459414)
		(width 0.13)
		(layer "In2.Cu")
		(net 133)
	)
	(arc
		(start 186.85 146.9)
		(mid 186.903033 146.878033)
		(end 186.925 146.825)
		(width 0.1)
		(layer "In2.Cu")
		(net 133)
	)
	(arc
		(start 186.925 146.825)
		(mid 186.946967 146.771967)
		(end 187 146.75)
		(width 0.1)
		(layer "In2.Cu")
		(net 133)
	)
	(arc
		(start 181.143294 118.306829)
		(mid 180.869031 118.193226)
		(end 180.594768 118.306829)
		(width 0.13)
		(layer "In2.Cu")
		(net 133)
	)
	(arc
		(start 180.509914 118.391681)
		(mid 180.065945 118.575579)
		(end 179.621976 118.391681)
		(width 0.13)
		(layer "In2.Cu")
		(net 133)
	)
	(arc
		(start 187.05 146.75)
		(mid 187.103033 146.771967)
		(end 187.125 146.825)
		(width 0.1)
		(layer "In2.Cu")
		(net 133)
	)
	(arc
		(start 187.125 146.825)
		(mid 187.146967 146.878033)
		(end 187.2 146.9)
		(width 0.1)
		(layer "In2.Cu")
		(net 133)
	)
	(segment
		(start 239.751 110.598)
		(end 239.751 109.446)
		(width 0.38)
		(layer "F.Cu")
		(net 134)
	)
	(segment
		(start 196.000501 148.9995)
		(end 196.5 148.5)
		(width 0.256)
		(layer "F.Cu")
		(net 134)
	)
	(via
		(at 239.751 109.446)
		(size 0.45)
		(drill 0.1)
		(layers "F.Cu" "B.Cu")
		(remove_unused_layers yes)
		(keep_end_layers yes)
		(zone_layer_connections)
		(net 134)
	)
	(via
		(at 196.5 148.5)
		(size 0.45)
		(drill 0.1)
		(layers "F.Cu" "B.Cu")
		(remove_unused_layers yes)
		(keep_end_layers yes)
		(zone_layer_connections)
		(net 134)
	)
	(segment
		(start 232.2 129.75)
		(end 231.9625 129.9875)
		(width 0.148)
		(layer "In2.Cu")
		(net 134)
	)
	(segment
		(start 230.689706 130.836029)
		(end 230.689707 130.836029)
		(width 0.148)
		(layer "In2.Cu")
		(net 134)
	)
	(segment
		(start 229.416914 132.533085)
		(end 229.416915 132.533086)
		(width 0.148)
		(layer "In2.Cu")
		(net 134)
	)
	(segment
		(start 223.202094 137.7734)
		(end 223.477214 138.04852)
		(width 0.148)
		(layer "In2.Cu")
		(net 134)
	)
	(segment
		(start 223.901479 137.624257)
		(end 223.626358 137.349136)
		(width 0.148)
		(layer "In2.Cu")
		(net 134)
	)
	(segment
		(start 222.628686 139.321313)
		(end 221.867655 140.082346)
		(width 0.148)
		(layer "In2.Cu")
		(net 134)
	)
	(segment
		(start 228.992649 132.533086)
		(end 228.99265 132.533086)
		(width 0.148)
		(layer "In2.Cu")
		(net 134)
	)
	(segment
		(start 226.447064 135.078671)
		(end 226.171888 134.803495)
		(width 0.148)
		(layer "In2.Cu")
		(net 134)
	)
	(segment
		(start 231.113971 130.836028)
		(end 231.113972 130.836029)
		(width 0.148)
		(layer "In2.Cu")
		(net 134)
	)
	(segment
		(start 243.325 117.475)
		(end 232.2 128.6)
		(width 0.148)
		(layer "In2.Cu")
		(net 134)
	)
	(segment
		(start 227.444718 133.530739)
		(end 227.719856 133.805877)
		(width 0.148)
		(layer "In2.Cu")
		(net 134)
	)
	(segment
		(start 224.050602 136.924851)
		(end 224.325742 137.199991)
		(width 0.148)
		(layer "In2.Cu")
		(net 134)
	)
	(segment
		(start 230.265442 131.684556)
		(end 230.265443 131.684557)
		(width 0.148)
		(layer "In2.Cu")
		(net 134)
	)
	(segment
		(start 226.447063 135.078671)
		(end 226.447064 135.078671)
		(width 0.148)
		(layer "In2.Cu")
		(net 134)
	)
	(segment
		(start 224.325742 137.624255)
		(end 224.325743 137.624256)
		(width 0.148)
		(layer "In2.Cu")
		(net 134)
	)
	(segment
		(start 228.14412 133.381614)
		(end 228.144121 133.381614)
		(width 0.148)
		(layer "In2.Cu")
		(net 134)
	)
	(segment
		(start 227.719857 134.230142)
		(end 227.719858 134.230143)
		(width 0.148)
		(layer "In2.Cu")
		(net 134)
	)
	(segment
		(start 232.2 128.6)
		(end 232.2 129.75)
		(width 0.148)
		(layer "In2.Cu")
		(net 134)
	)
	(segment
		(start 231.538235 129.9875)
		(end 231.263096 129.712361)
		(width 0.148)
		(layer "In2.Cu")
		(net 134)
	)
	(segment
		(start 227.719856 134.230141)
		(end 227.719857 134.230142)
		(width 0.148)
		(layer "In2.Cu")
		(net 134)
	)
	(segment
		(start 223.052949 138.472785)
		(end 223.05295 138.472785)
		(width 0.148)
		(layer "In2.Cu")
		(net 134)
	)
	(segment
		(start 196.975 150.444669)
		(end 196.95 150.419669)
		(width 0.148)
		(layer "In2.Cu")
		(net 134)
	)
	(segment
		(start 225.598535 135.9272)
		(end 225.598536 135.9272)
		(width 0.148)
		(layer "In2.Cu")
		(net 134)
	)
	(segment
		(start 196.505331 149.975)
		(end 196.325 149.975)
		(width 0.1)
		(layer "In2.Cu")
		(net 134)
	)
	(segment
		(start 229.841177 131.684557)
		(end 229.841178 131.684557)
		(width 0.148)
		(layer "In2.Cu")
		(net 134)
	)
	(segment
		(start 245.55 117.475)
		(end 243.325 117.475)
		(width 0.148)
		(layer "In2.Cu")
		(net 134)
	)
	(segment
		(start 196.124999 149.325001)
		(end 196.5 148.95)
		(width 0.1)
		(layer "In2.Cu")
		(net 134)
	)
	(segment
		(start 223.901478 137.624257)
		(end 223.901479 137.624257)
		(width 0.148)
		(layer "In2.Cu")
		(net 134)
	)
	(segment
		(start 230.838832 130.136625)
		(end 231.11397 130.411763)
		(width 0.148)
		(layer "In2.Cu")
		(net 134)
	)
	(segment
		(start 229.416913 132.533085)
		(end 229.416914 132.533085)
		(width 0.148)
		(layer "In2.Cu")
		(net 134)
	)
	(segment
		(start 201.974 150.95)
		(end 197.15 150.95)
		(width 0.148)
		(layer "In2.Cu")
		(net 134)
	)
	(segment
		(start 225.598536 135.9272)
		(end 225.323397 135.652061)
		(width 0.148)
		(layer "In2.Cu")
		(net 134)
	)
	(segment
		(start 223.05295 138.472785)
		(end 222.777811 138.197646)
		(width 0.148)
		(layer "In2.Cu")
		(net 134)
	)
	(segment
		(start 225.174271 136.775727)
		(end 225.174272 136.775728)
		(width 0.148)
		(layer "In2.Cu")
		(net 134)
	)
	(segment
		(start 243.7 104.275)
		(end 249.275 104.275)
		(width 0.148)
		(layer "In2.Cu")
		(net 134)
	)
	(segment
		(start 229.141811 131.833719)
		(end 229.416913 132.108821)
		(width 0.148)
		(layer "In2.Cu")
		(net 134)
	)
	(segment
		(start 227.295592 134.230143)
		(end 227.295593 134.230143)
		(width 0.148)
		(layer "In2.Cu")
		(net 134)
	)
	(segment
		(start 231.538234 129.9875)
		(end 231.538235 129.9875)
		(width 0.148)
		(layer "In2.Cu")
		(net 134)
	)
	(segment
		(start 196.124999 149.774999)
		(end 196.124999 149.325001)
		(width 0.1)
		(layer "In2.Cu")
		(net 134)
	)
	(segment
		(start 229.990304 130.985154)
		(end 230.265442 131.260292)
		(width 0.148)
		(layer "In2.Cu")
		(net 134)
	)
	(segment
		(start 226.022799 135.927198)
		(end 226.0228 135.927199)
		(width 0.148)
		(layer "In2.Cu")
		(net 134)
	)
	(segment
		(start 249.275 104.275)
		(end 250.375 105.375)
		(width 0.148)
		(layer "In2.Cu")
		(net 134)
	)
	(segment
		(start 225.747624 135.227759)
		(end 226.022799 135.502934)
		(width 0.148)
		(layer "In2.Cu")
		(net 134)
	)
	(segment
		(start 250.375 105.375)
		(end 250.375 112.65)
		(width 0.148)
		(layer "In2.Cu")
		(net 134)
	)
	(segment
		(start 241.85 106.125)
		(end 243.7 104.275)
		(width 0.148)
		(layer "In2.Cu")
		(net 134)
	)
	(segment
		(start 204.65 150.65)
		(end 202.274 150.65)
		(width 0.148)
		(layer "In2.Cu")
		(net 134)
	)
	(segment
		(start 227.295593 134.230143)
		(end 227.020481 133.955031)
		(width 0.148)
		(layer "In2.Cu")
		(net 134)
	)
	(segment
		(start 202.274 150.65)
		(end 201.974 150.95)
		(width 0.148)
		(layer "In2.Cu")
		(net 134)
	)
	(segment
		(start 222.353547 138.62191)
		(end 222.628685 138.897048)
		(width 0.148)
		(layer "In2.Cu")
		(net 134)
	)
	(segment
		(start 220.85 141.1)
		(end 214.2 141.1)
		(width 0.148)
		(layer "In2.Cu")
		(net 134)
	)
	(segment
		(start 228.568385 133.381613)
		(end 228.568386 133.381614)
		(width 0.148)
		(layer "In2.Cu")
		(net 134)
	)
	(segment
		(start 228.293247 132.682211)
		(end 228.568385 132.957349)
		(width 0.148)
		(layer "In2.Cu")
		(net 134)
	)
	(segment
		(start 221.867655 140.082346)
		(end 221.867651 140.082346)
		(width 0.148)
		(layer "In2.Cu")
		(net 134)
	)
	(segment
		(start 228.99265 132.533086)
		(end 228.717511 132.257947)
		(width 0.148)
		(layer "In2.Cu")
		(net 134)
	)
	(segment
		(start 229.841178 131.684557)
		(end 229.566075 131.409454)
		(width 0.148)
		(layer "In2.Cu")
		(net 134)
	)
	(segment
		(start 228.144121 133.381614)
		(end 227.868982 133.106475)
		(width 0.148)
		(layer "In2.Cu")
		(net 134)
	)
	(segment
		(start 226.871328 135.07867)
		(end 226.871329 135.078671)
		(width 0.148)
		(layer "In2.Cu")
		(net 134)
	)
	(segment
		(start 197.15 150.95)
		(end 196.975 150.775)
		(width 0.148)
		(layer "In2.Cu")
		(net 134)
	)
	(segment
		(start 196.325 149.975)
		(end 196.124999 149.774999)
		(width 0.1)
		(layer "In2.Cu")
		(net 134)
	)
	(segment
		(start 223.477214 138.472784)
		(end 223.477215 138.472785)
		(width 0.148)
		(layer "In2.Cu")
		(net 134)
	)
	(segment
		(start 222.628685 139.321312)
		(end 222.628686 139.321313)
		(width 0.148)
		(layer "In2.Cu")
		(net 134)
	)
	(segment
		(start 226.596217 134.379295)
		(end 226.871328 134.654406)
		(width 0.148)
		(layer "In2.Cu")
		(net 134)
	)
	(segment
		(start 224.899133 136.076325)
		(end 225.174271 136.351463)
		(width 0.148)
		(layer "In2.Cu")
		(net 134)
	)
	(segment
		(start 250.375 112.65)
		(end 245.55 117.475)
		(width 0.148)
		(layer "In2.Cu")
		(net 134)
	)
	(segment
		(start 226.0228 135.927199)
		(end 226.022801 135.9272)
		(width 0.148)
		(layer "In2.Cu")
		(net 134)
	)
	(segment
		(start 224.750007 136.775728)
		(end 224.474866 136.500587)
		(width 0.148)
		(layer "In2.Cu")
		(net 134)
	)
	(segment
		(start 224.750006 136.775728)
		(end 224.750007 136.775728)
		(width 0.148)
		(layer "In2.Cu")
		(net 134)
	)
	(segment
		(start 221.867651 140.082346)
		(end 220.85 141.1)
		(width 0.148)
		(layer "In2.Cu")
		(net 134)
	)
	(segment
		(start 224.325743 137.624256)
		(end 224.325744 137.624257)
		(width 0.148)
		(layer "In2.Cu")
		(net 134)
	)
	(segment
		(start 239.751 109.446)
		(end 241.85 107.347)
		(width 0.148)
		(layer "In2.Cu")
		(net 134)
	)
	(segment
		(start 214.2 141.1)
		(end 204.65 150.65)
		(width 0.148)
		(layer "In2.Cu")
		(net 134)
	)
	(segment
		(start 241.85 107.347)
		(end 241.85 106.125)
		(width 0.148)
		(layer "In2.Cu")
		(net 134)
	)
	(segment
		(start 230.689707 130.836029)
		(end 230.414568 130.56089)
		(width 0.148)
		(layer "In2.Cu")
		(net 134)
	)
	(segment
		(start 229.14181 131.409455)
		(end 229.141811 131.409455)
		(width 0.148)
		(layer "In2.Cu")
		(net 134)
	)
	(segment
		(start 196.95 150.419669)
		(end 196.505331 149.975)
		(width 0.1)
		(layer "In2.Cu")
		(net 134)
	)
	(segment
		(start 196.5 148.95)
		(end 196.5 148.5)
		(width 0.1)
		(layer "In2.Cu")
		(net 134)
	)
	(segment
		(start 231.11397 130.836027)
		(end 231.113971 130.836028)
		(width 0.148)
		(layer "In2.Cu")
		(net 134)
	)
	(segment
		(start 196.975 150.775)
		(end 196.975 150.444669)
		(width 0.148)
		(layer "In2.Cu")
		(net 134)
	)
	(arc
		(start 224.050602 136.500587)
		(mid 223.962734 136.712719)
		(end 224.050602 136.924851)
		(width 0.148)
		(layer "In2.Cu")
		(net 134)
	)
	(arc
		(start 229.416913 132.108821)
		(mid 229.504781 132.320953)
		(end 229.416913 132.533085)
		(width 0.148)
		(layer "In2.Cu")
		(net 134)
	)
	(arc
		(start 231.11397 130.411763)
		(mid 231.201838 130.623895)
		(end 231.11397 130.836027)
		(width 0.148)
		(layer "In2.Cu")
		(net 134)
	)
	(arc
		(start 228.293247 132.257947)
		(mid 228.205379 132.470079)
		(end 228.293247 132.682211)
		(width 0.148)
		(layer "In2.Cu")
		(net 134)
	)
	(arc
		(start 226.596217 133.955031)
		(mid 226.508349 134.167163)
		(end 226.596217 134.379295)
		(width 0.148)
		(layer "In2.Cu")
		(net 134)
	)
	(arc
		(start 224.899133 135.652061)
		(mid 224.811265 135.864193)
		(end 224.899133 136.076325)
		(width 0.148)
		(layer "In2.Cu")
		(net 134)
	)
	(arc
		(start 231.9625 129.9875)
		(mid 231.750367 130.075368)
		(end 231.538234 129.9875)
		(width 0.148)
		(layer "In2.Cu")
		(net 134)
	)
	(arc
		(start 224.474866 136.500587)
		(mid 224.262734 136.412719)
		(end 224.050602 136.500587)
		(width 0.148)
		(layer "In2.Cu")
		(net 134)
	)
	(arc
		(start 229.416915 132.533086)
		(mid 229.204782 132.620954)
		(end 228.992649 132.533086)
		(width 0.148)
		(layer "In2.Cu")
		(net 134)
	)
	(arc
		(start 229.141811 131.409455)
		(mid 229.053943 131.621587)
		(end 229.141811 131.833719)
		(width 0.148)
		(layer "In2.Cu")
		(net 134)
	)
	(arc
		(start 223.477215 138.472785)
		(mid 223.265082 138.560653)
		(end 223.052949 138.472785)
		(width 0.148)
		(layer "In2.Cu")
		(net 134)
	)
	(arc
		(start 228.568385 132.957349)
		(mid 228.656253 133.169481)
		(end 228.568385 133.381613)
		(width 0.148)
		(layer "In2.Cu")
		(net 134)
	)
	(arc
		(start 223.477214 138.04852)
		(mid 223.565082 138.260652)
		(end 223.477214 138.472784)
		(width 0.148)
		(layer "In2.Cu")
		(net 134)
	)
	(arc
		(start 226.171888 134.803495)
		(mid 225.959756 134.715627)
		(end 225.747624 134.803495)
		(width 0.148)
		(layer "In2.Cu")
		(net 134)
	)
	(arc
		(start 226.022801 135.9272)
		(mid 225.810668 136.015068)
		(end 225.598535 135.9272)
		(width 0.148)
		(layer "In2.Cu")
		(net 134)
	)
	(arc
		(start 222.353547 138.197646)
		(mid 222.265679 138.409778)
		(end 222.353547 138.62191)
		(width 0.148)
		(layer "In2.Cu")
		(net 134)
	)
	(arc
		(start 231.113972 130.836029)
		(mid 230.901839 130.923897)
		(end 230.689706 130.836029)
		(width 0.148)
		(layer "In2.Cu")
		(net 134)
	)
	(arc
		(start 228.568386 133.381614)
		(mid 228.356253 133.469482)
		(end 228.14412 133.381614)
		(width 0.148)
		(layer "In2.Cu")
		(net 134)
	)
	(arc
		(start 224.325744 137.624257)
		(mid 224.113611 137.712125)
		(end 223.901478 137.624257)
		(width 0.148)
		(layer "In2.Cu")
		(net 134)
	)
	(arc
		(start 227.444718 133.106475)
		(mid 227.35685 133.318607)
		(end 227.444718 133.530739)
		(width 0.148)
		(layer "In2.Cu")
		(net 134)
	)
	(arc
		(start 222.777811 138.197646)
		(mid 222.565679 138.109778)
		(end 222.353547 138.197646)
		(width 0.148)
		(layer "In2.Cu")
		(net 134)
	)
	(arc
		(start 230.414568 130.56089)
		(mid 230.202436 130.473022)
		(end 229.990304 130.56089)
		(width 0.148)
		(layer "In2.Cu")
		(net 134)
	)
	(arc
		(start 222.628685 138.897048)
		(mid 222.716553 139.10918)
		(end 222.628685 139.321312)
		(width 0.148)
		(layer "In2.Cu")
		(net 134)
	)
	(arc
		(start 231.263096 129.712361)
		(mid 231.050964 129.624493)
		(end 230.838832 129.712361)
		(width 0.148)
		(layer "In2.Cu")
		(net 134)
	)
	(arc
		(start 230.265442 131.260292)
		(mid 230.35331 131.472424)
		(end 230.265442 131.684556)
		(width 0.148)
		(layer "In2.Cu")
		(net 134)
	)
	(arc
		(start 229.990304 130.56089)
		(mid 229.902436 130.773022)
		(end 229.990304 130.985154)
		(width 0.148)
		(layer "In2.Cu")
		(net 134)
	)
	(arc
		(start 226.871329 135.078671)
		(mid 226.659196 135.166539)
		(end 226.447063 135.078671)
		(width 0.148)
		(layer "In2.Cu")
		(net 134)
	)
	(arc
		(start 223.626358 137.349136)
		(mid 223.414226 137.261268)
		(end 223.202094 137.349136)
		(width 0.148)
		(layer "In2.Cu")
		(net 134)
	)
	(arc
		(start 229.566075 131.409454)
		(mid 229.353942 131.321586)
		(end 229.14181 131.409455)
		(width 0.148)
		(layer "In2.Cu")
		(net 134)
	)
	(arc
		(start 225.747624 134.803495)
		(mid 225.659756 135.015627)
		(end 225.747624 135.227759)
		(width 0.148)
		(layer "In2.Cu")
		(net 134)
	)
	(arc
		(start 230.265443 131.684557)
		(mid 230.05331 131.772425)
		(end 229.841177 131.684557)
		(width 0.148)
		(layer "In2.Cu")
		(net 134)
	)
	(arc
		(start 227.719856 133.805877)
		(mid 227.807724 134.018009)
		(end 227.719856 134.230141)
		(width 0.148)
		(layer "In2.Cu")
		(net 134)
	)
	(arc
		(start 223.202094 137.349136)
		(mid 223.114226 137.561268)
		(end 223.202094 137.7734)
		(width 0.148)
		(layer "In2.Cu")
		(net 134)
	)
	(arc
		(start 225.323397 135.652061)
		(mid 225.111265 135.564193)
		(end 224.899133 135.652061)
		(width 0.148)
		(layer "In2.Cu")
		(net 134)
	)
	(arc
		(start 226.022799 135.502934)
		(mid 226.110667 135.715066)
		(end 226.022799 135.927198)
		(width 0.148)
		(layer "In2.Cu")
		(net 134)
	)
	(arc
		(start 227.868982 133.106475)
		(mid 227.65685 133.018607)
		(end 227.444718 133.106475)
		(width 0.148)
		(layer "In2.Cu")
		(net 134)
	)
	(arc
		(start 224.325742 137.199991)
		(mid 224.41361 137.412123)
		(end 224.325742 137.624255)
		(width 0.148)
		(layer "In2.Cu")
		(net 134)
	)
	(arc
		(start 227.020481 133.955031)
		(mid 226.808349 133.867163)
		(end 226.596217 133.955031)
		(width 0.148)
		(layer "In2.Cu")
		(net 134)
	)
	(arc
		(start 225.174271 136.351463)
		(mid 225.262139 136.563595)
		(end 225.174271 136.775727)
		(width 0.148)
		(layer "In2.Cu")
		(net 134)
	)
	(arc
		(start 227.719858 134.230143)
		(mid 227.507725 134.318011)
		(end 227.295592 134.230143)
		(width 0.148)
		(layer "In2.Cu")
		(net 134)
	)
	(arc
		(start 226.871328 134.654406)
		(mid 226.959196 134.866538)
		(end 226.871328 135.07867)
		(width 0.148)
		(layer "In2.Cu")
		(net 134)
	)
	(arc
		(start 230.838832 129.712361)
		(mid 230.750964 129.924493)
		(end 230.838832 130.136625)
		(width 0.148)
		(layer "In2.Cu")
		(net 134)
	)
	(arc
		(start 225.174272 136.775728)
		(mid 224.962139 136.863596)
		(end 224.750006 136.775728)
		(width 0.148)
		(layer "In2.Cu")
		(net 134)
	)
	(arc
		(start 228.717511 132.257947)
		(mid 228.505379 132.170079)
		(end 228.293247 132.257947)
		(width 0.148)
		(layer "In2.Cu")
		(net 134)
	)
	(segment
		(start 195.0005 148.9995)
		(end 195.5 148.5)
		(width 0.256)
		(layer "F.Cu")
		(net 135)
	)
	(segment
		(start 238.051 110.598)
		(end 238.051 109.446)
		(width 0.38)
		(layer "F.Cu")
		(net 135)
	)
	(via
		(at 238.051 109.446)
		(size 0.45)
		(drill 0.1)
		(layers "F.Cu" "B.Cu")
		(remove_unused_layers yes)
		(keep_end_layers yes)
		(zone_layer_connections)
		(net 135)
	)
	(via
		(at 195.5 148.5)
		(size 0.45)
		(drill 0.1)
		(layers "F.Cu" "B.Cu")
		(remove_unused_layers yes)
		(keep_end_layers yes)
		(zone_layer_connections)
		(net 135)
	)
	(segment
		(start 238.630025 124.325)
		(end 238.441087 124.136062)
		(width 0.148)
		(layer "In2.Cu")
		(net 135)
	)
	(segment
		(start 202.649 151.175)
		(end 201.849 151.975)
		(width 0.148)
		(layer "In2.Cu")
		(net 135)
	)
	(segment
		(start 245.925 118.125)
		(end 243.725 118.125)
		(width 0.148)
		(layer "In2.Cu")
		(net 135)
	)
	(segment
		(start 234.976272 127.600896)
		(end 235.165199 127.789823)
		(width 0.148)
		(layer "In2.Cu")
		(net 135)
	)
	(segment
		(start 232.925296 130.524704)
		(end 221.425 142.025)
		(width 0.148)
		(layer "In2.Cu")
		(net 135)
	)
	(segment
		(start 195.875 149.25)
		(end 195.875 150.125)
		(width 0.1)
		(layer "In2.Cu")
		(net 135)
	)
	(segment
		(start 236.650125 126.3049)
		(end 236.461187 126.115962)
		(width 0.148)
		(layer "In2.Cu")
		(net 135)
	)
	(segment
		(start 201.849 151.975)
		(end 196.25 151.975)
		(width 0.148)
		(layer "In2.Cu")
		(net 135)
	)
	(segment
		(start 204.95 151.7)
		(end 204.425 151.175)
		(width 0.148)
		(layer "In2.Cu")
		(net 135)
	)
	(segment
		(start 237.1451 126.304898)
		(end 237.145099 126.304898)
		(width 0.148)
		(layer "In2.Cu")
		(net 135)
	)
	(segment
		(start 249.5625 103.7)
		(end 251.25 105.3875)
		(width 0.148)
		(layer "In2.Cu")
		(net 135)
	)
	(segment
		(start 237.640075 125.31495)
		(end 237.451148 125.126023)
		(width 0.148)
		(layer "In2.Cu")
		(net 135)
	)
	(segment
		(start 237.946112 124.631036)
		(end 238.135049 124.819973)
		(width 0.148)
		(layer "In2.Cu")
		(net 135)
	)
	(segment
		(start 233.986312 128.590836)
		(end 234.175249 128.779773)
		(width 0.148)
		(layer "In2.Cu")
		(net 135)
	)
	(segment
		(start 236.956173 125.620997)
		(end 237.145099 125.809923)
		(width 0.148)
		(layer "In2.Cu")
		(net 135)
	)
	(segment
		(start 234.670225 128.2848)
		(end 234.481287 128.095862)
		(width 0.148)
		(layer "In2.Cu")
		(net 135)
	)
	(segment
		(start 234.976273 127.105922)
		(end 234.976272 127.105922)
		(width 0.148)
		(layer "In2.Cu")
		(net 135)
	)
	(segment
		(start 234.175249 129.274747)
		(end 234.17525 129.27475)
		(width 0.148)
		(layer "In2.Cu")
		(net 135)
	)
	(segment
		(start 238.9735 108.5235)
		(end 239.8765 108.5235)
		(width 0.148)
		(layer "In2.Cu")
		(net 135)
	)
	(segment
		(start 195.975 151.7)
		(end 195.975 150.225)
		(width 0.148)
		(layer "In2.Cu")
		(net 135)
	)
	(segment
		(start 237.946113 124.136062)
		(end 237.946112 124.136062)
		(width 0.148)
		(layer "In2.Cu")
		(net 135)
	)
	(segment
		(start 196.25 151.975)
		(end 195.975 151.7)
		(width 0.148)
		(layer "In2.Cu")
		(net 135)
	)
	(segment
		(start 233.185299 130.264698)
		(end 232.925296 130.524704)
		(width 0.148)
		(layer "In2.Cu")
		(net 135)
	)
	(segment
		(start 241.225 107.175)
		(end 241.225 105.825)
		(width 0.148)
		(layer "In2.Cu")
		(net 135)
	)
	(segment
		(start 239.8765 108.5235)
		(end 241.225 107.175)
		(width 0.148)
		(layer "In2.Cu")
		(net 135)
	)
	(segment
		(start 221.425 142.025)
		(end 215.275 142.025)
		(width 0.148)
		(layer "In2.Cu")
		(net 135)
	)
	(segment
		(start 215.275 142.025)
		(end 208.35 148.95)
		(width 0.148)
		(layer "In2.Cu")
		(net 135)
	)
	(segment
		(start 232.996377 129.085826)
		(end 232.996377 129.085827)
		(width 0.148)
		(layer "In2.Cu")
		(net 135)
	)
	(segment
		(start 233.680274 129.27475)
		(end 233.680275 129.27475)
		(width 0.148)
		(layer "In2.Cu")
		(net 135)
	)
	(segment
		(start 195.5 148.5)
		(end 195.5 148.875)
		(width 0.1)
		(layer "In2.Cu")
		(net 135)
	)
	(segment
		(start 232.996377 129.580801)
		(end 233.185299 129.769723)
		(width 0.148)
		(layer "In2.Cu")
		(net 135)
	)
	(segment
		(start 207.95 150.4)
		(end 206.95 150.4)
		(width 0.148)
		(layer "In2.Cu")
		(net 135)
	)
	(segment
		(start 236.155149 127.294847)
		(end 236.15515 127.29485)
		(width 0.148)
		(layer "In2.Cu")
		(net 135)
	)
	(segment
		(start 251.25 112.8)
		(end 245.925 118.125)
		(width 0.148)
		(layer "In2.Cu")
		(net 135)
	)
	(segment
		(start 208.35 148.95)
		(end 208.35 150)
		(width 0.148)
		(layer "In2.Cu")
		(net 135)
	)
	(segment
		(start 243.725 118.125)
		(end 239.3 122.55)
		(width 0.148)
		(layer "In2.Cu")
		(net 135)
	)
	(segment
		(start 238.630024 124.325)
		(end 238.630025 124.325)
		(width 0.148)
		(layer "In2.Cu")
		(net 135)
	)
	(segment
		(start 236.650124 126.3049)
		(end 236.650125 126.3049)
		(width 0.148)
		(layer "In2.Cu")
		(net 135)
	)
	(segment
		(start 237.145099 126.304898)
		(end 237.1451 126.3049)
		(width 0.148)
		(layer "In2.Cu")
		(net 135)
	)
	(segment
		(start 195.875 150.125)
		(end 195.975 150.225)
		(width 0.1)
		(layer "In2.Cu")
		(net 135)
	)
	(segment
		(start 233.1853 130.264698)
		(end 233.185299 130.264698)
		(width 0.148)
		(layer "In2.Cu")
		(net 135)
	)
	(segment
		(start 241.225 105.825)
		(end 243.35 103.7)
		(width 0.148)
		(layer "In2.Cu")
		(net 135)
	)
	(segment
		(start 235.966213 126.115962)
		(end 235.966212 126.115962)
		(width 0.148)
		(layer "In2.Cu")
		(net 135)
	)
	(segment
		(start 243.35 103.7)
		(end 249.5625 103.7)
		(width 0.148)
		(layer "In2.Cu")
		(net 135)
	)
	(segment
		(start 208.35 150)
		(end 207.95 150.4)
		(width 0.148)
		(layer "In2.Cu")
		(net 135)
	)
	(segment
		(start 235.660175 127.29485)
		(end 235.471247 127.105922)
		(width 0.148)
		(layer "In2.Cu")
		(net 135)
	)
	(segment
		(start 251.25 105.3875)
		(end 251.25 112.8)
		(width 0.148)
		(layer "In2.Cu")
		(net 135)
	)
	(segment
		(start 238.135049 125.314947)
		(end 238.13505 125.31495)
		(width 0.148)
		(layer "In2.Cu")
		(net 135)
	)
	(segment
		(start 239.3 124.15)
		(end 239.125 124.325)
		(width 0.148)
		(layer "In2.Cu")
		(net 135)
	)
	(segment
		(start 237.640074 125.31495)
		(end 237.640075 125.31495)
		(width 0.148)
		(layer "In2.Cu")
		(net 135)
	)
	(segment
		(start 233.680275 129.27475)
		(end 233.491352 129.085827)
		(width 0.148)
		(layer "In2.Cu")
		(net 135)
	)
	(segment
		(start 205.65 151.7)
		(end 204.95 151.7)
		(width 0.148)
		(layer "In2.Cu")
		(net 135)
	)
	(segment
		(start 238.051 109.446)
		(end 238.9735 108.5235)
		(width 0.148)
		(layer "In2.Cu")
		(net 135)
	)
	(segment
		(start 235.660174 127.29485)
		(end 235.660175 127.29485)
		(width 0.148)
		(layer "In2.Cu")
		(net 135)
	)
	(segment
		(start 195.5 148.875)
		(end 195.875 149.25)
		(width 0.1)
		(layer "In2.Cu")
		(net 135)
	)
	(segment
		(start 206.95 150.4)
		(end 205.65 151.7)
		(width 0.148)
		(layer "In2.Cu")
		(net 135)
	)
	(segment
		(start 235.966212 126.610936)
		(end 236.155149 126.799873)
		(width 0.148)
		(layer "In2.Cu")
		(net 135)
	)
	(segment
		(start 204.425 151.175)
		(end 202.649 151.175)
		(width 0.148)
		(layer "In2.Cu")
		(net 135)
	)
	(segment
		(start 233.986313 128.095862)
		(end 233.986312 128.095862)
		(width 0.148)
		(layer "In2.Cu")
		(net 135)
	)
	(segment
		(start 235.165199 128.284797)
		(end 235.1652 128.2848)
		(width 0.148)
		(layer "In2.Cu")
		(net 135)
	)
	(segment
		(start 234.670224 128.2848)
		(end 234.670225 128.2848)
		(width 0.148)
		(layer "In2.Cu")
		(net 135)
	)
	(segment
		(start 236.956173 125.126022)
		(end 236.956173 125.126023)
		(width 0.148)
		(layer "In2.Cu")
		(net 135)
	)
	(segment
		(start 239.3 122.55)
		(end 239.3 124.15)
		(width 0.148)
		(layer "In2.Cu")
		(net 135)
	)
	(arc
		(start 233.185299 129.769723)
		(mid 233.287812 130.01721)
		(end 233.1853 130.264698)
		(width 0.148)
		(layer "In2.Cu")
		(net 135)
	)
	(arc
		(start 233.491352 129.085827)
		(mid 233.243865 128.983314)
		(end 232.996377 129.085826)
		(width 0.148)
		(layer "In2.Cu")
		(net 135)
	)
	(arc
		(start 235.1652 128.2848)
		(mid 234.917712 128.387313)
		(end 234.670224 128.2848)
		(width 0.148)
		(layer "In2.Cu")
		(net 135)
	)
	(arc
		(start 234.481287 128.095862)
		(mid 234.2338 127.99335)
		(end 233.986313 128.095862)
		(width 0.148)
		(layer "In2.Cu")
		(net 135)
	)
	(arc
		(start 234.17525 129.27475)
		(mid 233.927762 129.377263)
		(end 233.680274 129.27475)
		(width 0.148)
		(layer "In2.Cu")
		(net 135)
	)
	(arc
		(start 238.135049 124.819973)
		(mid 238.237561 125.06746)
		(end 238.135049 125.314947)
		(width 0.148)
		(layer "In2.Cu")
		(net 135)
	)
	(arc
		(start 237.1451 126.3049)
		(mid 236.897612 126.407413)
		(end 236.650124 126.3049)
		(width 0.148)
		(layer "In2.Cu")
		(net 135)
	)
	(arc
		(start 236.155149 126.799873)
		(mid 236.257661 127.04736)
		(end 236.155149 127.294847)
		(width 0.148)
		(layer "In2.Cu")
		(net 135)
	)
	(arc
		(start 238.13505 125.31495)
		(mid 237.887562 125.417463)
		(end 237.640074 125.31495)
		(width 0.148)
		(layer "In2.Cu")
		(net 135)
	)
	(arc
		(start 238.441087 124.136062)
		(mid 238.1936 124.03355)
		(end 237.946113 124.136062)
		(width 0.148)
		(layer "In2.Cu")
		(net 135)
	)
	(arc
		(start 233.986312 128.095862)
		(mid 233.8838 128.343349)
		(end 233.986312 128.590836)
		(width 0.148)
		(layer "In2.Cu")
		(net 135)
	)
	(arc
		(start 237.145099 125.809923)
		(mid 237.247612 126.05741)
		(end 237.1451 126.304898)
		(width 0.148)
		(layer "In2.Cu")
		(net 135)
	)
	(arc
		(start 236.461187 126.115962)
		(mid 236.2137 126.01345)
		(end 235.966213 126.115962)
		(width 0.148)
		(layer "In2.Cu")
		(net 135)
	)
	(arc
		(start 234.976272 127.105922)
		(mid 234.87376 127.353409)
		(end 234.976272 127.600896)
		(width 0.148)
		(layer "In2.Cu")
		(net 135)
	)
	(arc
		(start 236.15515 127.29485)
		(mid 235.907662 127.397363)
		(end 235.660174 127.29485)
		(width 0.148)
		(layer "In2.Cu")
		(net 135)
	)
	(arc
		(start 235.966212 126.115962)
		(mid 235.8637 126.363449)
		(end 235.966212 126.610936)
		(width 0.148)
		(layer "In2.Cu")
		(net 135)
	)
	(arc
		(start 232.996377 129.085827)
		(mid 232.893865 129.333314)
		(end 232.996377 129.580801)
		(width 0.148)
		(layer "In2.Cu")
		(net 135)
	)
	(arc
		(start 234.175249 128.779773)
		(mid 234.277761 129.02726)
		(end 234.175249 129.274747)
		(width 0.148)
		(layer "In2.Cu")
		(net 135)
	)
	(arc
		(start 235.471247 127.105922)
		(mid 235.22376 127.00341)
		(end 234.976273 127.105922)
		(width 0.148)
		(layer "In2.Cu")
		(net 135)
	)
	(arc
		(start 235.165199 127.789823)
		(mid 235.267711 128.03731)
		(end 235.165199 128.284797)
		(width 0.148)
		(layer "In2.Cu")
		(net 135)
	)
	(arc
		(start 237.451148 125.126023)
		(mid 237.203661 125.02351)
		(end 236.956173 125.126022)
		(width 0.148)
		(layer "In2.Cu")
		(net 135)
	)
	(arc
		(start 239.125 124.325)
		(mid 238.877512 124.427513)
		(end 238.630024 124.325)
		(width 0.148)
		(layer "In2.Cu")
		(net 135)
	)
	(arc
		(start 237.946112 124.136062)
		(mid 237.8436 124.383549)
		(end 237.946112 124.631036)
		(width 0.148)
		(layer "In2.Cu")
		(net 135)
	)
	(arc
		(start 236.956173 125.126023)
		(mid 236.853661 125.37351)
		(end 236.956173 125.620997)
		(width 0.148)
		(layer "In2.Cu")
		(net 135)
	)
	(segment
		(start 236.35 110.598)
		(end 236.35 111.75)
		(width 0.38)
		(layer "F.Cu")
		(net 136)
	)
	(segment
		(start 198.0005 146.9995)
		(end 198.5 146.5)
		(width 0.256)
		(layer "F.Cu")
		(net 136)
	)
	(via
		(at 198.5 146.5)
		(size 0.45)
		(drill 0.1)
		(layers "F.Cu" "B.Cu")
		(remove_unused_layers yes)
		(keep_end_layers yes)
		(zone_layer_connections)
		(net 136)
	)
	(via
		(at 236.35 111.75)
		(size 0.45)
		(drill 0.1)
		(layers "F.Cu" "B.Cu")
		(remove_unused_layers yes)
		(keep_end_layers yes)
		(zone_layer_connections)
		(net 136)
	)
	(segment
		(start 227.95 130.115382)
		(end 227.950001 130.11538)
		(width 0.148)
		(layer "In4.Cu")
		(net 136)
	)
	(segment
		(start 228.869241 129.655762)
		(end 228.86924 129.65576)
		(width 0.148)
		(layer "In4.Cu")
		(net 136)
	)
	(segment
		(start 227.950001 130.11538)
		(end 227.282131 129.44751)
		(width 0.148)
		(layer "In4.Cu")
		(net 136)
	)
	(segment
		(start 229.78848 128.736521)
		(end 229.78848 128.73652)
		(width 0.148)
		(layer "In4.Cu")
		(net 136)
	)
	(segment
		(start 198.8305 146.4985)
		(end 199.39 147.058)
		(width 0.148)
		(layer "In4.Cu")
		(net 136)
	)
	(segment
		(start 226.025 129.95)
		(end 226.878554 130.803554)
		(width 0.148)
		(layer "In4.Cu")
		(net 136)
	)
	(segment
		(start 208.7375 144.1625)
		(end 209.3125 144.1625)
		(width 0.148)
		(layer "In4.Cu")
		(net 136)
	)
	(segment
		(start 230.959092 125.310931)
		(end 230.95909 125.310932)
		(width 0.148)
		(layer "In4.Cu")
		(net 136)
	)
	(segment
		(start 231.878332 124.391691)
		(end 231.87833 124.391692)
		(width 0.148)
		(layer "In4.Cu")
		(net 136)
	)
	(segment
		(start 228.869241 129.19614)
		(end 228.201339 128.528238)
		(width 0.148)
		(layer "In4.Cu")
		(net 136)
	)
	(segment
		(start 199.39 147.058)
		(end 205.842 147.058)
		(width 0.148)
		(layer "In4.Cu")
		(net 136)
	)
	(segment
		(start 233.716812 122.553211)
		(end 233.71681 122.553212)
		(width 0.148)
		(layer "In4.Cu")
		(net 136)
	)
	(segment
		(start 234.38468 123.680702)
		(end 234.384681 123.6807)
		(width 0.148)
		(layer "In4.Cu")
		(net 136)
	)
	(segment
		(start 233.257174 123.472436)
		(end 233.925061 124.140323)
		(width 0.148)
		(layer "In4.Cu")
		(net 136)
	)
	(segment
		(start 231.62696 126.898041)
		(end 231.62696 126.89804)
		(width 0.148)
		(layer "In4.Cu")
		(net 136)
	)
	(segment
		(start 233.46544 124.599942)
		(end 233.465441 124.59994)
		(width 0.148)
		(layer "In4.Cu")
		(net 136)
	)
	(segment
		(start 235.30392 123.221082)
		(end 235.303921 123.221082)
		(width 0.148)
		(layer "In4.Cu")
		(net 136)
	)
	(segment
		(start 198.4995 146.4985)
		(end 198.8305 146.4985)
		(width 0.148)
		(layer "In4.Cu")
		(net 136)
	)
	(segment
		(start 230.70772 127.357662)
		(end 230.707721 127.35766)
		(width 0.148)
		(layer "In4.Cu")
		(net 136)
	)
	(segment
		(start 227.282132 128.987891)
		(end 227.28213 128.987892)
		(width 0.148)
		(layer "In4.Cu")
		(net 136)
	)
	(segment
		(start 228.86924 129.655762)
		(end 228.869241 129.655762)
		(width 0.148)
		(layer "In4.Cu")
		(net 136)
	)
	(segment
		(start 232.546201 125.978802)
		(end 232.5462 125.9788)
		(width 0.148)
		(layer "In4.Cu")
		(net 136)
	)
	(segment
		(start 232.5462 125.519182)
		(end 232.546201 125.51918)
		(width 0.148)
		(layer "In4.Cu")
		(net 136)
	)
	(segment
		(start 235.4 117.5)
		(end 236.35 116.55)
		(width 0.148)
		(layer "In4.Cu")
		(net 136)
	)
	(segment
		(start 228.86924 129.196142)
		(end 228.869241 129.19614)
		(width 0.148)
		(layer "In4.Cu")
		(net 136)
	)
	(segment
		(start 229.580248 127.149427)
		(end 230.248102 127.817281)
		(width 0.148)
		(layer "In4.Cu")
		(net 136)
	)
	(segment
		(start 213.1 140.375)
		(end 218.1 140.375)
		(width 0.148)
		(layer "In4.Cu")
		(net 136)
	)
	(segment
		(start 235.303921 123.221082)
		(end 235.4 123.125)
		(width 0.148)
		(layer "In4.Cu")
		(net 136)
	)
	(segment
		(start 205.842 147.058)
		(end 208.7375 144.1625)
		(width 0.148)
		(layer "In4.Cu")
		(net 136)
	)
	(segment
		(start 227.74175 128.987892)
		(end 228.409621 129.655763)
		(width 0.148)
		(layer "In4.Cu")
		(net 136)
	)
	(segment
		(start 209.3125 144.1625)
		(end 213.1 140.375)
		(width 0.148)
		(layer "In4.Cu")
		(net 136)
	)
	(segment
		(start 232.5462 125.978802)
		(end 232.546201 125.978802)
		(width 0.148)
		(layer "In4.Cu")
		(net 136)
	)
	(segment
		(start 232.546201 125.51918)
		(end 231.878331 124.85131)
		(width 0.148)
		(layer "In4.Cu")
		(net 136)
	)
	(segment
		(start 230.707721 127.35766)
		(end 230.039819 126.689758)
		(width 0.148)
		(layer "In4.Cu")
		(net 136)
	)
	(segment
		(start 229.788481 128.2769)
		(end 229.120628 127.609047)
		(width 0.148)
		(layer "In4.Cu")
		(net 136)
	)
	(segment
		(start 229.78848 128.276902)
		(end 229.788481 128.2769)
		(width 0.148)
		(layer "In4.Cu")
		(net 136)
	)
	(segment
		(start 223.85 134.625)
		(end 223.85 130.7)
		(width 0.148)
		(layer "In4.Cu")
		(net 136)
	)
	(segment
		(start 232.33795 124.391692)
		(end 233.005821 125.059563)
		(width 0.148)
		(layer "In4.Cu")
		(net 136)
	)
	(segment
		(start 224.6 129.95)
		(end 226.025 129.95)
		(width 0.148)
		(layer "In4.Cu")
		(net 136)
	)
	(segment
		(start 233.46544 125.059562)
		(end 233.465441 125.059562)
		(width 0.148)
		(layer "In4.Cu")
		(net 136)
	)
	(segment
		(start 234.384681 123.6807)
		(end 233.716811 123.01283)
		(width 0.148)
		(layer "In4.Cu")
		(net 136)
	)
	(segment
		(start 231.41871 125.310932)
		(end 232.086581 125.978803)
		(width 0.148)
		(layer "In4.Cu")
		(net 136)
	)
	(segment
		(start 231.62696 126.438422)
		(end 231.626961 126.43842)
		(width 0.148)
		(layer "In4.Cu")
		(net 136)
	)
	(segment
		(start 232.797555 123.472434)
		(end 232.797554 123.472436)
		(width 0.148)
		(layer "In4.Cu")
		(net 136)
	)
	(segment
		(start 230.707721 127.817282)
		(end 230.707722 127.817281)
		(width 0.148)
		(layer "In4.Cu")
		(net 136)
	)
	(segment
		(start 230.499439 126.230138)
		(end 231.167342 126.898041)
		(width 0.148)
		(layer "In4.Cu")
		(net 136)
	)
	(segment
		(start 233.465441 124.59994)
		(end 232.797555 123.932054)
		(width 0.148)
		(layer "In4.Cu")
		(net 136)
	)
	(segment
		(start 227.721447 130.803553)
		(end 227.95 130.575)
		(width 0.148)
		(layer "In4.Cu")
		(net 136)
	)
	(segment
		(start 229.788482 128.736521)
		(end 229.78848 128.736521)
		(width 0.148)
		(layer "In4.Cu")
		(net 136)
	)
	(segment
		(start 230.707722 127.817281)
		(end 230.70772 127.81728)
		(width 0.148)
		(layer "In4.Cu")
		(net 136)
	)
	(segment
		(start 223.85 130.7)
		(end 224.6 129.95)
		(width 0.148)
		(layer "In4.Cu")
		(net 136)
	)
	(segment
		(start 233.465441 125.059562)
		(end 233.46544 125.05956)
		(width 0.148)
		(layer "In4.Cu")
		(net 136)
	)
	(segment
		(start 228.660959 128.068618)
		(end 229.328862 128.736521)
		(width 0.148)
		(layer "In4.Cu")
		(net 136)
	)
	(segment
		(start 234.17643 122.553212)
		(end 234.844301 123.221083)
		(width 0.148)
		(layer "In4.Cu")
		(net 136)
	)
	(segment
		(start 236.35 116.55)
		(end 236.35 111.75)
		(width 0.148)
		(layer "In4.Cu")
		(net 136)
	)
	(segment
		(start 234.384681 124.140322)
		(end 234.38468 124.14032)
		(width 0.148)
		(layer "In4.Cu")
		(net 136)
	)
	(segment
		(start 229.120627 127.149428)
		(end 229.120628 127.149427)
		(width 0.148)
		(layer "In4.Cu")
		(net 136)
	)
	(segment
		(start 235.4 123.125)
		(end 235.4 117.5)
		(width 0.148)
		(layer "In4.Cu")
		(net 136)
	)
	(segment
		(start 234.384681 124.140323)
		(end 234.384681 124.140322)
		(width 0.148)
		(layer "In4.Cu")
		(net 136)
	)
	(segment
		(start 227.232107 130.95)
		(end 227.367893 130.95)
		(width 0.148)
		(layer "In4.Cu")
		(net 136)
	)
	(segment
		(start 231.626961 126.43842)
		(end 230.959091 125.77055)
		(width 0.148)
		(layer "In4.Cu")
		(net 136)
	)
	(segment
		(start 231.626962 126.898041)
		(end 231.62696 126.898041)
		(width 0.148)
		(layer "In4.Cu")
		(net 136)
	)
	(segment
		(start 218.1 140.375)
		(end 223.85 134.625)
		(width 0.148)
		(layer "In4.Cu")
		(net 136)
	)
	(arc
		(start 233.71681 122.553212)
		(mid 233.94662 122.458022)
		(end 234.17643 122.553212)
		(width 0.148)
		(layer "In4.Cu")
		(net 136)
	)
	(arc
		(start 231.167342 126.898041)
		(mid 231.397152 126.993231)
		(end 231.626962 126.898041)
		(width 0.148)
		(layer "In4.Cu")
		(net 136)
	)
	(arc
		(start 230.959091 125.77055)
		(mid 230.863901 125.54074)
		(end 230.959092 125.310931)
		(width 0.148)
		(layer "In4.Cu")
		(net 136)
	)
	(arc
		(start 229.328862 128.736521)
		(mid 229.558672 128.831711)
		(end 229.788482 128.736521)
		(width 0.148)
		(layer "In4.Cu")
		(net 136)
	)
	(arc
		(start 227.95 130.575)
		(mid 228.045191 130.34519)
		(end 227.95 130.115382)
		(width 0.148)
		(layer "In4.Cu")
		(net 136)
	)
	(arc
		(start 231.62696 126.89804)
		(mid 231.722151 126.66823)
		(end 231.62696 126.438422)
		(width 0.148)
		(layer "In4.Cu")
		(net 136)
	)
	(arc
		(start 230.039819 126.689758)
		(mid 229.944629 126.459948)
		(end 230.039819 126.230138)
		(width 0.148)
		(layer "In4.Cu")
		(net 136)
	)
	(arc
		(start 228.409621 129.655763)
		(mid 228.639431 129.750953)
		(end 228.86924 129.655762)
		(width 0.148)
		(layer "In4.Cu")
		(net 136)
	)
	(arc
		(start 228.86924 129.65576)
		(mid 228.964431 129.42595)
		(end 228.86924 129.196142)
		(width 0.148)
		(layer "In4.Cu")
		(net 136)
	)
	(arc
		(start 230.248102 127.817281)
		(mid 230.477911 127.912472)
		(end 230.707721 127.817282)
		(width 0.148)
		(layer "In4.Cu")
		(net 136)
	)
	(arc
		(start 227.282131 129.44751)
		(mid 227.186941 129.2177)
		(end 227.282132 128.987891)
		(width 0.148)
		(layer "In4.Cu")
		(net 136)
	)
	(arc
		(start 228.201339 128.528238)
		(mid 228.106149 128.298428)
		(end 228.201339 128.068618)
		(width 0.148)
		(layer "In4.Cu")
		(net 136)
	)
	(arc
		(start 232.797555 123.932054)
		(mid 232.702365 123.702244)
		(end 232.797555 123.472434)
		(width 0.148)
		(layer "In4.Cu")
		(net 136)
	)
	(arc
		(start 230.70772 127.81728)
		(mid 230.802911 127.58747)
		(end 230.70772 127.357662)
		(width 0.148)
		(layer "In4.Cu")
		(net 136)
	)
	(arc
		(start 229.78848 128.73652)
		(mid 229.883671 128.50671)
		(end 229.78848 128.276902)
		(width 0.148)
		(layer "In4.Cu")
		(net 136)
	)
	(arc
		(start 233.925061 124.140323)
		(mid 234.154871 124.235513)
		(end 234.384681 124.140323)
		(width 0.148)
		(layer "In4.Cu")
		(net 136)
	)
	(arc
		(start 234.38468 124.14032)
		(mid 234.479871 123.91051)
		(end 234.38468 123.680702)
		(width 0.148)
		(layer "In4.Cu")
		(net 136)
	)
	(arc
		(start 226.878554 130.803554)
		(mid 227.040766 130.91194)
		(end 227.232107 130.95)
		(width 0.148)
		(layer "In4.Cu")
		(net 136)
	)
	(arc
		(start 234.844301 123.221083)
		(mid 235.074111 123.316273)
		(end 235.30392 123.221082)
		(width 0.148)
		(layer "In4.Cu")
		(net 136)
	)
	(arc
		(start 227.367893 130.95)
		(mid 227.559235 130.91194)
		(end 227.721447 130.803553)
		(width 0.148)
		(layer "In4.Cu")
		(net 136)
	)
	(arc
		(start 230.039819 126.230138)
		(mid 230.269629 126.134948)
		(end 230.499439 126.230138)
		(width 0.148)
		(layer "In4.Cu")
		(net 136)
	)
	(arc
		(start 233.716811 123.01283)
		(mid 233.621621 122.78302)
		(end 233.716812 122.553211)
		(width 0.148)
		(layer "In4.Cu")
		(net 136)
	)
	(arc
		(start 233.46544 125.05956)
		(mid 233.560631 124.82975)
		(end 233.46544 124.599942)
		(width 0.148)
		(layer "In4.Cu")
		(net 136)
	)
	(arc
		(start 227.28213 128.987892)
		(mid 227.51194 128.892702)
		(end 227.74175 128.987892)
		(width 0.148)
		(layer "In4.Cu")
		(net 136)
	)
	(arc
		(start 233.005821 125.059563)
		(mid 233.235631 125.154753)
		(end 233.46544 125.059562)
		(width 0.148)
		(layer "In4.Cu")
		(net 136)
	)
	(arc
		(start 229.120628 127.609047)
		(mid 229.025437 127.379238)
		(end 229.120627 127.149428)
		(width 0.148)
		(layer "In4.Cu")
		(net 136)
	)
	(arc
		(start 232.086581 125.978803)
		(mid 232.316391 126.073993)
		(end 232.5462 125.978802)
		(width 0.148)
		(layer "In4.Cu")
		(net 136)
	)
	(arc
		(start 231.878331 124.85131)
		(mid 231.783141 124.6215)
		(end 231.878332 124.391691)
		(width 0.148)
		(layer "In4.Cu")
		(net 136)
	)
	(arc
		(start 228.201339 128.068618)
		(mid 228.431149 127.973428)
		(end 228.660959 128.068618)
		(width 0.148)
		(layer "In4.Cu")
		(net 136)
	)
	(arc
		(start 232.5462 125.9788)
		(mid 232.641391 125.74899)
		(end 232.5462 125.519182)
		(width 0.148)
		(layer "In4.Cu")
		(net 136)
	)
	(arc
		(start 230.95909 125.310932)
		(mid 231.1889 125.215742)
		(end 231.41871 125.310932)
		(width 0.148)
		(layer "In4.Cu")
		(net 136)
	)
	(arc
		(start 229.120628 127.149427)
		(mid 229.350438 127.054237)
		(end 229.580248 127.149427)
		(width 0.148)
		(layer "In4.Cu")
		(net 136)
	)
	(arc
		(start 231.87833 124.391692)
		(mid 232.10814 124.296502)
		(end 232.33795 124.391692)
		(width 0.148)
		(layer "In4.Cu")
		(net 136)
	)
	(arc
		(start 232.797554 123.472436)
		(mid 233.027364 123.377246)
		(end 233.257174 123.472436)
		(width 0.148)
		(layer "In4.Cu")
		(net 136)
	)
	(segment
		(start 252.239499 133.664)
		(end 252.874499 133.664)
		(width 0.15)
		(layer "F.Cu")
		(net 137)
	)
	(segment
		(start 251.319499 133.20252)
		(end 251.319499 132.394)
		(width 0.15)
		(layer "F.Cu")
		(net 137)
	)
	(segment
		(start 251.495239 133.37826)
		(end 251.319499 133.20252)
		(width 0.15)
		(layer "F.Cu")
		(net 137)
	)
	(segment
		(start 251.953759 133.37826)
		(end 252.239499 133.664)
		(width 0.15)
		(layer "F.Cu")
		(net 137)
	)
	(segment
		(start 251.953759 133.37826)
		(end 251.495239 133.37826)
		(width 0.15)
		(layer "F.Cu")
		(net 137)
	)
	(segment
		(start 246.903 139.101)
		(end 247.904 139.101)
		(width 0.256)
		(layer "F.Cu")
		(net 137)
	)
	(via
		(at 251.953759 133.37826)
		(size 0.45)
		(drill 0.1)
		(layers "F.Cu" "B.Cu")
		(remove_unused_layers yes)
		(keep_end_layers yes)
		(zone_layer_connections)
		(net 137)
	)
	(via
		(at 247.904 139.101)
		(size 0.45)
		(drill 0.1)
		(layers "F.Cu" "B.Cu")
		(remove_unused_layers yes)
		(keep_end_layers yes)
		(zone_layer_connections)
		(net 137)
	)
	(segment
		(start 253.580239 133.37826)
		(end 254.274499 132.684)
		(width 0.15)
		(layer "B.Cu")
		(net 137)
	)
	(segment
		(start 251.953759 133.37826)
		(end 253.580239 133.37826)
		(width 0.15)
		(layer "B.Cu")
		(net 137)
	)
	(segment
		(start 248.475 140.5)
		(end 248.85 140.5)
		(width 0.1)
		(layer "In2.Cu")
		(net 137)
	)
	(segment
		(start 251.6 137.75)
		(end 251.6 133.732019)
		(width 0.1)
		(layer "In2.Cu")
		(net 137)
	)
	(segment
		(start 248.3 139.497)
		(end 248.3 140.325)
		(width 0.1)
		(layer "In2.Cu")
		(net 137)
	)
	(segment
		(start 248.85 140.5)
		(end 251.6 137.75)
		(width 0.1)
		(layer "In2.Cu")
		(net 137)
	)
	(segment
		(start 247.904 139.101)
		(end 248.3 139.497)
		(width 0.1)
		(layer "In2.Cu")
		(net 137)
	)
	(segment
		(start 248.3 140.325)
		(end 248.475 140.5)
		(width 0.1)
		(layer "In2.Cu")
		(net 137)
	)
	(segment
		(start 251.6 133.732019)
		(end 251.953759 133.37826)
		(width 0.1)
		(layer "In2.Cu")
		(net 137)
	)
	(segment
		(start 252.127499 131.767)
		(end 252.124499 131.764)
		(width 0.15)
		(layer "F.Cu")
		(net 138)
	)
	(segment
		(start 241.001 138.101)
		(end 240 138.101)
		(width 0.256)
		(layer "F.Cu")
		(net 138)
	)
	(segment
		(start 253.010499 131.767)
		(end 252.127499 131.767)
		(width 0.15)
		(layer "F.Cu")
		(net 138)
	)
	(via
		(at 252.124499 131.764)
		(size 0.45)
		(drill 0.1)
		(layers "F.Cu" "B.Cu")
		(remove_unused_layers yes)
		(keep_end_layers yes)
		(zone_layer_connections)
		(net 138)
	)
	(via
		(at 240 138.101)
		(size 0.45)
		(drill 0.1)
		(layers "F.Cu" "B.Cu")
		(remove_unused_layers yes)
		(keep_end_layers yes)
		(zone_layer_connections)
		(net 138)
	)
	(segment
		(start 254.274499 131.714)
		(end 252.924499 131.714)
		(width 0.15)
		(layer "B.Cu")
		(net 138)
	)
	(segment
		(start 252.124499 131.764)
		(end 252.889499 131.764)
		(width 0.256)
		(layer "B.Cu")
		(net 138)
	)
	(segment
		(start 252.889499 131.764)
		(end 252.924499 131.729)
		(width 0.1)
		(layer "B.Cu")
		(net 138)
	)
	(segment
		(start 252.924499 131.729)
		(end 252.924499 131.714)
		(width 0.1)
		(layer "B.Cu")
		(net 138)
	)
	(segment
		(start 243.297998 138.101)
		(end 249.634998 131.764)
		(width 0.1)
		(layer "In2.Cu")
		(net 138)
	)
	(segment
		(start 240 138.101)
		(end 243.297998 138.101)
		(width 0.1)
		(layer "In2.Cu")
		(net 138)
	)
	(segment
		(start 249.634998 131.764)
		(end 252.124499 131.764)
		(width 0.1)
		(layer "In2.Cu")
		(net 138)
	)
	(segment
		(start 147.075499 172.934)
		(end 146.975499 172.834)
		(width 0.15)
		(layer "F.Cu")
		(net 139)
	)
	(segment
		(start 147.281499 172.128)
		(end 147.075499 172.334)
		(width 0.15)
		(layer "F.Cu")
		(net 139)
	)
	(segment
		(start 146.975499 172.834)
		(end 146.259499 172.834)
		(width 0.15)
		(layer "F.Cu")
		(net 139)
	)
	(segment
		(start 147.075499 172.334)
		(end 147.075499 172.934)
		(width 0.15)
		(layer "F.Cu")
		(net 139)
	)
	(segment
		(start 146.259499 172.834)
		(end 146.174499 172.749)
		(width 0.15)
		(layer "F.Cu")
		(net 139)
	)
	(segment
		(start 147.281499 171.383)
		(end 147.281499 172.128)
		(width 0.15)
		(layer "F.Cu")
		(net 139)
	)
	(segment
		(start 234.65 110.598)
		(end 234.65 111.75)
		(width 0.38)
		(layer "F.Cu")
		(net 140)
	)
	(segment
		(start 199.000499 146.9995)
		(end 199.5 146.5)
		(width 0.256)
		(layer "F.Cu")
		(net 140)
	)
	(via
		(at 199.5 146.5)
		(size 0.45)
		(drill 0.1)
		(layers "F.Cu" "B.Cu")
		(remove_unused_layers yes)
		(keep_end_layers yes)
		(zone_layer_connections)
		(net 140)
	)
	(via
		(at 234.65 111.75)
		(size 0.45)
		(drill 0.1)
		(layers "F.Cu" "B.Cu")
		(remove_unused_layers yes)
		(keep_end_layers yes)
		(zone_layer_connections)
		(net 140)
	)
	(segment
		(start 228.3125 124.596816)
		(end 228.312501 124.596814)
		(width 0.148)
		(layer "In4.Cu")
		(net 140)
	)
	(segment
		(start 233.175 120.3)
		(end 233.175 119.825)
		(width 0.148)
		(layer "In4.Cu")
		(net 140)
	)
	(segment
		(start 229.443873 123.465442)
		(end 228.913543 122.935112)
		(width 0.148)
		(layer "In4.Cu")
		(net 140)
	)
	(segment
		(start 230.6106 121.238056)
		(end 231.140931 121.768387)
		(width 0.148)
		(layer "In4.Cu")
		(net 140)
	)
	(segment
		(start 200.01 145.988)
		(end 204.662 145.988)
		(width 0.148)
		(layer "In4.Cu")
		(net 140)
	)
	(segment
		(start 231.706616 121.768386)
		(end 231.706617 121.768386)
		(width 0.148)
		(layer "In4.Cu")
		(net 140)
	)
	(segment
		(start 204.662 145.988)
		(end 208.525 142.125)
		(width 0.148)
		(layer "In4.Cu")
		(net 140)
	)
	(segment
		(start 231.706617 121.202698)
		(end 231.176287 120.672368)
		(width 0.148)
		(layer "In4.Cu")
		(net 140)
	)
	(segment
		(start 208.525 140.175)
		(end 208.525 139.025)
		(width 0.148)
		(layer "In4.Cu")
		(net 140)
	)
	(segment
		(start 227.175 126.606715)
		(end 227.175 125.95)
		(width 0.148)
		(layer "In4.Cu")
		(net 140)
	)
	(segment
		(start 228.312501 124.596814)
		(end 227.782171 124.066484)
		(width 0.148)
		(layer "In4.Cu")
		(net 140)
	)
	(segment
		(start 229.443873 124.03113)
		(end 229.443872 124.031128)
		(width 0.148)
		(layer "In4.Cu")
		(net 140)
	)
	(segment
		(start 231.706616 121.2027)
		(end 231.706617 121.202698)
		(width 0.148)
		(layer "In4.Cu")
		(net 140)
	)
	(segment
		(start 224.475 125.95)
		(end 224.475 126.606742)
		(width 0.148)
		(layer "In4.Cu")
		(net 140)
	)
	(segment
		(start 230.575245 122.899758)
		(end 230.575244 122.899756)
		(width 0.148)
		(layer "In4.Cu")
		(net 140)
	)
	(segment
		(start 209.125 138.425)
		(end 209.475 138.425)
		(width 0.148)
		(layer "In4.Cu")
		(net 140)
	)
	(segment
		(start 199.4995 146.4985)
		(end 200.01 145.988)
		(width 0.148)
		(layer "In4.Cu")
		(net 140)
	)
	(segment
		(start 234.65 115.45)
		(end 234.65 111.75)
		(width 0.148)
		(layer "In4.Cu")
		(net 140)
	)
	(segment
		(start 228.913544 122.369427)
		(end 228.913542 122.369428)
		(width 0.148)
		(layer "In4.Cu")
		(net 140)
	)
	(segment
		(start 208.525 142.125)
		(end 208.525 141.775)
		(width 0.148)
		(layer "In4.Cu")
		(net 140)
	)
	(segment
		(start 229.443872 123.465444)
		(end 229.443873 123.465442)
		(width 0.148)
		(layer "In4.Cu")
		(net 140)
	)
	(segment
		(start 227.782172 123.500799)
		(end 227.78217 123.5008)
		(width 0.148)
		(layer "In4.Cu")
		(net 140)
	)
	(segment
		(start 227.625 125.5)
		(end 227.975 125.5)
		(width 0.148)
		(layer "In4.Cu")
		(net 140)
	)
	(segment
		(start 233.175 116.925)
		(end 234.65 115.45)
		(width 0.148)
		(layer "In4.Cu")
		(net 140)
	)
	(segment
		(start 211.175 138.425)
		(end 215.775 138.425)
		(width 0.148)
		(layer "In4.Cu")
		(net 140)
	)
	(segment
		(start 209.9 138.85)
		(end 209.9 139.55)
		(width 0.148)
		(layer "In4.Cu")
		(net 140)
	)
	(segment
		(start 222.675 125.95)
		(end 222.675 126.606742)
		(width 0.148)
		(layer "In4.Cu")
		(net 140)
	)
	(segment
		(start 231.706617 121.768386)
		(end 231.706616 121.768384)
		(width 0.148)
		(layer "In4.Cu")
		(net 140)
	)
	(segment
		(start 221.95 125.5)
		(end 222.225 125.5)
		(width 0.148)
		(layer "In4.Cu")
		(net 140)
	)
	(segment
		(start 228.347856 123.5008)
		(end 228.878187 124.031131)
		(width 0.148)
		(layer "In4.Cu")
		(net 140)
	)
	(segment
		(start 231.741972 120.106684)
		(end 232.272303 120.637015)
		(width 0.148)
		(layer "In4.Cu")
		(net 140)
	)
	(segment
		(start 231.675 118.025)
		(end 232.575 118.025)
		(width 0.148)
		(layer "In4.Cu")
		(net 140)
	)
	(segment
		(start 225.375 126.606742)
		(end 225.375 125.95)
		(width 0.148)
		(layer "In4.Cu")
		(net 140)
	)
	(segment
		(start 230.575244 122.334072)
		(end 230.575245 122.33407)
		(width 0.148)
		(layer "In4.Cu")
		(net 140)
	)
	(segment
		(start 219.725 127.725)
		(end 221.95 125.5)
		(width 0.148)
		(layer "In4.Cu")
		(net 140)
	)
	(segment
		(start 230.044916 121.238055)
		(end 230.044914 121.238056)
		(width 0.148)
		(layer "In4.Cu")
		(net 140)
	)
	(segment
		(start 229.479228 122.369428)
		(end 230.009559 122.899759)
		(width 0.148)
		(layer "In4.Cu")
		(net 140)
	)
	(segment
		(start 215.775 138.425)
		(end 219.725 134.475)
		(width 0.148)
		(layer "In4.Cu")
		(net 140)
	)
	(segment
		(start 208.525 139.025)
		(end 209.125 138.425)
		(width 0.148)
		(layer "In4.Cu")
		(net 140)
	)
	(segment
		(start 233.175 117.425)
		(end 233.175 116.925)
		(width 0.148)
		(layer "In4.Cu")
		(net 140)
	)
	(segment
		(start 229.443872 124.03113)
		(end 229.443873 124.03113)
		(width 0.148)
		(layer "In4.Cu")
		(net 140)
	)
	(segment
		(start 208.925 141.375)
		(end 209.125 141.375)
		(width 0.148)
		(layer "In4.Cu")
		(net 140)
	)
	(segment
		(start 230.575244 122.899758)
		(end 230.575245 122.899758)
		(width 0.148)
		(layer "In4.Cu")
		(net 140)
	)
	(segment
		(start 210.75 139.55)
		(end 210.75 138.85)
		(width 0.148)
		(layer "In4.Cu")
		(net 140)
	)
	(segment
		(start 209.125 140.575)
		(end 208.925 140.575)
		(width 0.148)
		(layer "In4.Cu")
		(net 140)
	)
	(segment
		(start 223.575 126.606742)
		(end 223.575 125.95)
		(width 0.148)
		(layer "In4.Cu")
		(net 140)
	)
	(segment
		(start 226.275 125.95)
		(end 226.275 126.606715)
		(width 0.148)
		(layer "In4.Cu")
		(net 140)
	)
	(segment
		(start 219.725 134.475)
		(end 219.725 127.725)
		(width 0.148)
		(layer "In4.Cu")
		(net 140)
	)
	(segment
		(start 230.575245 122.33407)
		(end 230.044915 121.80374)
		(width 0.148)
		(layer "In4.Cu")
		(net 140)
	)
	(segment
		(start 231.176288 120.106683)
		(end 231.176286 120.106684)
		(width 0.148)
		(layer "In4.Cu")
		(net 140)
	)
	(segment
		(start 232.837988 120.637014)
		(end 233.175 120.3)
		(width 0.148)
		(layer "In4.Cu")
		(net 140)
	)
	(segment
		(start 227.975 125.5)
		(end 228.3125 125.1625)
		(width 0.148)
		(layer "In4.Cu")
		(net 140)
	)
	(segment
		(start 232.575 119.225)
		(end 231.675 119.225)
		(width 0.148)
		(layer "In4.Cu")
		(net 140)
	)
	(arc
		(start 231.176286 120.106684)
		(mid 231.459129 119.989527)
		(end 231.741972 120.106684)
		(width 0.148)
		(layer "In4.Cu")
		(net 140)
	)
	(arc
		(start 209.475 138.425)
		(mid 209.77552 138.54948)
		(end 209.9 138.85)
		(width 0.148)
		(layer "In4.Cu")
		(net 140)
	)
	(arc
		(start 227.782171 124.066484)
		(mid 227.665014 123.783641)
		(end 227.782172 123.500799)
		(width 0.148)
		(layer "In4.Cu")
		(net 140)
	)
	(arc
		(start 224.025 125.5)
		(mid 224.343198 125.631802)
		(end 224.475 125.95)
		(width 0.148)
		(layer "In4.Cu")
		(net 140)
	)
	(arc
		(start 222.225 125.5)
		(mid 222.543198 125.631802)
		(end 222.675 125.95)
		(width 0.148)
		(layer "In4.Cu")
		(net 140)
	)
	(arc
		(start 231.176287 120.672368)
		(mid 231.05913 120.389525)
		(end 231.176288 120.106683)
		(width 0.148)
		(layer "In4.Cu")
		(net 140)
	)
	(arc
		(start 229.443872 124.031128)
		(mid 229.56103 123.748285)
		(end 229.443872 123.465444)
		(width 0.148)
		(layer "In4.Cu")
		(net 140)
	)
	(arc
		(start 232.272303 120.637015)
		(mid 232.555146 120.754172)
		(end 232.837988 120.637014)
		(width 0.148)
		(layer "In4.Cu")
		(net 140)
	)
	(arc
		(start 228.3125 125.1625)
		(mid 228.429658 124.879657)
		(end 228.3125 124.596816)
		(width 0.148)
		(layer "In4.Cu")
		(net 140)
	)
	(arc
		(start 227.175 125.95)
		(mid 227.306802 125.631802)
		(end 227.625 125.5)
		(width 0.148)
		(layer "In4.Cu")
		(net 140)
	)
	(arc
		(start 228.913542 122.369428)
		(mid 229.196385 122.252271)
		(end 229.479228 122.369428)
		(width 0.148)
		(layer "In4.Cu")
		(net 140)
	)
	(arc
		(start 230.044915 121.80374)
		(mid 229.927758 121.520897)
		(end 230.044916 121.238055)
		(width 0.148)
		(layer "In4.Cu")
		(net 140)
	)
	(arc
		(start 233.175 119.825)
		(mid 232.999264 119.400736)
		(end 232.575 119.225)
		(width 0.148)
		(layer "In4.Cu")
		(net 140)
	)
	(arc
		(start 209.9 139.55)
		(mid 210.02448 139.85052)
		(end 210.325 139.975)
		(width 0.148)
		(layer "In4.Cu")
		(net 140)
	)
	(arc
		(start 231.140931 121.768387)
		(mid 231.423774 121.885544)
		(end 231.706616 121.768386)
		(width 0.148)
		(layer "In4.Cu")
		(net 140)
	)
	(arc
		(start 209.125 141.375)
		(mid 209.407843 141.257843)
		(end 209.525 140.975)
		(width 0.148)
		(layer "In4.Cu")
		(net 140)
	)
	(arc
		(start 223.125 127.056742)
		(mid 223.443198 126.92494)
		(end 223.575 126.606742)
		(width 0.148)
		(layer "In4.Cu")
		(net 140)
	)
	(arc
		(start 227.78217 123.5008)
		(mid 228.065013 123.383643)
		(end 228.347856 123.5008)
		(width 0.148)
		(layer "In4.Cu")
		(net 140)
	)
	(arc
		(start 208.525 141.775)
		(mid 208.642157 141.492157)
		(end 208.925 141.375)
		(width 0.148)
		(layer "In4.Cu")
		(net 140)
	)
	(arc
		(start 230.009559 122.899759)
		(mid 230.292402 123.016916)
		(end 230.575244 122.899758)
		(width 0.148)
		(layer "In4.Cu")
		(net 140)
	)
	(arc
		(start 210.325 139.975)
		(mid 210.62552 139.85052)
		(end 210.75 139.55)
		(width 0.148)
		(layer "In4.Cu")
		(net 140)
	)
	(arc
		(start 226.275 126.606715)
		(mid 226.406802 126.924913)
		(end 226.725 127.056715)
		(width 0.148)
		(layer "In4.Cu")
		(net 140)
	)
	(arc
		(start 225.825 125.5)
		(mid 226.143198 125.631802)
		(end 226.275 125.95)
		(width 0.148)
		(layer "In4.Cu")
		(net 140)
	)
	(arc
		(start 230.575244 122.899756)
		(mid 230.692402 122.616913)
		(end 230.575244 122.334072)
		(width 0.148)
		(layer "In4.Cu")
		(net 140)
	)
	(arc
		(start 226.725 127.056715)
		(mid 227.043198 126.924913)
		(end 227.175 126.606715)
		(width 0.148)
		(layer "In4.Cu")
		(net 140)
	)
	(arc
		(start 224.925 127.056742)
		(mid 225.243198 126.92494)
		(end 225.375 126.606742)
		(width 0.148)
		(layer "In4.Cu")
		(net 140)
	)
	(arc
		(start 232.575 118.025)
		(mid 232.999264 117.849264)
		(end 233.175 117.425)
		(width 0.148)
		(layer "In4.Cu")
		(net 140)
	)
	(arc
		(start 224.475 126.606742)
		(mid 224.606802 126.92494)
		(end 224.925 127.056742)
		(width 0.148)
		(layer "In4.Cu")
		(net 140)
	)
	(arc
		(start 230.044914 121.238056)
		(mid 230.327757 121.120899)
		(end 230.6106 121.238056)
		(width 0.148)
		(layer "In4.Cu")
		(net 140)
	)
	(arc
		(start 225.375 125.95)
		(mid 225.506802 125.631802)
		(end 225.825 125.5)
		(width 0.148)
		(layer "In4.Cu")
		(net 140)
	)
	(arc
		(start 231.706616 121.768384)
		(mid 231.823774 121.485541)
		(end 231.706616 121.2027)
		(width 0.148)
		(layer "In4.Cu")
		(net 140)
	)
	(arc
		(start 231.075 118.625)
		(mid 231.250736 118.200736)
		(end 231.675 118.025)
		(width 0.148)
		(layer "In4.Cu")
		(net 140)
	)
	(arc
		(start 223.575 125.95)
		(mid 223.706802 125.631802)
		(end 224.025 125.5)
		(width 0.148)
		(layer "In4.Cu")
		(net 140)
	)
	(arc
		(start 222.675 126.606742)
		(mid 222.806802 126.92494)
		(end 223.125 127.056742)
		(width 0.148)
		(layer "In4.Cu")
		(net 140)
	)
	(arc
		(start 228.913543 122.935112)
		(mid 228.796386 122.652269)
		(end 228.913544 122.369427)
		(width 0.148)
		(layer "In4.Cu")
		(net 140)
	)
	(arc
		(start 209.525 140.975)
		(mid 209.407843 140.692157)
		(end 209.125 140.575)
		(width 0.148)
		(layer "In4.Cu")
		(net 140)
	)
	(arc
		(start 208.925 140.575)
		(mid 208.642157 140.457843)
		(end 208.525 140.175)
		(width 0.148)
		(layer "In4.Cu")
		(net 140)
	)
	(arc
		(start 231.675 119.225)
		(mid 231.250736 119.049264)
		(end 231.075 118.625)
		(width 0.148)
		(layer "In4.Cu")
		(net 140)
	)
	(arc
		(start 228.878187 124.031131)
		(mid 229.16103 124.148288)
		(end 229.443872 124.03113)
		(width 0.148)
		(layer "In4.Cu")
		(net 140)
	)
	(arc
		(start 210.75 138.85)
		(mid 210.87448 138.54948)
		(end 211.175 138.425)
		(width 0.148)
		(layer "In4.Cu")
		(net 140)
	)
	(segment
		(start 149.65 106)
		(end 149.65 107.152)
		(width 0.38)
		(layer "F.Cu")
		(net 141)
	)
	(segment
		(start 185.9995 143.9995)
		(end 185.5 143.5)
		(width 0.256)
		(layer "F.Cu")
		(net 141)
	)
	(via
		(at 185.5 143.5)
		(size 0.45)
		(drill 0.1)
		(layers "F.Cu" "B.Cu")
		(remove_unused_layers yes)
		(keep_end_layers yes)
		(zone_layer_connections)
		(net 141)
	)
	(via
		(at 149.65 107.152)
		(size 0.45)
		(drill 0.1)
		(layers "F.Cu" "B.Cu")
		(remove_unused_layers yes)
		(keep_end_layers yes)
		(zone_layer_connections)
		(net 141)
	)
	(segment
		(start 185.5 143.2)
		(end 185.6 143.1)
		(width 0.1)
		(layer "In6.Cu")
		(net 141)
	)
	(segment
		(start 185.791422 139.9)
		(end 185.341422 139.9)
		(width 0.1)
		(layer "In6.Cu")
		(net 141)
	)
	(segment
		(start 155.699706 110.48)
		(end 151.374706 110.48)
		(width 0.13)
		(layer "In6.Cu")
		(net 141)
	)
	(segment
		(start 185.809644 143.1)
		(end 186.1 142.809644)
		(width 0.1)
		(layer "In6.Cu")
		(net 141)
	)
	(segment
		(start 156.57 111.350294)
		(end 155.699706 110.48)
		(width 0.13)
		(layer "In6.Cu")
		(net 141)
	)
	(segment
		(start 157.12 113.410294)
		(end 156.57 112.860294)
		(width 0.13)
		(layer "In6.Cu")
		(net 141)
	)
	(segment
		(start 186.1 142.809644)
		(end 186.1 140.208578)
		(width 0.1)
		(layer "In6.Cu")
		(net 141)
	)
	(segment
		(start 157.12 130.275294)
		(end 157.12 118.4)
		(width 0.13)
		(layer "In6.Cu")
		(net 141)
	)
	(segment
		(start 172.525294 136.705)
		(end 171.652375 137.577919)
		(width 0.13)
		(layer "In6.Cu")
		(net 141)
	)
	(segment
		(start 186.1 140.208578)
		(end 185.791422 139.9)
		(width 0.1)
		(layer "In6.Cu")
		(net 141)
	)
	(segment
		(start 185.125187 137.280481)
		(end 184.549706 136.705)
		(width 0.13)
		(layer "In6.Cu")
		(net 141)
	)
	(segment
		(start 185.5 143.5)
		(end 185.5 143.2)
		(width 0.1)
		(layer "In6.Cu")
		(net 141)
	)
	(segment
		(start 150.595 109.700294)
		(end 150.595 109.050294)
		(width 0.13)
		(layer "In6.Cu")
		(net 141)
	)
	(segment
		(start 171.652375 137.577919)
		(end 164.422625 137.577919)
		(width 0.13)
		(layer "In6.Cu")
		(net 141)
	)
	(segment
		(start 184.549706 136.705)
		(end 172.525294 136.705)
		(width 0.13)
		(layer "In6.Cu")
		(net 141)
	)
	(segment
		(start 164.422625 137.577919)
		(end 157.12 130.275294)
		(width 0.13)
		(layer "In6.Cu")
		(net 141)
	)
	(segment
		(start 149.345 107.457)
		(end 149.65 107.152)
		(width 0.13)
		(layer "In6.Cu")
		(net 141)
	)
	(segment
		(start 185.1 137.767386)
		(end 185.125187 137.742199)
		(width 0.1)
		(layer "In6.Cu")
		(net 141)
	)
	(segment
		(start 185.341422 139.9)
		(end 185.1 139.658578)
		(width 0.1)
		(layer "In6.Cu")
		(net 141)
	)
	(segment
		(start 156.57 112.860294)
		(end 156.57 111.350294)
		(width 0.13)
		(layer "In6.Cu")
		(net 141)
	)
	(segment
		(start 185.1 139.658578)
		(end 185.1 137.767386)
		(width 0.1)
		(layer "In6.Cu")
		(net 141)
	)
	(segment
		(start 149.345 107.800294)
		(end 149.345 107.457)
		(width 0.13)
		(layer "In6.Cu")
		(net 141)
	)
	(segment
		(start 156.45 117.73)
		(end 156.263989 117.73)
		(width 0.13)
		(layer "In6.Cu")
		(net 141)
	)
	(segment
		(start 151.374706 110.48)
		(end 150.595 109.700294)
		(width 0.13)
		(layer "In6.Cu")
		(net 141)
	)
	(segment
		(start 185.125187 137.742199)
		(end 185.125187 137.280481)
		(width 0.13)
		(layer "In6.Cu")
		(net 141)
	)
	(segment
		(start 185.6 143.1)
		(end 185.809644 143.1)
		(width 0.1)
		(layer "In6.Cu")
		(net 141)
	)
	(segment
		(start 156.263989 114.67)
		(end 156.45 114.67)
		(width 0.13)
		(layer "In6.Cu")
		(net 141)
	)
	(segment
		(start 156.45 115.53)
		(end 156.263989 115.53)
		(width 0.13)
		(layer "In6.Cu")
		(net 141)
	)
	(segment
		(start 157.12 114)
		(end 157.12 113.410294)
		(width 0.13)
		(layer "In6.Cu")
		(net 141)
	)
	(segment
		(start 156.263989 116.87)
		(end 156.45 116.87)
		(width 0.13)
		(layer "In6.Cu")
		(net 141)
	)
	(segment
		(start 150.595 109.050294)
		(end 149.345 107.800294)
		(width 0.13)
		(layer "In6.Cu")
		(net 141)
	)
	(arc
		(start 156.45 114.67)
		(mid 156.923762 114.473762)
		(end 157.12 114)
		(width 0.13)
		(layer "In6.Cu")
		(net 141)
	)
	(arc
		(start 156.263989 115.53)
		(mid 155.959933 115.404056)
		(end 155.833989 115.1)
		(width 0.13)
		(layer "In6.Cu")
		(net 141)
	)
	(arc
		(start 156.263989 117.73)
		(mid 155.959933 117.604056)
		(end 155.833989 117.3)
		(width 0.13)
		(layer "In6.Cu")
		(net 141)
	)
	(arc
		(start 155.833989 117.3)
		(mid 155.959933 116.995944)
		(end 156.263989 116.87)
		(width 0.13)
		(layer "In6.Cu")
		(net 141)
	)
	(arc
		(start 156.45 116.87)
		(mid 156.923762 116.673762)
		(end 157.12 116.2)
		(width 0.13)
		(layer "In6.Cu")
		(net 141)
	)
	(arc
		(start 157.12 118.4)
		(mid 156.923762 117.926238)
		(end 156.45 117.73)
		(width 0.13)
		(layer "In6.Cu")
		(net 141)
	)
	(arc
		(start 157.12 116.2)
		(mid 156.923762 115.726238)
		(end 156.45 115.53)
		(width 0.13)
		(layer "In6.Cu")
		(net 141)
	)
	(arc
		(start 155.833989 115.1)
		(mid 155.959933 114.795944)
		(end 156.263989 114.67)
		(width 0.13)
		(layer "In6.Cu")
		(net 141)
	)
	(segment
		(start 185.9995 142.999499)
		(end 185.500001 142.5)
		(width 0.256)
		(layer "F.Cu")
		(net 142)
	)
	(segment
		(start 148.8 106)
		(end 148.8 107.152)
		(width 0.38)
		(layer "F.Cu")
		(net 142)
	)
	(via
		(at 148.8 107.152)
		(size 0.45)
		(drill 0.1)
		(layers "F.Cu" "B.Cu")
		(remove_unused_layers yes)
		(keep_end_layers yes)
		(zone_layer_connections)
		(net 142)
	)
	(via
		(at 185.500001 142.5)
		(size 0.45)
		(drill 0.1)
		(layers "F.Cu" "B.Cu")
		(remove_unused_layers yes)
		(keep_end_layers yes)
		(zone_layer_connections)
		(net 142)
	)
	(segment
		(start 171.751787 137.817919)
		(end 164.323213 137.817919)
		(width 0.13)
		(layer "In6.Cu")
		(net 142)
	)
	(segment
		(start 156.33 111.449706)
		(end 155.600294 110.72)
		(width 0.13)
		(layer "In6.Cu")
		(net 142)
	)
	(segment
		(start 150.355 109.149706)
		(end 149.105 107.899706)
		(width 0.13)
		(layer "In6.Cu")
		(net 142)
	)
	(segment
		(start 185.7268 142.9)
		(end 185.9 142.7268)
		(width 0.1)
		(layer "In6.Cu")
		(net 142)
	)
	(segment
		(start 185.9 141.715952)
		(end 185.9 140.291422)
		(width 0.1)
		(layer "In6.Cu")
		(net 142)
	)
	(segment
		(start 156.45 117.97)
		(end 156.263989 117.97)
		(width 0.13)
		(layer "In6.Cu")
		(net 142)
	)
	(segment
		(start 149.105 107.415)
		(end 148.842 107.152)
		(width 0.13)
		(layer "In6.Cu")
		(net 142)
	)
	(segment
		(start 156.45 115.77)
		(end 156.263989 115.77)
		(width 0.13)
		(layer "In6.Cu")
		(net 142)
	)
	(segment
		(start 184.9 137.757012)
		(end 184.885187 137.742199)
		(width 0.1)
		(layer "In6.Cu")
		(net 142)
	)
	(segment
		(start 184.885187 137.742199)
		(end 184.885187 137.379893)
		(width 0.13)
		(layer "In6.Cu")
		(net 142)
	)
	(segment
		(start 185.605951 142.015952)
		(end 185.605951 142.01)
		(width 0.1)
		(layer "In6.Cu")
		(net 142)
	)
	(segment
		(start 185.56 142.9)
		(end 185.7268 142.9)
		(width 0.1)
		(layer "In6.Cu")
		(net 142)
	)
	(segment
		(start 185.752975 141.862976)
		(end 185.752976 141.862976)
		(width 0.1)
		(layer "In6.Cu")
		(net 142)
	)
	(segment
		(start 184.450294 136.945)
		(end 172.624706 136.945)
		(width 0.13)
		(layer "In6.Cu")
		(net 142)
	)
	(segment
		(start 172.624706 136.945)
		(end 171.751787 137.817919)
		(width 0.13)
		(layer "In6.Cu")
		(net 142)
	)
	(segment
		(start 156.263989 114.43)
		(end 156.45 114.43)
		(width 0.13)
		(layer "In6.Cu")
		(net 142)
	)
	(segment
		(start 184.885187 137.379893)
		(end 184.450294 136.945)
		(width 0.13)
		(layer "In6.Cu")
		(net 142)
	)
	(segment
		(start 156.33 112.959706)
		(end 156.33 111.449706)
		(width 0.13)
		(layer "In6.Cu")
		(net 142)
	)
	(segment
		(start 151.275294 110.72)
		(end 150.355 109.799706)
		(width 0.13)
		(layer "In6.Cu")
		(net 142)
	)
	(segment
		(start 185.258578 140.1)
		(end 184.9 139.741422)
		(width 0.1)
		(layer "In6.Cu")
		(net 142)
	)
	(segment
		(start 185.500001 142.840001)
		(end 185.56 142.9)
		(width 0.1)
		(layer "In6.Cu")
		(net 142)
	)
	(segment
		(start 156.88 113.509706)
		(end 156.33 112.959706)
		(width 0.13)
		(layer "In6.Cu")
		(net 142)
	)
	(segment
		(start 185.708578 140.1)
		(end 185.258578 140.1)
		(width 0.1)
		(layer "In6.Cu")
		(net 142)
	)
	(segment
		(start 185.9 142.7268)
		(end 185.9 142.31)
		(width 0.1)
		(layer "In6.Cu")
		(net 142)
	)
	(segment
		(start 155.600294 110.72)
		(end 151.275294 110.72)
		(width 0.13)
		(layer "In6.Cu")
		(net 142)
	)
	(segment
		(start 156.88 130.374706)
		(end 156.88 118.4)
		(width 0.13)
		(layer "In6.Cu")
		(net 142)
	)
	(segment
		(start 156.263989 116.63)
		(end 156.45 116.63)
		(width 0.13)
		(layer "In6.Cu")
		(net 142)
	)
	(segment
		(start 156.88 114)
		(end 156.88 113.509706)
		(width 0.13)
		(layer "In6.Cu")
		(net 142)
	)
	(segment
		(start 184.9 139.741422)
		(end 184.9 137.757012)
		(width 0.1)
		(layer "In6.Cu")
		(net 142)
	)
	(segment
		(start 185.752976 142.162976)
		(end 185.752975 142.162976)
		(width 0.1)
		(layer "In6.Cu")
		(net 142)
	)
	(segment
		(start 185.9 140.291422)
		(end 185.708578 140.1)
		(width 0.1)
		(layer "In6.Cu")
		(net 142)
	)
	(segment
		(start 150.355 109.799706)
		(end 150.355 109.149706)
		(width 0.13)
		(layer "In6.Cu")
		(net 142)
	)
	(segment
		(start 148.842 107.152)
		(end 148.8 107.152)
		(width 0.13)
		(layer "In6.Cu")
		(net 142)
	)
	(segment
		(start 164.323213 137.817919)
		(end 156.88 130.374706)
		(width 0.13)
		(layer "In6.Cu")
		(net 142)
	)
	(segment
		(start 185.500001 142.5)
		(end 185.500001 142.840001)
		(width 0.1)
		(layer "In6.Cu")
		(net 142)
	)
	(segment
		(start 149.105 107.899706)
		(end 149.105 107.415)
		(width 0.13)
		(layer "In6.Cu")
		(net 142)
	)
	(arc
		(start 185.9 142.31)
		(mid 185.856938 142.206038)
		(end 185.752976 142.162976)
		(width 0.1)
		(layer "In6.Cu")
		(net 142)
	)
	(arc
		(start 156.263989 117.97)
		(mid 155.790227 117.773762)
		(end 155.593989 117.3)
		(width 0.13)
		(layer "In6.Cu")
		(net 142)
	)
	(arc
		(start 156.45 114.43)
		(mid 156.754056 114.304056)
		(end 156.88 114)
		(width 0.13)
		(layer "In6.Cu")
		(net 142)
	)
	(arc
		(start 185.752975 142.162976)
		(mid 185.649013 142.119914)
		(end 185.605951 142.015952)
		(width 0.1)
		(layer "In6.Cu")
		(net 142)
	)
	(arc
		(start 185.752976 141.862976)
		(mid 185.856938 141.819914)
		(end 185.9 141.715952)
		(width 0.1)
		(layer "In6.Cu")
		(net 142)
	)
	(arc
		(start 156.45 116.63)
		(mid 156.754056 116.504056)
		(end 156.88 116.2)
		(width 0.13)
		(layer "In6.Cu")
		(net 142)
	)
	(arc
		(start 156.263989 115.77)
		(mid 155.790227 115.573762)
		(end 155.593989 115.1)
		(width 0.13)
		(layer "In6.Cu")
		(net 142)
	)
	(arc
		(start 156.88 118.4)
		(mid 156.754056 118.095944)
		(end 156.45 117.97)
		(width 0.13)
		(layer "In6.Cu")
		(net 142)
	)
	(arc
		(start 155.593989 115.1)
		(mid 155.790227 114.626238)
		(end 156.263989 114.43)
		(width 0.13)
		(layer "In6.Cu")
		(net 142)
	)
	(arc
		(start 156.88 116.2)
		(mid 156.754056 115.895944)
		(end 156.45 115.77)
		(width 0.13)
		(layer "In6.Cu")
		(net 142)
	)
	(arc
		(start 155.593989 117.3)
		(mid 155.790227 116.826238)
		(end 156.263989 116.63)
		(width 0.13)
		(layer "In6.Cu")
		(net 142)
	)
	(arc
		(start 185.605951 142.01)
		(mid 185.649013 141.906038)
		(end 185.752975 141.862976)
		(width 0.1)
		(layer "In6.Cu")
		(net 142)
	)
	(segment
		(start 230.4 110.598)
		(end 230.4 111.75)
		(width 0.38)
		(layer "F.Cu")
		(net 143)
	)
	(segment
		(start 201.0005 148.999501)
		(end 201.5 148.5)
		(width 0.256)
		(layer "F.Cu")
		(net 143)
	)
	(via
		(at 230.4 111.75)
		(size 0.45)
		(drill 0.1)
		(layers "F.Cu" "B.Cu")
		(remove_unused_layers yes)
		(keep_end_layers yes)
		(zone_layer_connections)
		(net 143)
	)
	(via
		(at 201.5 148.5)
		(size 0.45)
		(drill 0.1)
		(layers "F.Cu" "B.Cu")
		(remove_unused_layers yes)
		(keep_end_layers yes)
		(zone_layer_connections)
		(net 143)
	)
	(segment
		(start 221.75 115.193353)
		(end 221.75 114.65)
		(width 0.148)
		(layer "In4.Cu")
		(net 143)
	)
	(segment
		(start 212.775 134.525)
		(end 206.075 134.525)
		(width 0.148)
		(layer "In4.Cu")
		(net 143)
	)
	(segment
		(start 228.771967 114.247703)
		(end 228.549264 114.025)
		(width 0.148)
		(layer "In4.Cu")
		(net 143)
	)
	(segment
		(start 204.4 136.2)
		(end 204.4 142.05)
		(width 0.148)
		(layer "In4.Cu")
		(net 143)
	)
	(segment
		(start 229.620477 113.399155)
		(end 229.397793 113.176471)
		(width 0.148)
		(layer "In4.Cu")
		(net 143)
	)
	(segment
		(start 219.35 114.25)
		(end 218.65 114.95)
		(width 0.148)
		(layer "In4.Cu")
		(net 143)
	)
	(segment
		(start 230.044741 112.97489)
		(end 230.044741 112.974889)
		(width 0.148)
		(layer "In4.Cu")
		(net 143)
	)
	(segment
		(start 225.75 114.65)
		(end 225.75 115.193353)
		(width 0.148)
		(layer "In4.Cu")
		(net 143)
	)
	(segment
		(start 228.125 114.025)
		(end 227.9 114.25)
		(width 0.148)
		(layer "In4.Cu")
		(net 143)
	)
	(segment
		(start 197 143.435728)
		(end 197 147.8)
		(width 0.148)
		(layer "In4.Cu")
		(net 143)
	)
	(segment
		(start 197.435728 143)
		(end 197 143.435728)
		(width 0.148)
		(layer "In4.Cu")
		(net 143)
	)
	(segment
		(start 215 132.3)
		(end 212.775 134.525)
		(width 0.148)
		(layer "In4.Cu")
		(net 143)
	)
	(segment
		(start 197.2 148)
		(end 201 148)
		(width 0.148)
		(layer "In4.Cu")
		(net 143)
	)
	(segment
		(start 220.95 114.65)
		(end 220.95 115.193353)
		(width 0.148)
		(layer "In4.Cu")
		(net 143)
	)
	(segment
		(start 201 148)
		(end 201.5 148.5)
		(width 0.148)
		(layer "In4.Cu")
		(net 143)
	)
	(segment
		(start 222.55 114.65)
		(end 222.55 115.193353)
		(width 0.148)
		(layer "In4.Cu")
		(net 143)
	)
	(segment
		(start 226.55 115.193353)
		(end 226.55 114.65)
		(width 0.148)
		(layer "In4.Cu")
		(net 143)
	)
	(segment
		(start 223.35 115.193353)
		(end 223.35 114.65)
		(width 0.148)
		(layer "In4.Cu")
		(net 143)
	)
	(segment
		(start 203.45 143)
		(end 197.435728 143)
		(width 0.148)
		(layer "In4.Cu")
		(net 143)
	)
	(segment
		(start 230.4 111.75)
		(end 229.822056 112.327941)
		(width 0.148)
		(layer "In4.Cu")
		(net 143)
	)
	(segment
		(start 215 123.8)
		(end 215 132.3)
		(width 0.148)
		(layer "In4.Cu")
		(net 143)
	)
	(segment
		(start 224.95 115.193353)
		(end 224.95 114.65)
		(width 0.148)
		(layer "In4.Cu")
		(net 143)
	)
	(segment
		(start 219.573892 114.25)
		(end 219.35 114.25)
		(width 0.148)
		(layer "In4.Cu")
		(net 143)
	)
	(segment
		(start 228.973529 113.176471)
		(end 228.973528 113.176471)
		(width 0.148)
		(layer "In4.Cu")
		(net 143)
	)
	(segment
		(start 218.65 114.95)
		(end 218.65 120.15)
		(width 0.148)
		(layer "In4.Cu")
		(net 143)
	)
	(segment
		(start 206.075 134.525)
		(end 204.4 136.2)
		(width 0.148)
		(layer "In4.Cu")
		(net 143)
	)
	(segment
		(start 229.196231 113.823438)
		(end 229.196231 113.823437)
		(width 0.148)
		(layer "In4.Cu")
		(net 143)
	)
	(segment
		(start 228.973527 113.600734)
		(end 229.196231 113.823438)
		(width 0.148)
		(layer "In4.Cu")
		(net 143)
	)
	(segment
		(start 224.15 114.65)
		(end 224.15 115.193353)
		(width 0.148)
		(layer "In4.Cu")
		(net 143)
	)
	(segment
		(start 228.973528 113.176471)
		(end 228.973527 113.17647)
		(width 0.148)
		(layer "In4.Cu")
		(net 143)
	)
	(segment
		(start 227.35 114.65)
		(end 227.35 115.193353)
		(width 0.148)
		(layer "In4.Cu")
		(net 143)
	)
	(segment
		(start 229.822056 112.752205)
		(end 230.044741 112.97489)
		(width 0.148)
		(layer "In4.Cu")
		(net 143)
	)
	(segment
		(start 218.65 120.15)
		(end 215 123.8)
		(width 0.148)
		(layer "In4.Cu")
		(net 143)
	)
	(segment
		(start 227.9 114.25)
		(end 227.75 114.25)
		(width 0.148)
		(layer "In4.Cu")
		(net 143)
	)
	(segment
		(start 220.15 115.193353)
		(end 220.15 114.65)
		(width 0.148)
		(layer "In4.Cu")
		(net 143)
	)
	(segment
		(start 219.75 114.25)
		(end 219.573892 114.25)
		(width 0.148)
		(layer "In4.Cu")
		(net 143)
	)
	(segment
		(start 197 147.8)
		(end 197.2 148)
		(width 0.148)
		(layer "In4.Cu")
		(net 143)
	)
	(segment
		(start 204.4 142.05)
		(end 203.45 143)
		(width 0.148)
		(layer "In4.Cu")
		(net 143)
	)
	(arc
		(start 222.55 115.193353)
		(mid 222.432843 115.476196)
		(end 222.15 115.593353)
		(width 0.148)
		(layer "In4.Cu")
		(net 143)
	)
	(arc
		(start 222.15 115.593353)
		(mid 221.867157 115.476196)
		(end 221.75 115.193353)
		(width 0.148)
		(layer "In4.Cu")
		(net 143)
	)
	(arc
		(start 226.95 115.593353)
		(mid 226.667157 115.476196)
		(end 226.55 115.193353)
		(width 0.148)
		(layer "In4.Cu")
		(net 143)
	)
	(arc
		(start 220.95 115.193353)
		(mid 220.832843 115.476196)
		(end 220.55 115.593353)
		(width 0.148)
		(layer "In4.Cu")
		(net 143)
	)
	(arc
		(start 222.95 114.25)
		(mid 222.667157 114.367157)
		(end 222.55 114.65)
		(width 0.148)
		(layer "In4.Cu")
		(net 143)
	)
	(arc
		(start 224.15 115.193353)
		(mid 224.032843 115.476196)
		(end 223.75 115.593353)
		(width 0.148)
		(layer "In4.Cu")
		(net 143)
	)
	(arc
		(start 230.044741 113.399155)
		(mid 229.832609 113.487023)
		(end 229.620477 113.399155)
		(width 0.148)
		(layer "In4.Cu")
		(net 143)
	)
	(arc
		(start 230.044741 112.974889)
		(mid 230.132609 113.187022)
		(end 230.044741 113.399155)
		(width 0.148)
		(layer "In4.Cu")
		(net 143)
	)
	(arc
		(start 223.75 115.593353)
		(mid 223.467157 115.476196)
		(end 223.35 115.193353)
		(width 0.148)
		(layer "In4.Cu")
		(net 143)
	)
	(arc
		(start 220.55 115.593353)
		(mid 220.267157 115.476196)
		(end 220.15 115.193353)
		(width 0.148)
		(layer "In4.Cu")
		(net 143)
	)
	(arc
		(start 225.75 115.193353)
		(mid 225.632843 115.476196)
		(end 225.35 115.593353)
		(width 0.148)
		(layer "In4.Cu")
		(net 143)
	)
	(arc
		(start 227.75 114.25)
		(mid 227.467157 114.367157)
		(end 227.35 114.65)
		(width 0.148)
		(layer "In4.Cu")
		(net 143)
	)
	(arc
		(start 224.95 114.65)
		(mid 224.832843 114.367157)
		(end 224.55 114.25)
		(width 0.148)
		(layer "In4.Cu")
		(net 143)
	)
	(arc
		(start 224.55 114.25)
		(mid 224.267157 114.367157)
		(end 224.15 114.65)
		(width 0.148)
		(layer "In4.Cu")
		(net 143)
	)
	(arc
		(start 221.75 114.65)
		(mid 221.632843 114.367157)
		(end 221.35 114.25)
		(width 0.148)
		(layer "In4.Cu")
		(net 143)
	)
	(arc
		(start 229.822056 112.327941)
		(mid 229.734188 112.540073)
		(end 229.822056 112.752205)
		(width 0.148)
		(layer "In4.Cu")
		(net 143)
	)
	(arc
		(start 221.35 114.25)
		(mid 221.067157 114.367157)
		(end 220.95 114.65)
		(width 0.148)
		(layer "In4.Cu")
		(net 143)
	)
	(arc
		(start 225.35 115.593353)
		(mid 225.067157 115.476196)
		(end 224.95 115.193353)
		(width 0.148)
		(layer "In4.Cu")
		(net 143)
	)
	(arc
		(start 228.549264 114.025)
		(mid 228.337132 113.937132)
		(end 228.125 114.025)
		(width 0.148)
		(layer "In4.Cu")
		(net 143)
	)
	(arc
		(start 227.35 115.193353)
		(mid 227.232843 115.476196)
		(end 226.95 115.593353)
		(width 0.148)
		(layer "In4.Cu")
		(net 143)
	)
	(arc
		(start 229.196231 113.823437)
		(mid 229.284099 114.03557)
		(end 229.196231 114.247703)
		(width 0.148)
		(layer "In4.Cu")
		(net 143)
	)
	(arc
		(start 229.397793 113.176471)
		(mid 229.185661 113.088603)
		(end 228.973529 113.176471)
		(width 0.148)
		(layer "In4.Cu")
		(net 143)
	)
	(arc
		(start 226.55 114.65)
		(mid 226.432843 114.367157)
		(end 226.15 114.25)
		(width 0.148)
		(layer "In4.Cu")
		(net 143)
	)
	(arc
		(start 228.973527 113.17647)
		(mid 228.885659 113.388602)
		(end 228.973527 113.600734)
		(width 0.148)
		(layer "In4.Cu")
		(net 143)
	)
	(arc
		(start 226.15 114.25)
		(mid 225.867157 114.367157)
		(end 225.75 114.65)
		(width 0.148)
		(layer "In4.Cu")
		(net 143)
	)
	(arc
		(start 229.196231 114.247703)
		(mid 228.984099 114.335571)
		(end 228.771967 114.247703)
		(width 0.148)
		(layer "In4.Cu")
		(net 143)
	)
	(arc
		(start 223.35 114.65)
		(mid 223.232843 114.367157)
		(end 222.95 114.25)
		(width 0.148)
		(layer "In4.Cu")
		(net 143)
	)
	(arc
		(start 220.15 114.65)
		(mid 220.032843 114.367157)
		(end 219.75 114.25)
		(width 0.148)
		(layer "In4.Cu")
		(net 143)
	)
	(segment
		(start 228.7 110.598)
		(end 228.7 111.75)
		(width 0.38)
		(layer "F.Cu")
		(net 144)
	)
	(segment
		(start 200.0005 148.9995)
		(end 200.5 148.5)
		(width 0.256)
		(layer "F.Cu")
		(net 144)
	)
	(via
		(at 228.7 111.75)
		(size 0.45)
		(drill 0.1)
		(layers "F.Cu" "B.Cu")
		(remove_unused_layers yes)
		(keep_end_layers yes)
		(zone_layer_connections)
		(net 144)
	)
	(via
		(at 200.5 148.5)
		(size 0.45)
		(drill 0.1)
		(layers "F.Cu" "B.Cu")
		(remove_unused_layers yes)
		(keep_end_layers yes)
		(zone_layer_connections)
		(net 144)
	)
	(segment
		(start 196 142.4)
		(end 196.4 142)
		(width 0.148)
		(layer "In4.Cu")
		(net 144)
	)
	(segment
		(start 196.25 149)
		(end 196 148.75)
		(width 0.148)
		(layer "In4.Cu")
		(net 144)
	)
	(segment
		(start 202.15 142)
		(end 202.95 141.2)
		(width 0.148)
		(layer "In4.Cu")
		(net 144)
	)
	(segment
		(start 209.193426 133.55)
		(end 211.875 133.55)
		(width 0.148)
		(layer "In4.Cu")
		(net 144)
	)
	(segment
		(start 212.75 126.675)
		(end 211.05 126.675)
		(width 0.148)
		(layer "In4.Cu")
		(net 144)
	)
	(segment
		(start 218.55 113.1)
		(end 227.35 113.1)
		(width 0.148)
		(layer "In4.Cu")
		(net 144)
	)
	(segment
		(start 211.875 133.55)
		(end 213.6 131.825)
		(width 0.148)
		(layer "In4.Cu")
		(net 144)
	)
	(segment
		(start 213.6 124.125)
		(end 213.6 123.2)
		(width 0.148)
		(layer "In4.Cu")
		(net 144)
	)
	(segment
		(start 213.6 131.825)
		(end 213.6 127.525)
		(width 0.148)
		(layer "In4.Cu")
		(net 144)
	)
	(segment
		(start 207.825 133.55)
		(end 209.193426 133.55)
		(width 0.148)
		(layer "In4.Cu")
		(net 144)
	)
	(segment
		(start 200 149)
		(end 196.25 149)
		(width 0.148)
		(layer "In4.Cu")
		(net 144)
	)
	(segment
		(start 211.05 124.975)
		(end 212.75 124.975)
		(width 0.148)
		(layer "In4.Cu")
		(net 144)
	)
	(segment
		(start 217.65 119.15)
		(end 217.65 114)
		(width 0.148)
		(layer "In4.Cu")
		(net 144)
	)
	(segment
		(start 202.95 141.2)
		(end 202.95 135.2)
		(width 0.148)
		(layer "In4.Cu")
		(net 144)
	)
	(segment
		(start 213.6 123.2)
		(end 217.65 119.15)
		(width 0.148)
		(layer "In4.Cu")
		(net 144)
	)
	(segment
		(start 205.65 132.825)
		(end 205.65 130.282826)
		(width 0.148)
		(layer "In4.Cu")
		(net 144)
	)
	(segment
		(start 227.35 113.1)
		(end 228.7 111.75)
		(width 0.148)
		(layer "In4.Cu")
		(net 144)
	)
	(segment
		(start 204.6 133.55)
		(end 204.925 133.55)
		(width 0.148)
		(layer "In4.Cu")
		(net 144)
	)
	(segment
		(start 200.5 148.5)
		(end 200 149)
		(width 0.148)
		(layer "In4.Cu")
		(net 144)
	)
	(segment
		(start 217.65 114)
		(end 218.55 113.1)
		(width 0.148)
		(layer "In4.Cu")
		(net 144)
	)
	(segment
		(start 196 148.75)
		(end 196 142.4)
		(width 0.148)
		(layer "In4.Cu")
		(net 144)
	)
	(segment
		(start 207.1 130.282826)
		(end 207.1 132.825)
		(width 0.148)
		(layer "In4.Cu")
		(net 144)
	)
	(segment
		(start 196.4 142)
		(end 202.15 142)
		(width 0.148)
		(layer "In4.Cu")
		(net 144)
	)
	(segment
		(start 202.95 135.2)
		(end 204.6 133.55)
		(width 0.148)
		(layer "In4.Cu")
		(net 144)
	)
	(arc
		(start 212.75 124.975)
		(mid 213.351041 124.726041)
		(end 213.6 124.125)
		(width 0.148)
		(layer "In4.Cu")
		(net 144)
	)
	(arc
		(start 213.6 127.525)
		(mid 213.351041 126.923959)
		(end 212.75 126.675)
		(width 0.148)
		(layer "In4.Cu")
		(net 144)
	)
	(arc
		(start 211.05 126.675)
		(mid 210.448959 126.426041)
		(end 210.2 125.825)
		(width 0.148)
		(layer "In4.Cu")
		(net 144)
	)
	(arc
		(start 206.375 129.557826)
		(mid 206.887652 129.770174)
		(end 207.1 130.282826)
		(width 0.148)
		(layer "In4.Cu")
		(net 144)
	)
	(arc
		(start 205.65 130.282826)
		(mid 205.862348 129.770174)
		(end 206.375 129.557826)
		(width 0.148)
		(layer "In4.Cu")
		(net 144)
	)
	(arc
		(start 207.1 132.825)
		(mid 207.312348 133.337652)
		(end 207.825 133.55)
		(width 0.148)
		(layer "In4.Cu")
		(net 144)
	)
	(arc
		(start 210.2 125.825)
		(mid 210.448959 125.223959)
		(end 211.05 124.975)
		(width 0.148)
		(layer "In4.Cu")
		(net 144)
	)
	(arc
		(start 204.925 133.55)
		(mid 205.437652 133.337652)
		(end 205.65 132.825)
		(width 0.148)
		(layer "In4.Cu")
		(net 144)
	)
	(segment
		(start 227 110.598)
		(end 227 111.75)
		(width 0.38)
		(layer "F.Cu")
		(net 145)
	)
	(segment
		(start 198.0005 143.9995)
		(end 198.5 143.5)
		(width 0.256)
		(layer "F.Cu")
		(net 145)
	)
	(via
		(at 198.5 143.5)
		(size 0.45)
		(drill 0.1)
		(layers "F.Cu" "B.Cu")
		(remove_unused_layers yes)
		(keep_end_layers yes)
		(zone_layer_connections)
		(net 145)
	)
	(via
		(at 227 111.75)
		(size 0.45)
		(drill 0.1)
		(layers "F.Cu" "B.Cu")
		(remove_unused_layers yes)
		(keep_end_layers yes)
		(zone_layer_connections)
		(net 145)
	)
	(segment
		(start 199.367156 142)
		(end 199.7 142)
		(width 0.15)
		(layer "In2.Cu")
		(net 145)
	)
	(segment
		(start 213.3 119.840551)
		(end 213.3 119.5)
		(width 0.148)
		(layer "In2.Cu")
		(net 145)
	)
	(segment
		(start 212.5 119.5)
		(end 212.5 119.84055)
		(width 0.148)
		(layer "In2.Cu")
		(net 145)
	)
	(segment
		(start 218.9 119.5)
		(end 218.9 119.840549)
		(width 0.148)
		(layer "In2.Cu")
		(net 145)
	)
	(segment
		(start 214.1 119.5)
		(end 214.1 119.840551)
		(width 0.148)
		(layer "In2.Cu")
		(net 145)
	)
	(segment
		(start 210.9 119.5)
		(end 210.9 119.840549)
		(width 0.148)
		(layer "In2.Cu")
		(net 145)
	)
	(segment
		(start 210.1 119.840549)
		(end 210.1 119.5)
		(width 0.148)
		(layer "In2.Cu")
		(net 145)
	)
	(segment
		(start 220.5 119.5)
		(end 220.5 119.840549)
		(width 0.148)
		(layer "In2.Cu")
		(net 145)
	)
	(segment
		(start 208.5 119.840551)
		(end 208.5 119.5)
		(width 0.148)
		(layer "In2.Cu")
		(net 145)
	)
	(segment
		(start 200 126.325)
		(end 200 140.5)
		(width 0.148)
		(layer "In2.Cu")
		(net 145)
	)
	(segment
		(start 216.5 119.840549)
		(end 216.5 119.5)
		(width 0.148)
		(layer "In2.Cu")
		(net 145)
	)
	(segment
		(start 214.9 119.840549)
		(end 214.9 119.5)
		(width 0.148)
		(layer "In2.Cu")
		(net 145)
	)
	(segment
		(start 205.15 119.8)
		(end 197.45 119.8)
		(width 0.148)
		(layer "In2.Cu")
		(net 145)
	)
	(segment
		(start 197.45 119.8)
		(end 196.45 120.8)
		(width 0.148)
		(layer "In2.Cu")
		(net 145)
	)
	(segment
		(start 206.5 119.1)
		(end 205.85 119.1)
		(width 0.148)
		(layer "In2.Cu")
		(net 145)
	)
	(segment
		(start 221.4 119.1)
		(end 220.9 119.1)
		(width 0.148)
		(layer "In2.Cu")
		(net 145)
	)
	(segment
		(start 205.85 119.1)
		(end 205.15 119.8)
		(width 0.148)
		(layer "In2.Cu")
		(net 145)
	)
	(segment
		(start 200 141.7)
		(end 200 140.5)
		(width 0.15)
		(layer "In2.Cu")
		(net 145)
	)
	(segment
		(start 219.7 119.840549)
		(end 219.7 119.5)
		(width 0.148)
		(layer "In2.Cu")
		(net 145)
	)
	(segment
		(start 215.7 119.5)
		(end 215.7 119.840549)
		(width 0.148)
		(layer "In2.Cu")
		(net 145)
	)
	(segment
		(start 199 142.367156)
		(end 199.367156 142)
		(width 0.15)
		(layer "In2.Cu")
		(net 145)
	)
	(segment
		(start 211.7 119.84055)
		(end 211.7 119.5)
		(width 0.148)
		(layer "In2.Cu")
		(net 145)
	)
	(segment
		(start 199.7 142)
		(end 200 141.7)
		(width 0.15)
		(layer "In2.Cu")
		(net 145)
	)
	(segment
		(start 217.3 119.5)
		(end 217.3 119.840549)
		(width 0.148)
		(layer "In2.Cu")
		(net 145)
	)
	(segment
		(start 227 113.5)
		(end 221.4 119.1)
		(width 0.148)
		(layer "In2.Cu")
		(net 145)
	)
	(segment
		(start 198.5 143.499999)
		(end 199 142.999999)
		(width 0.15)
		(layer "In2.Cu")
		(net 145)
	)
	(segment
		(start 196.45 122.775)
		(end 200 126.325)
		(width 0.148)
		(layer "In2.Cu")
		(net 145)
	)
	(segment
		(start 209.3 119.5)
		(end 209.3 119.840551)
		(width 0.148)
		(layer "In2.Cu")
		(net 145)
	)
	(segment
		(start 199 142.999999)
		(end 199 142.367156)
		(width 0.15)
		(layer "In2.Cu")
		(net 145)
	)
	(segment
		(start 218.1 119.840549)
		(end 218.1 119.5)
		(width 0.148)
		(layer "In2.Cu")
		(net 145)
	)
	(segment
		(start 227 111.75)
		(end 227 113.5)
		(width 0.148)
		(layer "In2.Cu")
		(net 145)
	)
	(segment
		(start 206.9 119.840549)
		(end 206.9 119.5)
		(width 0.148)
		(layer "In2.Cu")
		(net 145)
	)
	(segment
		(start 207.7 119.5)
		(end 207.7 119.840549)
		(width 0.148)
		(layer "In2.Cu")
		(net 145)
	)
	(segment
		(start 196.45 120.8)
		(end 196.45 122.775)
		(width 0.148)
		(layer "In2.Cu")
		(net 145)
	)
	(arc
		(start 215.7 119.840549)
		(mid 215.582843 120.123392)
		(end 215.3 120.240549)
		(width 0.148)
		(layer "In2.Cu")
		(net 145)
	)
	(arc
		(start 219.3 119.1)
		(mid 219.017157 119.217157)
		(end 218.9 119.5)
		(width 0.148)
		(layer "In2.Cu")
		(net 145)
	)
	(arc
		(start 211.7 119.5)
		(mid 211.582843 119.217157)
		(end 211.3 119.1)
		(width 0.148)
		(layer "In2.Cu")
		(net 145)
	)
	(arc
		(start 209.7 119.1)
		(mid 209.417157 119.217157)
		(end 209.3 119.5)
		(width 0.148)
		(layer "In2.Cu")
		(net 145)
	)
	(arc
		(start 217.3 119.840549)
		(mid 217.182843 120.123392)
		(end 216.9 120.240549)
		(width 0.148)
		(layer "In2.Cu")
		(net 145)
	)
	(arc
		(start 216.5 119.5)
		(mid 216.382843 119.217157)
		(end 216.1 119.1)
		(width 0.148)
		(layer "In2.Cu")
		(net 145)
	)
	(arc
		(start 206.9 119.5)
		(mid 206.782843 119.217157)
		(end 206.5 119.1)
		(width 0.148)
		(layer "In2.Cu")
		(net 145)
	)
	(arc
		(start 217.7 119.1)
		(mid 217.417157 119.217157)
		(end 217.3 119.5)
		(width 0.148)
		(layer "In2.Cu")
		(net 145)
	)
	(arc
		(start 208.1 119.1)
		(mid 207.817157 119.217157)
		(end 207.7 119.5)
		(width 0.148)
		(layer "In2.Cu")
		(net 145)
	)
	(arc
		(start 210.1 119.5)
		(mid 209.982843 119.217157)
		(end 209.7 119.1)
		(width 0.148)
		(layer "In2.Cu")
		(net 145)
	)
	(arc
		(start 220.5 119.840549)
		(mid 220.382843 120.123392)
		(end 220.1 120.240549)
		(width 0.148)
		(layer "In2.Cu")
		(net 145)
	)
	(arc
		(start 212.5 119.84055)
		(mid 212.382843 120.123393)
		(end 212.1 120.24055)
		(width 0.148)
		(layer "In2.Cu")
		(net 145)
	)
	(arc
		(start 213.7 120.240551)
		(mid 213.417157 120.123394)
		(end 213.3 119.840551)
		(width 0.148)
		(layer "In2.Cu")
		(net 145)
	)
	(arc
		(start 209.3 119.840551)
		(mid 209.182843 120.123394)
		(end 208.9 120.240551)
		(width 0.148)
		(layer "In2.Cu")
		(net 145)
	)
	(arc
		(start 219.7 119.5)
		(mid 219.582843 119.217157)
		(end 219.3 119.1)
		(width 0.148)
		(layer "In2.Cu")
		(net 145)
	)
	(arc
		(start 214.9 119.5)
		(mid 214.782843 119.217157)
		(end 214.5 119.1)
		(width 0.148)
		(layer "In2.Cu")
		(net 145)
	)
	(arc
		(start 208.5 119.5)
		(mid 208.382843 119.217157)
		(end 208.1 119.1)
		(width 0.148)
		(layer "In2.Cu")
		(net 145)
	)
	(arc
		(start 215.3 120.240549)
		(mid 215.017157 120.123392)
		(end 214.9 119.840549)
		(width 0.148)
		(layer "In2.Cu")
		(net 145)
	)
	(arc
		(start 218.5 120.240549)
		(mid 218.217157 120.123392)
		(end 218.1 119.840549)
		(width 0.148)
		(layer "In2.Cu")
		(net 145)
	)
	(arc
		(start 210.9 119.840549)
		(mid 210.782843 120.123392)
		(end 210.5 120.240549)
		(width 0.148)
		(layer "In2.Cu")
		(net 145)
	)
	(arc
		(start 213.3 119.5)
		(mid 213.182843 119.217157)
		(end 212.9 119.1)
		(width 0.148)
		(layer "In2.Cu")
		(net 145)
	)
	(arc
		(start 207.7 119.840549)
		(mid 207.582843 120.123392)
		(end 207.3 120.240549)
		(width 0.148)
		(layer "In2.Cu")
		(net 145)
	)
	(arc
		(start 212.1 120.24055)
		(mid 211.817157 120.123393)
		(end 211.7 119.84055)
		(width 0.148)
		(layer "In2.Cu")
		(net 145)
	)
	(arc
		(start 207.3 120.240549)
		(mid 207.017157 120.123392)
		(end 206.9 119.840549)
		(width 0.148)
		(layer "In2.Cu")
		(net 145)
	)
	(arc
		(start 212.9 119.1)
		(mid 212.617157 119.217157)
		(end 212.5 119.5)
		(width 0.148)
		(layer "In2.Cu")
		(net 145)
	)
	(arc
		(start 211.3 119.1)
		(mid 211.017157 119.217157)
		(end 210.9 119.5)
		(width 0.148)
		(layer "In2.Cu")
		(net 145)
	)
	(arc
		(start 216.1 119.1)
		(mid 215.817157 119.217157)
		(end 215.7 119.5)
		(width 0.148)
		(layer "In2.Cu")
		(net 145)
	)
	(arc
		(start 208.9 120.240551)
		(mid 208.617157 120.123394)
		(end 208.5 119.840551)
		(width 0.148)
		(layer "In2.Cu")
		(net 145)
	)
	(arc
		(start 218.1 119.5)
		(mid 217.982843 119.217157)
		(end 217.7 119.1)
		(width 0.148)
		(layer "In2.Cu")
		(net 145)
	)
	(arc
		(start 214.1 119.840551)
		(mid 213.982843 120.123394)
		(end 213.7 120.240551)
		(width 0.148)
		(layer "In2.Cu")
		(net 145)
	)
	(arc
		(start 210.5 120.240549)
		(mid 210.217157 120.123392)
		(end 210.1 119.840549)
		(width 0.148)
		(layer "In2.Cu")
		(net 145)
	)
	(arc
		(start 220.1 120.240549)
		(mid 219.817157 120.123392)
		(end 219.7 119.840549)
		(width 0.148)
		(layer "In2.Cu")
		(net 145)
	)
	(arc
		(start 220.9 119.1)
		(mid 220.617157 119.217157)
		(end 220.5 119.5)
		(width 0.148)
		(layer "In2.Cu")
		(net 145)
	)
	(arc
		(start 218.9 119.840549)
		(mid 218.782843 120.123392)
		(end 218.5 120.240549)
		(width 0.148)
		(layer "In2.Cu")
		(net 145)
	)
	(arc
		(start 214.5 119.1)
		(mid 214.217157 119.217157)
		(end 214.1 119.5)
		(width 0.148)
		(layer "In2.Cu")
		(net 145)
	)
	(arc
		(start 216.9 120.240549)
		(mid 216.617157 120.123392)
		(end 216.5 119.840549)
		(width 0.148)
		(layer "In2.Cu")
		(net 145)
	)
	(segment
		(start 225.3 110.598)
		(end 225.3 111.75)
		(width 0.38)
		(layer "F.Cu")
		(net 146)
	)
	(segment
		(start 198.0005 142.9995)
		(end 198.5 142.500001)
		(width 0.256)
		(layer "F.Cu")
		(net 146)
	)
	(via
		(at 198.5 142.500001)
		(size 0.45)
		(drill 0.1)
		(layers "F.Cu" "B.Cu")
		(remove_unused_layers yes)
		(keep_end_layers yes)
		(zone_layer_connections)
		(net 146)
	)
	(via
		(at 225.3 111.75)
		(size 0.45)
		(drill 0.1)
		(layers "F.Cu" "B.Cu")
		(remove_unused_layers yes)
		(keep_end_layers yes)
		(zone_layer_connections)
		(net 146)
	)
	(segment
		(start 199.675 118.883983)
		(end 199.675 118.025)
		(width 0.148)
		(layer "In2.Cu")
		(net 146)
	)
	(segment
		(start 195.15 119.65)
		(end 197.1 117.7)
		(width 0.148)
		(layer "In2.Cu")
		(net 146)
	)
	(segment
		(start 197.725 118.025)
		(end 197.725 118.883983)
		(width 0.148)
		(layer "In2.Cu")
		(net 146)
	)
	(segment
		(start 201.625 118.025)
		(end 201.625 118.883983)
		(width 0.148)
		(layer "In2.Cu")
		(net 146)
	)
	(segment
		(start 202.275 118.883983)
		(end 202.275 118.025)
		(width 0.148)
		(layer "In2.Cu")
		(net 146)
	)
	(segment
		(start 204.875 118.883961)
		(end 204.875 118.025)
		(width 0.148)
		(layer "In2.Cu")
		(net 146)
	)
	(segment
		(start 205.2 117.7)
		(end 205.9 117.7)
		(width 0.148)
		(layer "In2.Cu")
		(net 146)
	)
	(segment
		(start 204.225 118.025)
		(end 204.225 118.883961)
		(width 0.148)
		(layer "In2.Cu")
		(net 146)
	)
	(segment
		(start 198.5 142.499999)
		(end 198.5 142.2)
		(width 0.148)
		(layer "In2.Cu")
		(net 146)
	)
	(segment
		(start 197.1 117.7)
		(end 197.4 117.7)
		(width 0.148)
		(layer "In2.Cu")
		(net 146)
	)
	(segment
		(start 195.15 123.2)
		(end 195.15 119.65)
		(width 0.148)
		(layer "In2.Cu")
		(net 146)
	)
	(segment
		(start 199 127.05)
		(end 195.15 123.2)
		(width 0.148)
		(layer "In2.Cu")
		(net 146)
	)
	(segment
		(start 200.325 118.025)
		(end 200.325 118.883961)
		(width 0.148)
		(layer "In2.Cu")
		(net 146)
	)
	(segment
		(start 225.3 113.9)
		(end 225.3 111.75)
		(width 0.148)
		(layer "In2.Cu")
		(net 146)
	)
	(segment
		(start 205.9 117.7)
		(end 221.5 117.7)
		(width 0.148)
		(layer "In2.Cu")
		(net 146)
	)
	(segment
		(start 198.5 142.2)
		(end 199 141.7)
		(width 0.148)
		(layer "In2.Cu")
		(net 146)
	)
	(segment
		(start 202.925 118.025)
		(end 202.925 118.883961)
		(width 0.148)
		(layer "In2.Cu")
		(net 146)
	)
	(segment
		(start 203.575 118.883961)
		(end 203.575 118.025)
		(width 0.148)
		(layer "In2.Cu")
		(net 146)
	)
	(segment
		(start 199 141.7)
		(end 199 127.05)
		(width 0.148)
		(layer "In2.Cu")
		(net 146)
	)
	(segment
		(start 199.025 118.025)
		(end 199.025 118.883983)
		(width 0.148)
		(layer "In2.Cu")
		(net 146)
	)
	(segment
		(start 198.375 118.883983)
		(end 198.375 118.025)
		(width 0.148)
		(layer "In2.Cu")
		(net 146)
	)
	(segment
		(start 200.975 118.883961)
		(end 200.975 118.025)
		(width 0.148)
		(layer "In2.Cu")
		(net 146)
	)
	(segment
		(start 221.5 117.7)
		(end 225.3 113.9)
		(width 0.148)
		(layer "In2.Cu")
		(net 146)
	)
	(arc
		(start 202.275 118.025)
		(mid 202.37019 117.79519)
		(end 202.6 117.7)
		(width 0.148)
		(layer "In2.Cu")
		(net 146)
	)
	(arc
		(start 199.025 118.883983)
		(mid 199.12019 119.113793)
		(end 199.35 119.208983)
		(width 0.148)
		(layer "In2.Cu")
		(net 146)
	)
	(arc
		(start 201.625 118.883983)
		(mid 201.72019 119.113793)
		(end 201.95 119.208983)
		(width 0.148)
		(layer "In2.Cu")
		(net 146)
	)
	(arc
		(start 199.675 118.025)
		(mid 199.77019 117.79519)
		(end 200 117.7)
		(width 0.148)
		(layer "In2.Cu")
		(net 146)
	)
	(arc
		(start 203.9 117.7)
		(mid 204.12981 117.79519)
		(end 204.225 118.025)
		(width 0.148)
		(layer "In2.Cu")
		(net 146)
	)
	(arc
		(start 202.6 117.7)
		(mid 202.82981 117.79519)
		(end 202.925 118.025)
		(width 0.148)
		(layer "In2.Cu")
		(net 146)
	)
	(arc
		(start 203.575 118.025)
		(mid 203.67019 117.79519)
		(end 203.9 117.7)
		(width 0.148)
		(layer "In2.Cu")
		(net 146)
	)
	(arc
		(start 198.7 117.7)
		(mid 198.92981 117.79519)
		(end 199.025 118.025)
		(width 0.148)
		(layer "In2.Cu")
		(net 146)
	)
	(arc
		(start 200.325 118.883961)
		(mid 200.42019 119.113771)
		(end 200.65 119.208961)
		(width 0.148)
		(layer "In2.Cu")
		(net 146)
	)
	(arc
		(start 201.3 117.7)
		(mid 201.52981 117.79519)
		(end 201.625 118.025)
		(width 0.148)
		(layer "In2.Cu")
		(net 146)
	)
	(arc
		(start 201.95 119.208983)
		(mid 202.17981 119.113793)
		(end 202.275 118.883983)
		(width 0.148)
		(layer "In2.Cu")
		(net 146)
	)
	(arc
		(start 197.4 117.7)
		(mid 197.62981 117.79519)
		(end 197.725 118.025)
		(width 0.148)
		(layer "In2.Cu")
		(net 146)
	)
	(arc
		(start 200.65 119.208961)
		(mid 200.87981 119.113771)
		(end 200.975 118.883961)
		(width 0.148)
		(layer "In2.Cu")
		(net 146)
	)
	(arc
		(start 204.875 118.025)
		(mid 204.97019 117.79519)
		(end 205.2 117.7)
		(width 0.148)
		(layer "In2.Cu")
		(net 146)
	)
	(arc
		(start 200 117.7)
		(mid 200.22981 117.79519)
		(end 200.325 118.025)
		(width 0.148)
		(layer "In2.Cu")
		(net 146)
	)
	(arc
		(start 198.05 119.208983)
		(mid 198.27981 119.113793)
		(end 198.375 118.883983)
		(width 0.148)
		(layer "In2.Cu")
		(net 146)
	)
	(arc
		(start 199.35 119.208983)
		(mid 199.57981 119.113793)
		(end 199.675 118.883983)
		(width 0.148)
		(layer "In2.Cu")
		(net 146)
	)
	(arc
		(start 200.975 118.025)
		(mid 201.07019 117.79519)
		(end 201.3 117.7)
		(width 0.148)
		(layer "In2.Cu")
		(net 146)
	)
	(arc
		(start 203.25 119.208961)
		(mid 203.47981 119.113771)
		(end 203.575 118.883961)
		(width 0.148)
		(layer "In2.Cu")
		(net 146)
	)
	(arc
		(start 198.375 118.025)
		(mid 198.47019 117.79519)
		(end 198.7 117.7)
		(width 0.148)
		(layer "In2.Cu")
		(net 146)
	)
	(arc
		(start 197.725 118.883983)
		(mid 197.82019 119.113793)
		(end 198.05 119.208983)
		(width 0.148)
		(layer "In2.Cu")
		(net 146)
	)
	(arc
		(start 204.55 119.208961)
		(mid 204.77981 119.113771)
		(end 204.875 118.883961)
		(width 0.148)
		(layer "In2.Cu")
		(net 146)
	)
	(arc
		(start 202.925 118.883961)
		(mid 203.02019 119.113771)
		(end 203.25 119.208961)
		(width 0.148)
		(layer "In2.Cu")
		(net 146)
	)
	(arc
		(start 204.225 118.883961)
		(mid 204.32019 119.113771)
		(end 204.55 119.208961)
		(width 0.148)
		(layer "In2.Cu")
		(net 146)
	)
	(segment
		(start 181.9995 141.9995)
		(end 181.5 141.5)
		(width 0.256)
		(layer "F.Cu")
		(net 147)
	)
	(segment
		(start 140.3 106)
		(end 140.3 107.152)
		(width 0.38)
		(layer "F.Cu")
		(net 147)
	)
	(via
		(at 140.3 107.152)
		(size 0.45)
		(drill 0.1)
		(layers "F.Cu" "B.Cu")
		(remove_unused_layers yes)
		(keep_end_layers yes)
		(zone_layer_connections)
		(net 147)
	)
	(via
		(at 181.5 141.5)
		(size 0.45)
		(drill 0.1)
		(layers "F.Cu" "B.Cu")
		(remove_unused_layers yes)
		(keep_end_layers yes)
		(zone_layer_connections)
		(net 147)
	)
	(segment
		(start 139.995 107.825294)
		(end 141.22 109.050294)
		(width 0.13)
		(layer "In4.Cu")
		(net 147)
	)
	(segment
		(start 181.5 141.5)
		(end 181.5 141.175)
		(width 0.1)
		(layer "In4.Cu")
		(net 147)
	)
	(segment
		(start 146.264706 119.095)
		(end 155.7 119.095)
		(width 0.13)
		(layer "In4.Cu")
		(net 147)
	)
	(segment
		(start 182.6 138.059033)
		(end 182.62352 138.035513)
		(width 0.1)
		(layer "In4.Cu")
		(net 147)
	)
	(segment
		(start 141.22 110.224706)
		(end 140.72 110.724706)
		(width 0.13)
		(layer "In4.Cu")
		(net 147)
	)
	(segment
		(start 140.3 107.152)
		(end 139.995 107.457)
		(width 0.13)
		(layer "In4.Cu")
		(net 147)
	)
	(segment
		(start 183.1 139.158578)
		(end 182.6 138.658578)
		(width 0.1)
		(layer "In4.Cu")
		(net 147)
	)
	(segment
		(start 181.5 141.175)
		(end 181.55 141.125)
		(width 0.1)
		(layer "In4.Cu")
		(net 147)
	)
	(segment
		(start 140.72 113.550294)
		(end 146.264706 119.095)
		(width 0.13)
		(layer "In4.Cu")
		(net 147)
	)
	(segment
		(start 156.349225 119.744225)
		(end 156.349225 119.859226)
		(width 0.13)
		(layer "In4.Cu")
		(net 147)
	)
	(segment
		(start 140.72 110.724706)
		(end 140.72 113.550294)
		(width 0.13)
		(layer "In4.Cu")
		(net 147)
	)
	(segment
		(start 160.7 119.095)
		(end 171.287636 119.095)
		(width 0.13)
		(layer "In4.Cu")
		(net 147)
	)
	(segment
		(start 156.76845 120.278451)
		(end 158.2 120.278451)
		(width 0.13)
		(layer "In4.Cu")
		(net 147)
	)
	(segment
		(start 182.716422 141.125)
		(end 183.1 140.741422)
		(width 0.1)
		(layer "In4.Cu")
		(net 147)
	)
	(segment
		(start 181.55 141.125)
		(end 182.716422 141.125)
		(width 0.1)
		(layer "In4.Cu")
		(net 147)
	)
	(segment
		(start 182.62352 130.430884)
		(end 182.62352 138.035513)
		(width 0.13)
		(layer "In4.Cu")
		(net 147)
	)
	(segment
		(start 159.23391 119.095)
		(end 160.7 119.095)
		(width 0.13)
		(layer "In4.Cu")
		(net 147)
	)
	(segment
		(start 141.22 109.050294)
		(end 141.22 110.224706)
		(width 0.13)
		(layer "In4.Cu")
		(net 147)
	)
	(segment
		(start 139.995 107.457)
		(end 139.995 107.825294)
		(width 0.13)
		(layer "In4.Cu")
		(net 147)
	)
	(segment
		(start 171.287636 119.095)
		(end 182.62352 130.430884)
		(width 0.13)
		(layer "In4.Cu")
		(net 147)
	)
	(segment
		(start 182.6 138.658578)
		(end 182.6 138.059033)
		(width 0.1)
		(layer "In4.Cu")
		(net 147)
	)
	(segment
		(start 158.619225 119.859226)
		(end 158.619225 119.709685)
		(width 0.13)
		(layer "In4.Cu")
		(net 147)
	)
	(segment
		(start 183.1 140.741422)
		(end 183.1 139.158578)
		(width 0.1)
		(layer "In4.Cu")
		(net 147)
	)
	(arc
		(start 158.2 120.278451)
		(mid 158.496437 120.155663)
		(end 158.619225 119.859226)
		(width 0.13)
		(layer "In4.Cu")
		(net 147)
	)
	(arc
		(start 156.349225 119.859226)
		(mid 156.472013 120.155663)
		(end 156.76845 120.278451)
		(width 0.13)
		(layer "In4.Cu")
		(net 147)
	)
	(arc
		(start 155.7 119.095)
		(mid 156.159071 119.285154)
		(end 156.349225 119.744225)
		(width 0.13)
		(layer "In4.Cu")
		(net 147)
	)
	(arc
		(start 158.619225 119.709685)
		(mid 158.799262 119.275037)
		(end 159.23391 119.095)
		(width 0.13)
		(layer "In4.Cu")
		(net 147)
	)
	(segment
		(start 139.45 106)
		(end 139.45 107.152)
		(width 0.38)
		(layer "F.Cu")
		(net 148)
	)
	(segment
		(start 181.9995 140.9995)
		(end 181.5 140.5)
		(width 0.256)
		(layer "F.Cu")
		(net 148)
	)
	(via
		(at 181.5 140.5)
		(size 0.45)
		(drill 0.1)
		(layers "F.Cu" "B.Cu")
		(remove_unused_layers yes)
		(keep_end_layers yes)
		(zone_layer_connections)
		(net 148)
	)
	(via
		(at 139.45 107.152)
		(size 0.45)
		(drill 0.1)
		(layers "F.Cu" "B.Cu")
		(remove_unused_layers yes)
		(keep_end_layers yes)
		(zone_layer_connections)
		(net 148)
	)
	(segment
		(start 182.4 138.051993)
		(end 182.4 138.741422)
		(width 0.1)
		(layer "In4.Cu")
		(net 148)
	)
	(segment
		(start 140.48 113.649706)
		(end 146.155294 119.325)
		(width 0.13)
		(layer "In4.Cu")
		(net 148)
	)
	(segment
		(start 146.155294 119.325)
		(end 155.7 119.325)
		(width 0.13)
		(layer "In4.Cu")
		(net 148)
	)
	(segment
		(start 139.755 107.924706)
		(end 140.98 109.149706)
		(width 0.13)
		(layer "In4.Cu")
		(net 148)
	)
	(segment
		(start 140.98 109.149706)
		(end 140.98 110.125294)
		(width 0.13)
		(layer "In4.Cu")
		(net 148)
	)
	(segment
		(start 181.775952 140.925)
		(end 181.575 140.925)
		(width 0.1)
		(layer "In4.Cu")
		(net 148)
	)
	(segment
		(start 182.9 140.658578)
		(end 182.633578 140.925)
		(width 0.1)
		(layer "In4.Cu")
		(net 148)
	)
	(segment
		(start 156.76845 120.508451)
		(end 158.2 120.508451)
		(width 0.13)
		(layer "In4.Cu")
		(net 148)
	)
	(segment
		(start 139.755 107.457)
		(end 139.755 107.924706)
		(width 0.13)
		(layer "In4.Cu")
		(net 148)
	)
	(segment
		(start 182.38352 138.035513)
		(end 182.4 138.051993)
		(width 0.1)
		(layer "In4.Cu")
		(net 148)
	)
	(segment
		(start 140.48 110.625294)
		(end 140.48 113.649706)
		(width 0.13)
		(layer "In4.Cu")
		(net 148)
	)
	(segment
		(start 139.45 107.152)
		(end 139.755 107.457)
		(width 0.13)
		(layer "In4.Cu")
		(net 148)
	)
	(segment
		(start 156.119225 119.744225)
		(end 156.119225 119.859226)
		(width 0.13)
		(layer "In4.Cu")
		(net 148)
	)
	(segment
		(start 182.38352 130.516156)
		(end 182.38352 138.035513)
		(width 0.13)
		(layer "In4.Cu")
		(net 148)
	)
	(segment
		(start 181.5 140.85)
		(end 181.5 140.5)
		(width 0.1)
		(layer "In4.Cu")
		(net 148)
	)
	(segment
		(start 182.025952 140.625475)
		(end 182.025 140.625475)
		(width 0.1)
		(layer "In4.Cu")
		(net 148)
	)
	(segment
		(start 181.900476 140.749999)
		(end 181.900476 140.800476)
		(width 0.1)
		(layer "In4.Cu")
		(net 148)
	)
	(segment
		(start 160.7 119.325)
		(end 171.192364 119.325)
		(width 0.13)
		(layer "In4.Cu")
		(net 148)
	)
	(segment
		(start 182.150476 140.800476)
		(end 182.150476 140.749999)
		(width 0.1)
		(layer "In4.Cu")
		(net 148)
	)
	(segment
		(start 158.849225 119.859226)
		(end 158.849225 119.744225)
		(width 0.13)
		(layer "In4.Cu")
		(net 148)
	)
	(segment
		(start 171.192364 119.325)
		(end 182.38352 130.516156)
		(width 0.13)
		(layer "In4.Cu")
		(net 148)
	)
	(segment
		(start 181.575 140.925)
		(end 181.5 140.85)
		(width 0.1)
		(layer "In4.Cu")
		(net 148)
	)
	(segment
		(start 182.4 138.741422)
		(end 182.9 139.241422)
		(width 0.1)
		(layer "In4.Cu")
		(net 148)
	)
	(segment
		(start 159.26845 119.325)
		(end 160.7 119.325)
		(width 0.13)
		(layer "In4.Cu")
		(net 148)
	)
	(segment
		(start 182.633578 140.925)
		(end 182.275 140.925)
		(width 0.1)
		(layer "In4.Cu")
		(net 148)
	)
	(segment
		(start 182.9 139.241422)
		(end 182.9 140.658578)
		(width 0.1)
		(layer "In4.Cu")
		(net 148)
	)
	(segment
		(start 140.98 110.125294)
		(end 140.48 110.625294)
		(width 0.13)
		(layer "In4.Cu")
		(net 148)
	)
	(arc
		(start 181.900476 140.800476)
		(mid 181.864004 140.888528)
		(end 181.775952 140.925)
		(width 0.1)
		(layer "In4.Cu")
		(net 148)
	)
	(arc
		(start 156.119225 119.859226)
		(mid 156.309379 120.318297)
		(end 156.76845 120.508451)
		(width 0.13)
		(layer "In4.Cu")
		(net 148)
	)
	(arc
		(start 158.2 120.508451)
		(mid 158.659071 120.318297)
		(end 158.849225 119.859226)
		(width 0.13)
		(layer "In4.Cu")
		(net 148)
	)
	(arc
		(start 182.150476 140.749999)
		(mid 182.114004 140.661947)
		(end 182.025952 140.625475)
		(width 0.1)
		(layer "In4.Cu")
		(net 148)
	)
	(arc
		(start 182.275 140.925)
		(mid 182.186948 140.888528)
		(end 182.150476 140.800476)
		(width 0.1)
		(layer "In4.Cu")
		(net 148)
	)
	(arc
		(start 182.025 140.625475)
		(mid 181.936948 140.661947)
		(end 181.900476 140.749999)
		(width 0.1)
		(layer "In4.Cu")
		(net 148)
	)
	(arc
		(start 158.849225 119.744225)
		(mid 158.972013 119.447788)
		(end 159.26845 119.325)
		(width 0.13)
		(layer "In4.Cu")
		(net 148)
	)
	(arc
		(start 155.7 119.325)
		(mid 155.996437 119.447788)
		(end 156.119225 119.744225)
		(width 0.13)
		(layer "In4.Cu")
		(net 148)
	)
	(segment
		(start 221.05 110.598)
		(end 221.05 111.75)
		(width 0.38)
		(layer "F.Cu")
		(net 149)
	)
	(segment
		(start 197.000499 144.9995)
		(end 197.5 144.5)
		(width 0.256)
		(layer "F.Cu")
		(net 149)
	)
	(via
		(at 197.5 144.5)
		(size 0.45)
		(drill 0.1)
		(layers "F.Cu" "B.Cu")
		(remove_unused_layers yes)
		(keep_end_layers yes)
		(zone_layer_connections)
		(net 149)
	)
	(via
		(at 221.05 111.75)
		(size 0.45)
		(drill 0.1)
		(layers "F.Cu" "B.Cu")
		(remove_unused_layers yes)
		(keep_end_layers yes)
		(zone_layer_connections)
		(net 149)
	)
	(segment
		(start 189.45 123.7495)
		(end 195.9005 130.2)
		(width 0.15)
		(layer "In2.Cu")
		(net 149)
	)
	(segment
		(start 195.9005 130.2)
		(end 195.9005 143.466184)
		(width 0.15)
		(layer "In2.Cu")
		(net 149)
	)
	(segment
		(start 189.15 118.8)
		(end 188.599823 118.8)
		(width 0.15)
		(layer "In2.Cu")
		(net 149)
	)
	(segment
		(start 196.534315 144.099999)
		(end 197.1 144.099999)
		(width 0.15)
		(layer "In2.Cu")
		(net 149)
	)
	(segment
		(start 189.15 117.6)
		(end 188.599823 117.6)
		(width 0.15)
		(layer "In2.Cu")
		(net 149)
	)
	(segment
		(start 189.15 120)
		(end 188.599806 120)
		(width 0.15)
		(layer "In2.Cu")
		(net 149)
	)
	(segment
		(start 189.15 122.4)
		(end 188.599823 122.4)
		(width 0.15)
		(layer "In2.Cu")
		(net 149)
	)
	(segment
		(start 188.599823 118.2)
		(end 189.15 118.2)
		(width 0.15)
		(layer "In2.Cu")
		(net 149)
	)
	(segment
		(start 189.45 123.3)
		(end 189.45 123.7495)
		(width 0.15)
		(layer "In2.Cu")
		(net 149)
	)
	(segment
		(start 189.45 117.25)
		(end 189.45 117.3)
		(width 0.15)
		(layer "In2.Cu")
		(net 149)
	)
	(segment
		(start 220 114.05)
		(end 192.65 114.05)
		(width 0.15)
		(layer "In2.Cu")
		(net 149)
	)
	(segment
		(start 188.599823 123)
		(end 189.15 123)
		(width 0.15)
		(layer "In2.Cu")
		(net 149)
	)
	(segment
		(start 221.0505 112.9995)
		(end 220 114.05)
		(width 0.15)
		(layer "In2.Cu")
		(net 149)
	)
	(segment
		(start 221.0505 111.749499)
		(end 221.0505 112.9995)
		(width 0.15)
		(layer "In2.Cu")
		(net 149)
	)
	(segment
		(start 189.15 121.2)
		(end 188.599806 121.2)
		(width 0.15)
		(layer "In2.Cu")
		(net 149)
	)
	(segment
		(start 188.599823 119.4)
		(end 189.15 119.4)
		(width 0.15)
		(layer "In2.Cu")
		(net 149)
	)
	(segment
		(start 192.65 114.05)
		(end 189.45 117.25)
		(width 0.15)
		(layer "In2.Cu")
		(net 149)
	)
	(segment
		(start 188.599806 121.8)
		(end 189.15 121.8)
		(width 0.15)
		(layer "In2.Cu")
		(net 149)
	)
	(segment
		(start 197.1 144.099999)
		(end 197.5 144.499999)
		(width 0.15)
		(layer "In2.Cu")
		(net 149)
	)
	(segment
		(start 195.9005 143.466184)
		(end 196.534315 144.099999)
		(width 0.15)
		(layer "In2.Cu")
		(net 149)
	)
	(segment
		(start 188.599806 120.6)
		(end 189.15 120.6)
		(width 0.15)
		(layer "In2.Cu")
		(net 149)
	)
	(arc
		(start 189.15 123)
		(mid 189.362132 123.087868)
		(end 189.45 123.3)
		(width 0.15)
		(layer "In2.Cu")
		(net 149)
	)
	(arc
		(start 189.15 119.4)
		(mid 189.362132 119.487868)
		(end 189.45 119.7)
		(width 0.15)
		(layer "In2.Cu")
		(net 149)
	)
	(arc
		(start 188.299806 120.3)
		(mid 188.387674 120.512132)
		(end 188.599806 120.6)
		(width 0.15)
		(layer "In2.Cu")
		(net 149)
	)
	(arc
		(start 189.45 117.3)
		(mid 189.362132 117.512132)
		(end 189.15 117.6)
		(width 0.15)
		(layer "In2.Cu")
		(net 149)
	)
	(arc
		(start 188.599806 121.2)
		(mid 188.387674 121.287868)
		(end 188.299806 121.5)
		(width 0.15)
		(layer "In2.Cu")
		(net 149)
	)
	(arc
		(start 189.15 121.8)
		(mid 189.362132 121.887868)
		(end 189.45 122.1)
		(width 0.15)
		(layer "In2.Cu")
		(net 149)
	)
	(arc
		(start 189.15 120.6)
		(mid 189.362132 120.687868)
		(end 189.45 120.9)
		(width 0.15)
		(layer "In2.Cu")
		(net 149)
	)
	(arc
		(start 189.45 120.9)
		(mid 189.362132 121.112132)
		(end 189.15 121.2)
		(width 0.15)
		(layer "In2.Cu")
		(net 149)
	)
	(arc
		(start 188.599806 120)
		(mid 188.387674 120.087868)
		(end 188.299806 120.3)
		(width 0.15)
		(layer "In2.Cu")
		(net 149)
	)
	(arc
		(start 188.299823 122.7)
		(mid 188.387691 122.912132)
		(end 188.599823 123)
		(width 0.15)
		(layer "In2.Cu")
		(net 149)
	)
	(arc
		(start 188.599823 117.6)
		(mid 188.387691 117.687868)
		(end 188.299823 117.9)
		(width 0.15)
		(layer "In2.Cu")
		(net 149)
	)
	(arc
		(start 188.299823 117.9)
		(mid 188.387691 118.112132)
		(end 188.599823 118.2)
		(width 0.15)
		(layer "In2.Cu")
		(net 149)
	)
	(arc
		(start 188.599823 118.8)
		(mid 188.387691 118.887868)
		(end 188.299823 119.1)
		(width 0.15)
		(layer "In2.Cu")
		(net 149)
	)
	(arc
		(start 188.299823 119.1)
		(mid 188.387691 119.312132)
		(end 188.599823 119.4)
		(width 0.15)
		(layer "In2.Cu")
		(net 149)
	)
	(arc
		(start 189.15 118.2)
		(mid 189.362132 118.287868)
		(end 189.45 118.5)
		(width 0.15)
		(layer "In2.Cu")
		(net 149)
	)
	(arc
		(start 188.299806 121.5)
		(mid 188.387674 121.712132)
		(end 188.599806 121.8)
		(width 0.15)
		(layer "In2.Cu")
		(net 149)
	)
	(arc
		(start 189.45 122.1)
		(mid 189.362132 122.312132)
		(end 189.15 122.4)
		(width 0.15)
		(layer "In2.Cu")
		(net 149)
	)
	(arc
		(start 189.45 118.5)
		(mid 189.362132 118.712132)
		(end 189.15 118.8)
		(width 0.15)
		(layer "In2.Cu")
		(net 149)
	)
	(arc
		(start 188.599823 122.4)
		(mid 188.387691 122.487868)
		(end 188.299823 122.7)
		(width 0.15)
		(layer "In2.Cu")
		(net 149)
	)
	(arc
		(start 189.45 119.7)
		(mid 189.362132 119.912132)
		(end 189.15 120)
		(width 0.15)
		(layer "In2.Cu")
		(net 149)
	)
	(segment
		(start 134.425 146.662149)
		(end 134.425 147.562149)
		(width 0.256)
		(layer "F.Cu")
		(net 150)
	)
	(segment
		(start 233.05 156.3)
		(end 233.05 139.55)
		(width 2)
		(layer "F.Cu")
		(net 150)
	)
	(segment
		(start 255.625499 162.424)
		(end 256.446998 162.424)
		(width 0.1)
		(layer "F.Cu")
		(net 150)
	)
	(segment
		(start 233.05 139.55)
		(end 218.4 124.9)
		(width 2)
		(layer "F.Cu")
		(net 150)
	)
	(segment
		(start 131.239179 140.995008)
		(end 130.655499 140.995008)
		(width 0.2)
		(layer "F.Cu")
		(net 150)
	)
	(segment
		(start 243 162.4)
		(end 241.81 161.21)
		(width 2)
		(layer "F.Cu")
		(net 150)
	)
	(segment
		(start 130.249008 145.546)
		(end 130.3 145.495008)
		(width 0.177)
		(layer "F.Cu")
		(net 150)
	)
	(segment
		(start 244.088 162.4)
		(end 243 162.4)
		(width 2)
		(layer "F.Cu")
		(net 150)
	)
	(segment
		(start 138.175 144.984)
		(end 139.196 144.984)
		(width 0.256)
		(layer "F.Cu")
		(net 150)
	)
	(segment
		(start 131.164992 145.495008)
		(end 131.176 145.484)
		(width 0.177)
		(layer "F.Cu")
		(net 150)
	)
	(segment
		(start 139.196 144.984)
		(end 139.21 144.97)
		(width 0.256)
		(layer "F.Cu")
		(net 150)
	)
	(segment
		(start 132.4035 147.649)
		(end 132.416328 147.636172)
		(width 0.15)
		(layer "F.Cu")
		(net 150)
	)
	(segment
		(start 218.4 124.9)
		(end 182.55 124.9)
		(width 2)
		(layer "F.Cu")
		(net 150)
	)
	(segment
		(start 129.705634 140.692165)
		(end 129.616328 140.602859)
		(width 0.2)
		(layer "F.Cu")
		(net 150)
	)
	(segment
		(start 130.617186 142.985)
		(end 131.176 142.985)
		(width 0.256)
		(layer "F.Cu")
		(net 150)
	)
	(segment
		(start 130.3 145.495008)
		(end 131.164992 145.495008)
		(width 0.177)
		(layer "F.Cu")
		(net 150)
	)
	(segment
		(start 182.55 124.9)
		(end 170.95 136.5)
		(width 2)
		(layer "F.Cu")
		(net 150)
	)
	(segment
		(start 121.275 169.65)
		(end 120.975 169.95)
		(width 0.4)
		(layer "F.Cu")
		(net 150)
	)
	(segment
		(start 132.416328 147.636172)
		(end 132.416328 146.672157)
		(width 0.256)
		(layer "F.Cu")
		(net 150)
	)
	(segment
		(start 147.68 143.46)
		(end 147.68 143.17)
		(width 0.4)
		(layer "F.Cu")
		(net 150)
	)
	(segment
		(start 130.655499 140.995008)
		(end 130.352656 140.692165)
		(width 0.2)
		(layer "F.Cu")
		(net 150)
	)
	(segment
		(start 120.625 169.675)
		(end 121.25 169.675)
		(width 0.4)
		(layer "F.Cu")
		(net 150)
	)
	(segment
		(start 146.516 144.624)
		(end 147.68 143.46)
		(width 0.4)
		(layer "F.Cu")
		(net 150)
	)
	(segment
		(start 154.2 136.5)
		(end 147.68 143.02)
		(width 2)
		(layer "F.Cu")
		(net 150)
	)
	(segment
		(start 130.575356 142.94317)
		(end 130.617186 142.985)
		(width 0.256)
		(layer "F.Cu")
		(net 150)
	)
	(segment
		(start 120.975 170.025)
		(end 120.625 169.675)
		(width 0.4)
		(layer "F.Cu")
		(net 150)
	)
	(segment
		(start 121.25 169.675)
		(end 121.275 169.65)
		(width 0.4)
		(layer "F.Cu")
		(net 150)
	)
	(segment
		(start 237.96 161.21)
		(end 233.05 156.3)
		(width 2)
		(layer "F.Cu")
		(net 150)
	)
	(segment
		(start 170.95 136.5)
		(end 154.2 136.5)
		(width 2)
		(layer "F.Cu")
		(net 150)
	)
	(segment
		(start 146.516 144.672149)
		(end 146.516 144.624)
		(width 0.4)
		(layer "F.Cu")
		(net 150)
	)
	(segment
		(start 120.975 169.95)
		(end 120.975 170.025)
		(width 0.4)
		(layer "F.Cu")
		(net 150)
	)
	(segment
		(start 120.975 170.295)
		(end 120.975 170.025)
		(width 0.4)
		(layer "F.Cu")
		(net 150)
	)
	(segment
		(start 129.625 145.546)
		(end 130.249008 145.546)
		(width 0.177)
		(layer "F.Cu")
		(net 150)
	)
	(segment
		(start 147.68 143.02)
		(end 147.68 143.17)
		(width 2)
		(layer "F.Cu")
		(net 150)
	)
	(segment
		(start 256.446998 162.424)
		(end 256.447 162.423998)
		(width 0.1)
		(layer "F.Cu")
		(net 150)
	)
	(segment
		(start 130.352656 140.692165)
		(end 129.705634 140.692165)
		(width 0.2)
		(layer "F.Cu")
		(net 150)
	)
	(segment
		(start 241.81 161.21)
		(end 237.96 161.21)
		(width 2)
		(layer "F.Cu")
		(net 150)
	)
	(via
		(at 134.424499 147.649)
		(size 0.45)
		(drill 0.1)
		(layers "F.Cu" "B.Cu")
		(remove_unused_layers yes)
		(keep_end_layers yes)
		(zone_layer_connections "In4.Cu")
		(net 150)
	)
	(via
		(at 132.4035 147.649)
		(size 0.45)
		(drill 0.1)
		(layers "F.Cu" "B.Cu")
		(remove_unused_layers yes)
		(keep_end_layers yes)
		(zone_layer_connections "In4.Cu")
		(net 150)
	)
	(via
		(at 139.21 144.97)
		(size 0.45)
		(drill 0.1)
		(layers "F.Cu" "B.Cu")
		(remove_unused_layers yes)
		(keep_end_layers yes)
		(zone_layer_connections "In4.Cu")
		(net 150)
	)
	(via
		(at 146.85 143.5)
		(size 0.45)
		(drill 0.1)
		(layers "F.Cu" "B.Cu")
		(remove_unused_layers yes)
		(keep_end_layers yes)
		(zone_layer_connections "In4.Cu")
		(net 150)
	)
	(via
		(at 147.4 143.15)
		(size 0.45)
		(drill 0.1)
		(layers "F.Cu" "B.Cu")
		(remove_unused_layers yes)
		(keep_end_layers yes)
		(zone_layer_connections "In4.Cu")
		(net 150)
	)
	(via
		(at 147.4 142.6)
		(size 0.45)
		(drill 0.1)
		(layers "F.Cu" "B.Cu")
		(remove_unused_layers yes)
		(keep_end_layers yes)
		(zone_layer_connections "In4.Cu")
		(net 150)
	)
	(via
		(at 146.85 142.9)
		(size 0.45)
		(drill 0.1)
		(layers "F.Cu" "B.Cu")
		(remove_unused_layers yes)
		(keep_end_layers yes)
		(zone_layer_connections "In4.Cu")
		(net 150)
	)
	(via
		(at 121.275 169.65)
		(size 0.45)
		(drill 0.1)
		(layers "F.Cu" "B.Cu")
		(net 150)
	)
	(via
		(at 130.575356 142.94317)
		(size 0.45)
		(drill 0.1)
		(layers "F.Cu" "B.Cu")
		(remove_unused_layers yes)
		(keep_end_layers yes)
		(zone_layer_connections "In4.Cu")
		(net 150)
	)
	(via
		(at 130.3 145.495008)
		(size 0.45)
		(drill 0.1)
		(layers "F.Cu" "B.Cu")
		(remove_unused_layers yes)
		(keep_end_layers yes)
		(zone_layer_connections "In4.Cu")
		(net 150)
	)
	(via
		(at 147.85 142.15)
		(size 0.45)
		(drill 0.1)
		(layers "F.Cu" "B.Cu")
		(remove_unused_layers yes)
		(keep_end_layers yes)
		(zone_layer_connections "In4.Cu")
		(net 150)
	)
	(via
		(at 120.625 169.675)
		(size 0.45)
		(drill 0.1)
		(layers "F.Cu" "B.Cu")
		(net 150)
	)
	(via
		(at 132.32 141.35)
		(size 0.45)
		(drill 0.1)
		(layers "F.Cu" "B.Cu")
		(remove_unused_layers yes)
		(keep_end_layers yes)
		(zone_layer_connections "In4.Cu")
		(net 150)
	)
	(via
		(at 130.35 140.7)
		(size 0.45)
		(drill 0.1)
		(layers "F.Cu" "B.Cu")
		(remove_unused_layers yes)
		(keep_end_layers yes)
		(zone_layer_connections "In4.Cu")
		(net 150)
	)
	(segment
		(start 131.233171 146.937992)
		(end 132.274499 146.937992)
		(width 0.4)
		(layer "B.Cu")
		(net 150)
	)
	(segment
		(start 132.424499 147.628001)
		(end 132.4035 147.649)
		(width 0.256)
		(layer "B.Cu")
		(net 150)
	)
	(segment
		(start 134.433171 146.937992)
		(end 134.433171 147.640328)
		(width 0.256)
		(layer "B.Cu")
		(net 150)
	)
	(segment
		(start 133.433171 146.937992)
		(end 134.433171 146.937992)
		(width 0.4)
		(layer "B.Cu")
		(net 150)
	)
	(segment
		(start 134.433171 147.640328)
		(end 134.424499 147.649)
		(width 0.256)
		(layer "B.Cu")
		(net 150)
	)
	(segment
		(start 133.511328 141.007157)
		(end 132.662843 141.007157)
		(width 0.4)
		(layer "B.Cu")
		(net 150)
	)
	(segment
		(start 138.740499 146.6)
		(end 138.740499 145.6)
		(width 0.256)
		(layer "B.Cu")
		(net 150)
	)
	(segment
		(start 130.575356 142.94317)
		(end 130.85083 142.94317)
		(width 0.256)
		(layer "B.Cu")
		(net 150)
	)
	(segment
		(start 130.85083 142.94317)
		(end 131.36 142.434)
		(width 0.256)
		(layer "B.Cu")
		(net 150)
	)
	(segment
		(start 138.740499 145.6)
		(end 138.740499 145.439501)
		(width 0.256)
		(layer "B.Cu")
		(net 150)
	)
	(segment
		(start 138.740499 145.439501)
		(end 139.21 144.97)
		(width 0.256)
		(layer "B.Cu")
		(net 150)
	)
	(segment
		(start 132.662843 141.007157)
		(end 132.32 141.35)
		(width 0.4)
		(layer "B.Cu")
		(net 150)
	)
	(segment
		(start 132.424499 147.087992)
		(end 132.424499 147.628001)
		(width 0.256)
		(layer "B.Cu")
		(net 150)
	)
	(segment
		(start 132.274499 146.937992)
		(end 132.424499 147.087992)
		(width 0.256)
		(layer "B.Cu")
		(net 150)
	)
	(segment
		(start 155.835 159.799999)
		(end 155.67 159.634999)
		(width 0.256)
		(layer "F.Cu")
		(net 151)
	)
	(segment
		(start 128.956 176.502)
		(end 128.306 176.502)
		(width 0.256)
		(layer "F.Cu")
		(net 151)
	)
	(segment
		(start 124.1995 161.9505)
		(end 124.25 161.9)
		(width 0.1)
		(layer "F.Cu")
		(net 151)
	)
	(segment
		(start 207.09 153.44)
		(end 206.49 153.44)
		(width 0.182)
		(layer "F.Cu")
		(net 151)
	)
	(segment
		(start 161.09 156.719999)
		(end 161.81 156.719999)
		(width 0.256)
		(layer "F.Cu")
		(net 151)
	)
	(segment
		(start 168.35 157.73)
		(end 168.145 157.525)
		(width 0.256)
		(layer "F.Cu")
		(net 151)
	)
	(segment
		(start 112.78 103.6)
		(end 113.404 102.976)
		(width 0.1)
		(layer "F.Cu")
		(net 151)
	)
	(segment
		(start 110.1 103.55)
		(end 110.13 103.55)
		(width 0.1)
		(layer "F.Cu")
		(net 151)
	)
	(segment
		(start 155.02 159.634999)
		(end 155.67 159.634999)
		(width 0.256)
		(layer "F.Cu")
		(net 151)
	)
	(segment
		(start 110.13 103.55)
		(end 110.705 102.975)
		(width 0.1)
		(layer "F.Cu")
		(net 151)
	)
	(segment
		(start 104.16 113.96)
		(end 104.365 113.755)
		(width 0.15)
		(layer "F.Cu")
		(net 151)
	)
	(segment
		(start 257.79 141.965)
		(end 257.79 142.7)
		(width 0.256)
		(layer "F.Cu")
		(net 151)
	)
	(segment
		(start 104.16 114.68)
		(end 104.16 113.96)
		(width 0.15)
		(layer "F.Cu")
		(net 151)
	)
	(segment
		(start 148.364499 163.458)
		(end 148.555499 163.458)
		(width 0.15)
		(layer "F.Cu")
		(net 151)
	)
	(segment
		(start 242.972 132.808)
		(end 242.98 132.8)
		(width 0.256)
		(layer "F.Cu")
		(net 151)
	)
	(segment
		(start 160.62 157.199999)
		(end 160.58 157.199999)
		(width 0.256)
		(layer "F.Cu")
		(net 151)
	)
	(segment
		(start 195.0005 151.9995)
		(end 195.5 151.5)
		(width 0.256)
		(layer "F.Cu")
		(net 151)
	)
	(segment
		(start 251.173002 183.549)
		(end 251.15 183.525998)
		(width 0.182)
		(layer "F.Cu")
		(net 151)
	)
	(segment
		(start 121.0265 165.6325)
		(end 127.681 165.6325)
		(width 0.201)
		(layer "F.Cu")
		(net 151)
	)
	(segment
		(start 128.306 176.502)
		(end 127.306 176.502)
		(width 0.256)
		(layer "F.Cu")
		(net 151)
	)
	(segment
		(start 104.65 103.6)
		(end 104.68 103.6)
		(width 0.15)
		(layer "F.Cu")
		(net 151)
	)
	(segment
		(start 104.365 113.755)
		(end 105.485 113.755)
		(width 0.15)
		(layer "F.Cu")
		(net 151)
	)
	(segment
		(start 132.206 170.552)
		(end 132.766 170.552)
		(width 0.201)
		(layer "F.Cu")
		(net 151)
	)
	(segment
		(start 168.35 158.45)
		(end 168.35 157.73)
		(width 0.256)
		(layer "F.Cu")
		(net 151)
	)
	(segment
		(start 159.81 157.969999)
		(end 160.1 157.679999)
		(width 0.256)
		(layer "F.Cu")
		(net 151)
	)
	(segment
		(start 251.92 183.549)
		(end 251.92 182.588)
		(width 0.182)
		(layer "F.Cu")
		(net 151)
	)
	(segment
		(start 132.206 170.552)
		(end 132.206 171.614)
		(width 0.201)
		(layer "F.Cu")
		(net 151)
	)
	(segment
		(start 113.178 159.8)
		(end 113.164 159.814)
		(width 0.256)
		(layer "F.Cu")
		(net 151)
	)
	(segment
		(start 251.45 184.699)
		(end 251.15 184.399)
		(width 0.182)
		(layer "F.Cu")
		(net 151)
	)
	(segment
		(start 207.29 153.24)
		(end 207.09 153.44)
		(width 0.182)
		(layer "F.Cu")
		(net 151)
	)
	(segment
		(start 182.9995 156.0005)
		(end 182.5 156.5)
		(width 0.256)
		(layer "F.Cu")
		(net 151)
	)
	(segment
		(start 123.65 161.9)
		(end 123.6995 161.9495)
		(width 0.1)
		(layer "F.Cu")
		(net 151)
	)
	(segment
		(start 162.625 161.799999)
		(end 164.775 161.799999)
		(width 0.256)
		(layer "F.Cu")
		(net 151)
	)
	(segment
		(start 106.385 113.755)
		(end 106.635 114.005)
		(width 0.182)
		(layer "F.Cu")
		(net 151)
	)
	(segment
		(start 198.5 150.5)
		(end 198.0005 150.9995)
		(width 0.256)
		(layer "F.Cu")
		(net 151)
	)
	(segment
		(start 179.9995 157.0005)
		(end 179.499999 157.5)
		(width 0.256)
		(layer "F.Cu")
		(net 151)
	)
	(segment
		(start 106.635 114.725)
		(end 106.635 114.005)
		(width 0.15)
		(layer "F.Cu")
		(net 151)
	)
	(segment
		(start 121.21 145.61)
		(end 120.58 145.61)
		(width 0.1)
		(layer "F.Cu")
		(net 151)
	)
	(segment
		(start 148.794499 163.219)
		(end 148.794499 163.079)
		(width 0.15)
		(layer "F.Cu")
		(net 151)
	)
	(segment
		(start 241.425499 132.808)
		(end 242.972 132.808)
		(width 0.256)
		(layer "F.Cu")
		(net 151)
	)
	(segment
		(start 251.15 183.549)
		(end 251.92 183.549)
		(width 0.182)
		(layer "F.Cu")
		(net 151)
	)
	(segment
		(start 121.026 165.632)
		(end 121.0265 165.6325)
		(width 0.201)
		(layer "F.Cu")
		(net 151)
	)
	(segment
		(start 127.076 176.732)
		(end 127.306 176.502)
		(width 0.201)
		(layer "F.Cu")
		(net 151)
	)
	(segment
		(start 253.226 144.551)
		(end 252.551 144.551)
		(width 0.256)
		(layer "F.Cu")
		(net 151)
	)
	(segment
		(start 159.81 158.984999)
		(end 159.81 157.969999)
		(width 0.256)
		(layer "F.Cu")
		(net 151)
	)
	(segment
		(start 156.995 159.799999)
		(end 155.835 159.799999)
		(width 0.256)
		(layer "F.Cu")
		(net 151)
	)
	(segment
		(start 251.92 182.588)
		(end 251.95 182.558)
		(width 0.182)
		(layer "F.Cu")
		(net 151)
	)
	(segment
		(start 108.973499 113.976501)
		(end 108.975 113.975)
		(width 0.182)
		(layer "F.Cu")
		(net 151)
	)
	(segment
		(start 165.58 161.634999)
		(end 164.94 161.634999)
		(width 0.256)
		(layer "F.Cu")
		(net 151)
	)
	(segment
		(start 251.15 184.399)
		(end 251.15 183.549)
		(width 0.182)
		(layer "F.Cu")
		(net 151)
	)
	(segment
		(start 104.095 114.745)
		(end 104.16 114.68)
		(width 0.15)
		(layer "F.Cu")
		(net 151)
	)
	(segment
		(start 108.973499 113.998)
		(end 108.973499 113.976501)
		(width 0.182)
		(layer "F.Cu")
		(net 151)
	)
	(segment
		(start 148.555499 159.758)
		(end 149.313499 159)
		(width 0.15)
		(layer "F.Cu")
		(net 151)
	)
	(segment
		(start 160.62 157.199999)
		(end 160.62 157.189999)
		(width 0.256)
		(layer "F.Cu")
		(net 151)
	)
	(segment
		(start 148.555499 163.458)
		(end 148.794499 163.219)
		(width 0.15)
		(layer "F.Cu")
		(net 151)
	)
	(segment
		(start 128.306 177.132)
		(end 128.306 176.502)
		(width 0.256)
		(layer "F.Cu")
		(net 151)
	)
	(segment
		(start 244.25 183.324)
		(end 244.325 183.249)
		(width 0.182)
		(layer "F.Cu")
		(net 151)
	)
	(segment
		(start 252.585 184.699)
		(end 251.813 184.699)
		(width 0.182)
		(layer "F.Cu")
		(net 151)
	)
	(segment
		(start 160.58 157.199999)
		(end 160.1 157.679999)
		(width 0.256)
		(layer "F.Cu")
		(net 151)
	)
	(segment
		(start 251.92 183.549)
		(end 251.173002 183.549)
		(width 0.182)
		(layer "F.Cu")
		(net 151)
	)
	(segment
		(start 114.6 159.8)
		(end 113.178 159.8)
		(width 0.256)
		(layer "F.Cu")
		(net 151)
	)
	(segment
		(start 125.406 186.1075)
		(end 124.756 186.1075)
		(width 0.256)
		(layer "F.Cu")
		(net 151)
	)
	(segment
		(start 244.801499 160.15)
		(end 244.800499 160.149)
		(width 0.1)
		(layer "F.Cu")
		(net 151)
	)
	(segment
		(start 101.95 103.65)
		(end 102.605 102.995)
		(width 0.15)
		(layer "F.Cu")
		(net 151)
	)
	(segment
		(start 124.576 185.9275)
		(end 124.756 186.1075)
		(width 0.201)
		(layer "F.Cu")
		(net 151)
	)
	(segment
		(start 179.9995 151.9995)
		(end 179.5 151.5)
		(width 0.256)
		(layer "F.Cu")
		(net 151)
	)
	(segment
		(start 104.68 103.6)
		(end 105.305 102.975)
		(width 0.15)
		(layer "F.Cu")
		(net 151)
	)
	(segment
		(start 245.597 160.15)
		(end 244.801499 160.15)
		(width 0.1)
		(layer "F.Cu")
		(net 151)
	)
	(segment
		(start 105.485 113.755)
		(end 106.385 113.755)
		(width 0.182)
		(layer "F.Cu")
		(net 151)
	)
	(segment
		(start 124.1995 162.51)
		(end 124.1995 161.9505)
		(width 0.1)
		(layer "F.Cu")
		(net 151)
	)
	(segment
		(start 242.98 132.8)
		(end 243.55 132.8)
		(width 0.256)
		(layer "F.Cu")
		(net 151)
	)
	(segment
		(start 149.313499 159)
		(end 149.4 159)
		(width 0.15)
		(layer "F.Cu")
		(net 151)
	)
	(segment
		(start 108.004 102.976)
		(end 108.004 102.996)
		(width 0.1)
		(layer "F.Cu")
		(net 151)
	)
	(segment
		(start 127.076 177.828)
		(end 127.076 176.732)
		(width 0.201)
		(layer "F.Cu")
		(net 151)
	)
	(segment
		(start 160.62 157.189999)
		(end 161.09 156.719999)
		(width 0.256)
		(layer "F.Cu")
		(net 151)
	)
	(segment
		(start 252.551 144.551)
		(end 252.55 144.55)
		(width 0.256)
		(layer "F.Cu")
		(net 151)
	)
	(segment
		(start 244.25 183.919)
		(end 244.25 183.324)
		(width 0.182)
		(layer "F.Cu")
		(net 151)
	)
	(segment
		(start 102.605 102.995)
		(end 102.605 102.975)
		(width 0.15)
		(layer "F.Cu")
		(net 151)
	)
	(segment
		(start 168.35 159.17)
		(end 168.145 159.375)
		(width 0.256)
		(layer "F.Cu")
		(net 151)
	)
	(segment
		(start 108.973499 114.448499)
		(end 108.973499 113.998)
		(width 0.15)
		(layer "F.Cu")
		(net 151)
	)
	(segment
		(start 182.9995 150.9995)
		(end 182.5 150.5)
		(width 0.256)
		(layer "F.Cu")
		(net 151)
	)
	(segment
		(start 112.75 103.6)
		(end 112.78 103.6)
		(width 0.1)
		(layer "F.Cu")
		(net 151)
	)
	(segment
		(start 251.813 184.699)
		(end 251.45 184.699)
		(width 0.182)
		(layer "F.Cu")
		(net 151)
	)
	(segment
		(start 109.25 114.725)
		(end 108.973499 114.448499)
		(width 0.15)
		(layer "F.Cu")
		(net 151)
	)
	(segment
		(start 123.6995 161.9495)
		(end 123.6995 162.51)
		(width 0.1)
		(layer "F.Cu")
		(net 151)
	)
	(segment
		(start 168.35 158.45)
		(end 168.35 159.17)
		(width 0.256)
		(layer "F.Cu")
		(net 151)
	)
	(segment
		(start 164.775 161.799999)
		(end 164.94 161.634999)
		(width 0.256)
		(layer "F.Cu")
		(net 151)
	)
	(segment
		(start 124.576 184.778)
		(end 124.576 185.9275)
		(width 0.201)
		(layer "F.Cu")
		(net 151)
	)
	(segment
		(start 108.004 102.996)
		(end 107.4 103.6)
		(width 0.1)
		(layer "F.Cu")
		(net 151)
	)
	(segment
		(start 148.364499 159.758)
		(end 148.555499 159.758)
		(width 0.15)
		(layer "F.Cu")
		(net 151)
	)
	(via
		(at 187.3 103.2)
		(size 0.45)
		(drill 0.1)
		(layers "F.Cu" "B.Cu")
		(remove_unused_layers yes)
		(keep_end_layers yes)
		(zone_layer_connections "In8.Cu")
		(net 151)
	)
	(via
		(at 125.406 186.1075)
		(size 0.45)
		(drill 0.1)
		(layers "F.Cu" "B.Cu")
		(remove_unused_layers yes)
		(keep_end_layers yes)
		(zone_layer_connections "In6.Cu")
		(net 151)
	)
	(via
		(at 167.6 161.375)
		(size 0.45)
		(drill 0.1)
		(layers "F.Cu" "B.Cu")
		(remove_unused_layers yes)
		(keep_end_layers yes)
		(zone_layer_connections "In8.Cu")
		(net 151)
	)
	(via
		(at 198.5 150.5)
		(size 0.45)
		(drill 0.1)
		(layers "F.Cu" "B.Cu")
		(remove_unused_layers yes)
		(keep_end_layers yes)
		(zone_layer_connections)
		(net 151)
	)
	(via
		(at 101.95 103.65)
		(size 0.45)
		(drill 0.1)
		(layers "F.Cu" "B.Cu")
		(remove_unused_layers yes)
		(keep_end_layers yes)
		(zone_layer_connections "In8.Cu")
		(net 151)
	)
	(via
		(at 115.7 170.63)
		(size 0.45)
		(drill 0.1)
		(layers "F.Cu" "B.Cu")
		(remove_unused_layers yes)
		(keep_end_layers yes)
		(zone_layer_connections "In6.Cu" "In8.Cu")
		(net 151)
	)
	(via
		(at 245.8 155.95)
		(size 0.45)
		(drill 0.1)
		(layers "F.Cu" "B.Cu")
		(remove_unused_layers yes)
		(keep_end_layers yes)
		(zone_layer_connections "In8.Cu")
		(net 151)
	)
	(via
		(at 245.375 157.425)
		(size 0.45)
		(drill 0.1)
		(layers "F.Cu" "B.Cu")
		(remove_unused_layers yes)
		(keep_end_layers yes)
		(zone_layer_connections "In8.Cu")
		(net 151)
	)
	(via
		(at 257.7955 102.7545)
		(size 0.45)
		(drill 0.1)
		(layers "F.Cu" "B.Cu")
		(remove_unused_layers yes)
		(keep_end_layers yes)
		(zone_layer_connections "In8.Cu")
		(net 151)
	)
	(via
		(at 182.5 156.5)
		(size 0.45)
		(drill 0.1)
		(layers "F.Cu" "B.Cu")
		(remove_unused_layers yes)
		(keep_end_layers yes)
		(zone_layer_connections)
		(net 151)
	)
	(via
		(at 121.21 145.61)
		(size 0.45)
		(drill 0.1)
		(layers "F.Cu" "B.Cu")
		(remove_unused_layers yes)
		(keep_end_layers yes)
		(zone_layer_connections "In6.Cu" "In8.Cu")
		(net 151)
	)
	(via
		(at 128.306 177.132)
		(size 0.45)
		(drill 0.1)
		(layers "F.Cu" "B.Cu")
		(remove_unused_layers yes)
		(keep_end_layers yes)
		(zone_layer_connections "In6.Cu" "In8.Cu")
		(net 151)
	)
	(via
		(at 113.84 170.18)
		(size 0.45)
		(drill 0.1)
		(layers "F.Cu" "B.Cu")
		(remove_unused_layers yes)
		(keep_end_layers yes)
		(zone_layer_connections "In6.Cu" "In8.Cu")
		(net 151)
	)
	(via
		(at 119.56 142.21)
		(size 0.45)
		(drill 0.1)
		(layers "F.Cu" "B.Cu")
		(remove_unused_layers yes)
		(keep_end_layers yes)
		(zone_layer_connections "In6.Cu" "In8.Cu")
		(net 151)
	)
	(via
		(at 148.794499 163.079)
		(size 0.45)
		(drill 0.1)
		(layers "F.Cu" "B.Cu")
		(remove_unused_layers yes)
		(keep_end_layers yes)
		(zone_layer_connections "In8.Cu")
		(net 151)
	)
	(via
		(at 106.905 123.543499)
		(size 0.45)
		(drill 0.1)
		(layers "F.Cu" "B.Cu")
		(remove_unused_layers yes)
		(keep_end_layers yes)
		(zone_layer_connections "In8.Cu")
		(net 151)
	)
	(via
		(at 244.4 157.475)
		(size 0.45)
		(drill 0.1)
		(layers "F.Cu" "B.Cu")
		(remove_unused_layers yes)
		(keep_end_layers yes)
		(zone_layer_connections "In8.Cu")
		(net 151)
	)
	(via
		(at 244.325 183.249)
		(size 0.45)
		(drill 0.1)
		(layers "F.Cu" "B.Cu")
		(remove_unused_layers yes)
		(keep_end_layers yes)
		(zone_layer_connections)
		(net 151)
	)
	(via
		(at 243.55 132.8)
		(size 0.45)
		(drill 0.1)
		(layers "F.Cu" "B.Cu")
		(remove_unused_layers yes)
		(keep_end_layers yes)
		(zone_layer_connections "In8.Cu")
		(net 151)
	)
	(via
		(at 114.6 159.8)
		(size 0.45)
		(drill 0.1)
		(layers "F.Cu" "B.Cu")
		(remove_unused_layers yes)
		(keep_end_layers yes)
		(zone_layer_connections "In6.Cu" "In8.Cu")
		(net 151)
	)
	(via
		(at 106.635 114.005)
		(size 0.45)
		(drill 0.1)
		(layers "F.Cu" "B.Cu")
		(remove_unused_layers yes)
		(keep_end_layers yes)
		(zone_layer_connections "In8.Cu")
		(net 151)
	)
	(via
		(at 245.375 155.575)
		(size 0.45)
		(drill 0.1)
		(layers "F.Cu" "B.Cu")
		(remove_unused_layers yes)
		(keep_end_layers yes)
		(zone_layer_connections "In8.Cu")
		(net 151)
	)
	(via
		(at 145.8 177.91)
		(size 0.45)
		(drill 0.1)
		(layers "F.Cu" "B.Cu")
		(remove_unused_layers yes)
		(keep_end_layers yes)
		(zone_layer_connections "In6.Cu" "In8.Cu")
		(net 151)
	)
	(via
		(at 182.5 150.5)
		(size 0.45)
		(drill 0.1)
		(layers "F.Cu" "B.Cu")
		(remove_unused_layers yes)
		(keep_end_layers yes)
		(zone_layer_connections)
		(net 151)
	)
	(via
		(at 251.15 183.525998)
		(size 0.45)
		(drill 0.1)
		(layers "F.Cu" "B.Cu")
		(remove_unused_layers yes)
		(keep_end_layers yes)
		(zone_layer_connections)
		(net 151)
	)
	(via
		(at 123.65 161.9)
		(size 0.45)
		(drill 0.1)
		(layers "F.Cu" "B.Cu")
		(remove_unused_layers yes)
		(keep_end_layers yes)
		(zone_layer_connections "In6.Cu")
		(net 151)
	)
	(via
		(at 106.9 127.55)
		(size 0.45)
		(drill 0.1)
		(layers "F.Cu" "B.Cu")
		(remove_unused_layers yes)
		(keep_end_layers yes)
		(zone_layer_connections "In8.Cu")
		(net 151)
	)
	(via
		(at 257.7955 103.4295)
		(size 0.45)
		(drill 0.1)
		(layers "F.Cu" "B.Cu")
		(remove_unused_layers yes)
		(keep_end_layers yes)
		(zone_layer_connections "In8.Cu")
		(net 151)
	)
	(via
		(at 257.2455 102.4545)
		(size 0.45)
		(drill 0.1)
		(layers "F.Cu" "B.Cu")
		(remove_unused_layers yes)
		(keep_end_layers yes)
		(zone_layer_connections "In8.Cu")
		(net 151)
	)
	(via
		(at 254 118.3)
		(size 0.45)
		(drill 0.1)
		(layers "F.Cu" "B.Cu")
		(net 151)
	)
	(via
		(at 179.499999 157.5)
		(size 0.45)
		(drill 0.1)
		(layers "F.Cu" "B.Cu")
		(remove_unused_layers yes)
		(keep_end_layers yes)
		(zone_layer_connections)
		(net 151)
	)
	(via
		(at 117.13 165.8)
		(size 0.45)
		(drill 0.1)
		(layers "F.Cu" "B.Cu")
		(remove_unused_layers yes)
		(keep_end_layers yes)
		(zone_layer_connections "In6.Cu" "In8.Cu")
		(net 151)
	)
	(via
		(at 132.766 170.552)
		(size 0.45)
		(drill 0.1)
		(layers "F.Cu" "B.Cu")
		(remove_unused_layers yes)
		(keep_end_layers yes)
		(zone_layer_connections "In6.Cu")
		(net 151)
	)
	(via
		(at 238.909499 185.184)
		(size 0.45)
		(drill 0.1)
		(layers "F.Cu" "B.Cu")
		(remove_unused_layers yes)
		(keep_end_layers yes)
		(zone_layer_connections)
		(net 151)
	)
	(via
		(at 124.25 161.9)
		(size 0.45)
		(drill 0.1)
		(layers "F.Cu" "B.Cu")
		(remove_unused_layers yes)
		(keep_end_layers yes)
		(zone_layer_connections "In6.Cu")
		(net 151)
	)
	(via
		(at 166.75 160.075)
		(size 0.45)
		(drill 0.1)
		(layers "F.Cu" "B.Cu")
		(remove_unused_layers yes)
		(keep_end_layers yes)
		(zone_layer_connections "In8.Cu")
		(net 151)
	)
	(via
		(at 168.45 162.2)
		(size 0.45)
		(drill 0.1)
		(layers "F.Cu" "B.Cu")
		(remove_unused_layers yes)
		(keep_end_layers yes)
		(zone_layer_connections "In8.Cu")
		(net 151)
	)
	(via
		(at 244 157)
		(size 0.45)
		(drill 0.1)
		(layers "F.Cu" "B.Cu")
		(remove_unused_layers yes)
		(keep_end_layers yes)
		(zone_layer_connections "In8.Cu")
		(net 151)
	)
	(via
		(at 245.3 156.5)
		(size 0.45)
		(drill 0.1)
		(layers "F.Cu" "B.Cu")
		(remove_unused_layers yes)
		(keep_end_layers yes)
		(zone_layer_connections "In8.Cu")
		(net 151)
	)
	(via
		(at 168.35 158.45)
		(size 0.45)
		(drill 0.1)
		(layers "F.Cu" "B.Cu")
		(remove_unused_layers yes)
		(keep_end_layers yes)
		(zone_layer_connections "In8.Cu")
		(net 151)
	)
	(via
		(at 257.2205 103.7295)
		(size 0.45)
		(drill 0.1)
		(layers "F.Cu" "B.Cu")
		(remove_unused_layers yes)
		(keep_end_layers yes)
		(zone_layer_connections "In8.Cu")
		(net 151)
	)
	(via
		(at 140.95 138.05)
		(size 0.45)
		(drill 0.1)
		(layers "F.Cu" "B.Cu")
		(remove_unused_layers yes)
		(keep_end_layers yes)
		(zone_layer_connections "In6.Cu")
		(net 151)
	)
	(via
		(at 244.925 155.95)
		(size 0.45)
		(drill 0.1)
		(layers "F.Cu" "B.Cu")
		(remove_unused_layers yes)
		(keep_end_layers yes)
		(zone_layer_connections "In8.Cu")
		(net 151)
	)
	(via
		(at 119.931 167.99)
		(size 0.45)
		(drill 0.1)
		(layers "F.Cu" "B.Cu")
		(remove_unused_layers yes)
		(keep_end_layers yes)
		(zone_layer_connections "In6.Cu")
		(net 151)
	)
	(via
		(at 110.1 103.55)
		(size 0.45)
		(drill 0.1)
		(layers "F.Cu" "B.Cu")
		(remove_unused_layers yes)
		(keep_end_layers yes)
		(zone_layer_connections "In8.Cu")
		(net 151)
	)
	(via
		(at 128.956 176.502)
		(size 0.45)
		(drill 0.1)
		(layers "F.Cu" "B.Cu")
		(remove_unused_layers yes)
		(keep_end_layers yes)
		(zone_layer_connections "In6.Cu" "In8.Cu")
		(net 151)
	)
	(via
		(at 179.5 151.5)
		(size 0.45)
		(drill 0.1)
		(layers "F.Cu" "B.Cu")
		(remove_unused_layers yes)
		(keep_end_layers yes)
		(zone_layer_connections)
		(net 151)
	)
	(via
		(at 121.026 165.632)
		(size 0.45)
		(drill 0.1)
		(layers "F.Cu" "B.Cu")
		(remove_unused_layers yes)
		(keep_end_layers yes)
		(zone_layer_connections "In6.Cu")
		(net 151)
	)
	(via
		(at 238.925 183.25)
		(size 0.45)
		(drill 0.1)
		(layers "F.Cu" "B.Cu")
		(remove_unused_layers yes)
		(keep_end_layers yes)
		(zone_layer_connections)
		(net 151)
	)
	(via
		(at 257.79 141.965)
		(size 0.45)
		(drill 0.1)
		(layers "F.Cu" "B.Cu")
		(remove_unused_layers yes)
		(keep_end_layers yes)
		(zone_layer_connections "In8.Cu")
		(net 151)
	)
	(via
		(at 244.85 156.975)
		(size 0.45)
		(drill 0.1)
		(layers "F.Cu" "B.Cu")
		(remove_unused_layers yes)
		(keep_end_layers yes)
		(zone_layer_connections "In8.Cu")
		(net 151)
	)
	(via
		(at 195.5 151.5)
		(size 0.45)
		(drill 0.1)
		(layers "F.Cu" "B.Cu")
		(remove_unused_layers yes)
		(keep_end_layers yes)
		(zone_layer_connections)
		(net 151)
	)
	(via
		(at 157.299499 191.299)
		(size 0.45)
		(drill 0.1)
		(layers "F.Cu" "B.Cu")
		(remove_unused_layers yes)
		(keep_end_layers yes)
		(zone_layer_connections "In6.Cu" "In8.Cu")
		(net 151)
	)
	(via
		(at 165.58 161.634999)
		(size 0.45)
		(drill 0.1)
		(layers "F.Cu" "B.Cu")
		(remove_unused_layers yes)
		(keep_end_layers yes)
		(zone_layer_connections "In8.Cu")
		(net 151)
	)
	(via
		(at 160.62 157.199999)
		(size 0.45)
		(drill 0.1)
		(layers "F.Cu" "B.Cu")
		(remove_unused_layers yes)
		(keep_end_layers yes)
		(zone_layer_connections "In8.Cu")
		(net 151)
	)
	(via
		(at 116.91 186.01)
		(size 0.45)
		(drill 0.1)
		(layers "F.Cu" "B.Cu")
		(remove_unused_layers yes)
		(keep_end_layers yes)
		(zone_layer_connections "In6.Cu" "In8.Cu")
		(net 151)
	)
	(via
		(at 149.4 159)
		(size 0.45)
		(drill 0.1)
		(layers "F.Cu" "B.Cu")
		(remove_unused_layers yes)
		(keep_end_layers yes)
		(zone_layer_connections "In8.Cu")
		(net 151)
	)
	(via
		(at 108.975 113.975)
		(size 0.45)
		(drill 0.1)
		(layers "F.Cu" "B.Cu")
		(remove_unused_layers yes)
		(keep_end_layers yes)
		(zone_layer_connections "In8.Cu")
		(net 151)
	)
	(via
		(at 252.55 144.55)
		(size 0.45)
		(drill 0.1)
		(layers "F.Cu" "B.Cu")
		(remove_unused_layers yes)
		(keep_end_layers yes)
		(zone_layer_connections "In8.Cu")
		(net 151)
	)
	(via
		(at 107.4 103.6)
		(size 0.45)
		(drill 0.1)
		(layers "F.Cu" "B.Cu")
		(remove_unused_layers yes)
		(keep_end_layers yes)
		(zone_layer_connections "In8.Cu")
		(net 151)
	)
	(via
		(at 257.2455 103.0545)
		(size 0.45)
		(drill 0.1)
		(layers "F.Cu" "B.Cu")
		(remove_unused_layers yes)
		(keep_end_layers yes)
		(zone_layer_connections "In8.Cu")
		(net 151)
	)
	(via
		(at 207.3 153.25)
		(size 0.45)
		(drill 0.1)
		(layers "F.Cu" "B.Cu")
		(remove_unused_layers yes)
		(keep_end_layers yes)
		(zone_layer_connections)
		(net 151)
	)
	(via
		(at 104.65 103.6)
		(size 0.45)
		(drill 0.1)
		(layers "F.Cu" "B.Cu")
		(remove_unused_layers yes)
		(keep_end_layers yes)
		(zone_layer_connections "In8.Cu")
		(net 151)
	)
	(via
		(at 112.75 103.6)
		(size 0.45)
		(drill 0.1)
		(layers "F.Cu" "B.Cu")
		(remove_unused_layers yes)
		(keep_end_layers yes)
		(zone_layer_connections "In8.Cu")
		(net 151)
	)
	(via
		(at 131.98 174.83)
		(size 0.45)
		(drill 0.1)
		(layers "F.Cu" "B.Cu")
		(remove_unused_layers yes)
		(keep_end_layers yes)
		(zone_layer_connections "In6.Cu" "In8.Cu")
		(net 151)
	)
	(via
		(at 244.325 182.599)
		(size 0.45)
		(drill 0.1)
		(layers "F.Cu" "B.Cu")
		(remove_unused_layers yes)
		(keep_end_layers yes)
		(zone_layer_connections)
		(net 151)
	)
	(via
		(at 143.79 178.36)
		(size 0.45)
		(drill 0.1)
		(layers "F.Cu" "B.Cu")
		(remove_unused_layers yes)
		(keep_end_layers yes)
		(zone_layer_connections "In6.Cu" "In8.Cu")
		(net 151)
	)
	(via
		(at 245.8 156.975)
		(size 0.45)
		(drill 0.1)
		(layers "F.Cu" "B.Cu")
		(remove_unused_layers yes)
		(keep_end_layers yes)
		(zone_layer_connections "In8.Cu")
		(net 151)
	)
	(via
		(at 155.02 159.634999)
		(size 0.45)
		(drill 0.1)
		(layers "F.Cu" "B.Cu")
		(remove_unused_layers yes)
		(keep_end_layers yes)
		(zone_layer_connections "In8.Cu")
		(net 151)
	)
	(segment
		(start 244.395 182.669)
		(end 244.325 182.599)
		(width 0.182)
		(layer "B.Cu")
		(net 151)
	)
	(segment
		(start 243.59 134.62)
		(end 242.97 135.24)
		(width 0.198)
		(layer "B.Cu")
		(net 151)
	)
	(segment
		(start 244.85 156.975)
		(end 244.933939 156.891061)
		(width 2)
		(layer "B.Cu")
		(net 151)
	)
	(segment
		(start 208.7 153.285)
		(end 208.7 149.7)
		(width 0.4)
		(layer "B.Cu")
		(net 151)
	)
	(segment
		(start 182.5 150.5)
		(end 182.498 150.5)
		(width 0.256)
		(layer "B.Cu")
		(net 151)
	)
	(segment
		(start 205.975 147.825)
		(end 203.5 150.3)
		(width 1.8)
		(layer "B.Cu")
		(net 151)
	)
	(segment
		(start 123.72 161.97)
		(end 123.72 162.5)
		(width 0.1)
		(layer "B.Cu")
		(net 151)
	)
	(segment
		(start 106.899 127.549)
		(end 106.9 127.55)
		(width 0.2)
		(layer "B.Cu")
		(net 151)
	)
	(segment
		(start 254 117.84)
		(end 253.27 117.11)
		(width 0.198)
		(layer "B.Cu")
		(net 151)
	)
	(segment
		(start 246.123 182.749)
		(end 246.043 182.669)
		(width 0.182)
		(layer "B.Cu")
		(net 151)
	)
	(segment
		(start 149.084499 159.315501)
		(end 149.4 159)
		(width 0.15)
		(layer "B.Cu")
		(net 151)
	)
	(segment
		(start 230.3 154.2)
		(end 224.943833 154.2)
		(width 1.8)
		(layer "B.Cu")
		(net 151)
	)
	(segment
		(start 148.794499 163.875)
		(end 149.084499 164.165)
		(width 0.15)
		(layer "B.Cu")
		(net 151)
	)
	(segment
		(start 238.909499 182.499)
		(end 238.909499 183.234499)
		(width 0.177)
		(layer "B.Cu")
		(net 151)
	)
	(segment
		(start 221.111833 150.368)
		(end 218.531332 150.368)
		(width 1.8)
		(layer "B.Cu")
		(net 151)
	)
	(segment
		(start 106.874499 127.549)
		(end 106.899 127.549)
		(width 0.2)
		(layer "B.Cu")
		(net 151)
	)
	(segment
		(start 181.998 156)
		(end 182 156)
		(width 0.182)
		(layer "B.Cu")
		(net 151)
	)
	(segment
		(start 168.905 158.45)
		(end 168.35 158.45)
		(width 0.256)
		(layer "B.Cu")
		(net 151)
	)
	(segment
		(start 206.325 153.71)
		(end 208.275 153.71)
		(width 0.182)
		(layer "B.Cu")
		(net 151)
	)
	(segment
		(start 246.043 182.669)
		(end 244.395 182.669)
		(width 0.182)
		(layer "B.Cu")
		(net 151)
	)
	(segment
		(start 148.794499 163.079)
		(end 148.794499 163.875)
		(width 0.15)
		(layer "B.Cu")
		(net 151)
	)
	(segment
		(start 117.999 166.36)
		(end 117.69 166.36)
		(width 0.15)
		(layer "B.Cu")
		(net 151)
	)
	(segment
		(start 208.1 149.1)
		(end 208.1 147.775)
		(width 0.4)
		(layer "B.Cu")
		(net 151)
	)
	(segment
		(start 233.675 150.825)
		(end 230.3 154.2)
		(width 1.8)
		(layer "B.Cu")
		(net 151)
	)
	(segment
		(start 208.275 153.71)
		(end 208.7 153.285)
		(width 0.4)
		(layer "B.Cu")
		(net 151)
	)
	(segment
		(start 205.975 147.775)
		(end 205.975 147.825)
		(width 1.8)
		(layer "B.Cu")
		(net 151)
	)
	(segment
		(start 182.498 150.5)
		(end 181.998 150)
		(width 0.256)
		(layer "B.Cu")
		(net 151)
	)
	(segment
		(start 115.034 160.234)
		(end 114.6 159.8)
		(width 0.256)
		(layer "B.Cu")
		(net 151)
	)
	(segment
		(start 238.909499 183.234499)
		(end 238.925 183.25)
		(width 0.177)
		(layer "B.Cu")
		(net 151)
	)
	(segment
		(start 149.084499 159.949)
		(end 149.084499 159.315501)
		(width 0.15)
		(layer "B.Cu")
		(net 151)
	)
	(segment
		(start 125.44 186.1415)
		(end 125.406 186.1075)
		(width 0.201)
		(layer "B.Cu")
		(net 151)
	)
	(segment
		(start 106.905 123.543499)
		(end 106.905 122.855)
		(width 0.2)
		(layer "B.Cu")
		(net 151)
	)
	(segment
		(start 119.801 167.22)
		(end 119.931 167.35)
		(width 0.15)
		(layer "B.Cu")
		(net 151)
	)
	(segment
		(start 140.216 138.007851)
		(end 140.907851 138.007851)
		(width 0.4)
		(layer "B.Cu")
		(net 151)
	)
	(segment
		(start 157.299499 191.299)
		(end 156.609499 191.299)
		(width 0.177)
		(layer "B.Cu")
		(net 151)
	)
	(segment
		(start 253.35 144.55)
		(end 253.519499 144.380501)
		(width 0.15)
		(layer "B.Cu")
		(net 151)
	)
	(segment
		(start 198.5 150.5)
		(end 198.5 150.498)
		(width 0.256)
		(layer "B.Cu")
		(net 151)
	)
	(segment
		(start 133.64 174.83)
		(end 132.63 174.83)
		(width 0.201)
		(layer "B.Cu")
		(net 151)
	)
	(segment
		(start 254 118.3)
		(end 254 117.84)
		(width 0.198)
		(layer "B.Cu")
		(net 151)
	)
	(segment
		(start 208.7 149.7)
		(end 208.1 149.1)
		(width 0.4)
		(layer "B.Cu")
		(net 151)
	)
	(segment
		(start 243.55 132.8)
		(end 243.4 132.8)
		(width 0.198)
		(layer "B.Cu")
		(net 151)
	)
	(segment
		(start 244.85 155.575)
		(end 240.1 150.825)
		(width 1.8)
		(layer "B.Cu")
		(net 151)
	)
	(segment
		(start 125.44 187.94)
		(end 125.44 186.1415)
		(width 0.201)
		(layer "B.Cu")
		(net 151)
	)
	(segment
		(start 117.69 166.36)
		(end 116.26 164.93)
		(width 0.15)
		(layer "B.Cu")
		(net 151)
	)
	(segment
		(start 179.5 152.425)
		(end 179.4 152.525)
		(width 0.4)
		(layer "B.Cu")
		(net 151)
	)
	(segment
		(start 179.5 151.5)
		(end 179.5 152.425)
		(width 0.4)
		(layer "B.Cu")
		(net 151)
	)
	(segment
		(start 238.909499 185.849)
		(end 238.909499 185.184)
		(width 0.177)
		(layer "B.Cu")
		(net 151)
	)
	(segment
		(start 140.907851 138.007851)
		(end 140.95 138.05)
		(width 0.4)
		(layer "B.Cu")
		(net 151)
	)
	(segment
		(start 187.92 103.2)
		(end 187.3 103.2)
		(width 0.198)
		(layer "B.Cu")
		(net 151)
	)
	(segment
		(start 208.1 147.775)
		(end 205.975 147.775)
		(width 1.8)
		(layer "B.Cu")
		(net 151)
	)
	(segment
		(start 224.943833 154.2)
		(end 221.111833 150.368)
		(width 1.8)
		(layer "B.Cu")
		(net 151)
	)
	(segment
		(start 205.7 140.6045)
		(end 205.7 141.6045)
		(width 0.256)
		(layer "B.Cu")
		(net 151)
	)
	(segment
		(start 244.85 156.975)
		(end 244.85 155.575)
		(width 1.8)
		(layer "B.Cu")
		(net 151)
	)
	(segment
		(start 106.874499 127.549)
		(end 106.874499 128.264)
		(width 0.2)
		(layer "B.Cu")
		(net 151)
	)
	(segment
		(start 252.55 144.55)
		(end 253.35 144.55)
		(width 0.15)
		(layer "B.Cu")
		(net 151)
	)
	(segment
		(start 119.051 167.22)
		(end 119.801 167.22)
		(width 0.15)
		(layer "B.Cu")
		(net 151)
	)
	(segment
		(start 198.5 150.498)
		(end 199 149.998)
		(width 0.256)
		(layer "B.Cu")
		(net 151)
	)
	(segment
		(start 244.933939 156.891061)
		(end 244.933939 155.911313)
		(width 2)
		(layer "B.Cu")
		(net 151)
	)
	(segment
		(start 240.1 150.825)
		(end 233.675 150.825)
		(width 1.8)
		(layer "B.Cu")
		(net 151)
	)
	(segment
		(start 205.7 141.6045)
		(end 205.7 147.5)
		(width 0.256)
		(layer "B.Cu")
		(net 151)
	)
	(segment
		(start 243.4 132.8)
		(end 242.97 132.37)
		(width 0.198)
		(layer "B.Cu")
		(net 151)
	)
	(segment
		(start 243.59 132.84)
		(end 243.59 134.62)
		(width 0.198)
		(layer "B.Cu")
		(net 151)
	)
	(segment
		(start 178.997999 157)
		(end 178.999999 157)
		(width 0.256)
		(layer "B.Cu")
		(net 151)
	)
	(segment
		(start 218.531332 150.368)
		(end 215.938332 147.775)
		(width 1.8)
		(layer "B.Cu")
		(net 151)
	)
	(segment
		(start 123.65 161.9)
		(end 123.72 161.97)
		(width 0.1)
		(layer "B.Cu")
		(net 151)
	)
	(segment
		(start 115.55 160.234)
		(end 115.034 160.234)
		(width 0.256)
		(layer "B.Cu")
		(net 151)
	)
	(segment
		(start 207.29 153.24)
		(end 207.29 153.71)
		(width 0.4)
		(layer "B.Cu")
		(net 151)
	)
	(segment
		(start 119.931 167.35)
		(end 119.931 167.99)
		(width 0.15)
		(layer "B.Cu")
		(net 151)
	)
	(segment
		(start 253.519499 144.380501)
		(end 253.519499 143.8)
		(width 0.15)
		(layer "B.Cu")
		(net 151)
	)
	(segment
		(start 243.55 132.8)
		(end 243.59 132.84)
		(width 0.198)
		(layer "B.Cu")
		(net 151)
	)
	(segment
		(start 205.7 147.5)
		(end 205.975 147.775)
		(width 0.256)
		(layer "B.Cu")
		(net 151)
	)
	(segment
		(start 215.938332 147.775)
		(end 208.1 147.775)
		(width 1.8)
		(layer "B.Cu")
		(net 151)
	)
	(segment
		(start 205.7 139.4545)
		(end 205.7 140.6045)
		(width 0.256)
		(layer "B.Cu")
		(net 151)
	)
	(segment
		(start 132.63 174.83)
		(end 131.98 174.83)
		(width 0.201)
		(layer "B.Cu")
		(net 151)
	)
	(segment
		(start 251.075998 183.6)
		(end 251.15 183.525998)
		(width 0.256)
		(layer "In2.Cu")
		(net 151)
	)
	(segment
		(start 244.325 182.8)
		(end 244.325 181.85)
		(width 0.4)
		(layer "In6.Cu")
		(net 151)
	)
	(segment
		(start 241.05 188.2)
		(end 242.75 188.2)
		(width 0.4)
		(layer "In6.Cu")
		(net 151)
	)
	(segment
		(start 243.125 171.95)
		(end 243.125 157.875)
		(width 0.4)
		(layer "In6.Cu")
		(net 151)
	)
	(segment
		(start 244.325 182.25)
		(end 244.375 182.3)
		(width 0.256)
		(layer "In6.Cu")
		(net 151)
	)
	(segment
		(start 244.35 181.85)
		(end 244.8 182.3)
		(width 0.4)
		(layer "In6.Cu")
		(net 151)
	)
	(segment
		(start 247.834361 183.525)
		(end 251.149002 183.525)
		(width 0.256)
		(layer "In6.Cu")
		(net 151)
	)
	(segment
		(start 238.925 183.25)
		(end 238.925 186.075)
		(width 0.4)
		(layer "In6.Cu")
		(net 151)
	)
	(segment
		(start 244.325 182.8)
		(end 244.325 182.775)
		(width 0.4)
		(layer "In6.Cu")
		(net 151)
	)
	(segment
		(start 244.325 181.85)
		(end 244.35 181.85)
		(width 0.4)
		(layer "In6.Cu")
		(net 151)
	)
	(segment
		(start 244.325 181.6)
		(end 244.325 178.167463)
		(width 0.4)
		(layer "In6.Cu")
		(net 151)
	)
	(segment
		(start 246.265 175.09)
		(end 243.125 171.95)
		(width 0.4)
		(layer "In6.Cu")
		(net 151)
	)
	(segment
		(start 238.925 186.075)
		(end 241.05 188.2)
		(width 0.4)
		(layer "In6.Cu")
		(net 151)
	)
	(segment
		(start 244.375 182.3)
		(end 244.8 182.3)
		(width 0.256)
		(layer "In6.Cu")
		(net 151)
	)
	(segment
		(start 244.325 181.6)
		(end 244.325 182.25)
		(width 0.256)
		(layer "In6.Cu")
		(net 151)
	)
	(segment
		(start 244.325 182.775)
		(end 244.8 182.3)
		(width 0.4)
		(layer "In6.Cu")
		(net 151)
	)
	(segment
		(start 244.325 186.625)
		(end 244.325 184.8)
		(width 0.4)
		(layer "In6.Cu")
		(net 151)
	)
	(segment
		(start 242.75 188.2)
		(end 244.325 186.625)
		(width 0.4)
		(layer "In6.Cu")
		(net 151)
	)
	(segment
		(start 246.609361 182.3)
		(end 247.834361 183.525)
		(width 0.256)
		(layer "In6.Cu")
		(net 151)
	)
	(segment
		(start 244.8 182.3)
		(end 246.609361 182.3)
		(width 0.256)
		(layer "In6.Cu")
		(net 151)
	)
	(segment
		(start 251.149002 183.525)
		(end 251.15 183.525998)
		(width 0.256)
		(layer "In6.Cu")
		(net 151)
	)
	(segment
		(start 246.265 176.227463)
		(end 246.265 175.09)
		(width 0.4)
		(layer "In6.Cu")
		(net 151)
	)
	(segment
		(start 244.325 184.8)
		(end 244.325 184.15)
		(width 0.4)
		(layer "In6.Cu")
		(net 151)
	)
	(segment
		(start 244.325 178.167463)
		(end 246.265 176.227463)
		(width 0.4)
		(layer "In6.Cu")
		(net 151)
	)
	(segment
		(start 244.325 184.15)
		(end 244.325 182.8)
		(width 0.4)
		(layer "In6.Cu")
		(net 151)
	)
	(segment
		(start 243.125 157.875)
		(end 244 157)
		(width 0.4)
		(layer "In6.Cu")
		(net 151)
	)
	(segment
		(start 244.325 181.85)
		(end 244.325 181.6)
		(width 0.4)
		(layer "In6.Cu")
		(net 151)
	)
	(segment
		(start 228.5265 160.842501)
		(end 229.542501 160.842501)
		(width 0.4)
		(layer "F.Cu")
		(net 152)
	)
	(segment
		(start 117.300999 170.532)
		(end 117.300999 170.951501)
		(width 0.45)
		(layer "F.Cu")
		(net 152)
	)
	(segment
		(start 230.701501 160.85)
		(end 231.0995 161.247999)
		(width 0.4)
		(layer "F.Cu")
		(net 152)
	)
	(segment
		(start 230.075 160.85)
		(end 229.55 160.85)
		(width 0.4)
		(layer "F.Cu")
		(net 152)
	)
	(segment
		(start 116.661 170.532)
		(end 116.661 170.9515)
		(width 0.45)
		(layer "F.Cu")
		(net 152)
	)
	(segment
		(start 230.701501 160.85)
		(end 231.0995 160.452001)
		(width 0.4)
		(layer "F.Cu")
		(net 152)
	)
	(segment
		(start 242.924499 150.599)
		(end 243.724499 150.599)
		(width 0.4)
		(layer "F.Cu")
		(net 152)
	)
	(segment
		(start 245.537 150.451)
		(end 244.781999 150.451)
		(width 0.1)
		(layer "F.Cu")
		(net 152)
	)
	(segment
		(start 229.542501 160.842501)
		(end 229.55 160.85)
		(width 0.4)
		(layer "F.Cu")
		(net 152)
	)
	(segment
		(start 229.55 160.85)
		(end 230.701501 160.85)
		(width 0.4)
		(layer "F.Cu")
		(net 152)
	)
	(segment
		(start 230.2 159.875)
		(end 230.2 160.866)
		(width 0.177)
		(layer "F.Cu")
		(net 152)
	)
	(segment
		(start 244.781999 150.451)
		(end 244.780999 150.45)
		(width 0.1)
		(layer "F.Cu")
		(net 152)
	)
	(via
		(at 121.95 138.4)
		(size 0.45)
		(drill 0.1)
		(layers "F.Cu" "B.Cu")
		(remove_unused_layers yes)
		(keep_end_layers yes)
		(zone_layer_connections)
		(net 152)
	)
	(via
		(at 244.849499 153.249)
		(size 0.45)
		(drill 0.1)
		(layers "F.Cu" "B.Cu")
		(remove_unused_layers yes)
		(keep_end_layers yes)
		(zone_layer_connections)
		(net 152)
	)
	(via
		(at 116.661 170.532)
		(size 0.45)
		(drill 0.1)
		(layers "F.Cu" "B.Cu")
		(remove_unused_layers yes)
		(keep_end_layers yes)
		(zone_layer_connections)
		(net 152)
	)
	(via
		(at 236.15 148.225)
		(size 0.45)
		(drill 0.1)
		(layers "F.Cu" "B.Cu")
		(remove_unused_layers yes)
		(keep_end_layers yes)
		(zone_layer_connections)
		(net 152)
	)
	(via
		(at 245.824499 153.249)
		(size 0.45)
		(drill 0.1)
		(layers "F.Cu" "B.Cu")
		(remove_unused_layers yes)
		(keep_end_layers yes)
		(zone_layer_connections)
		(net 152)
	)
	(via
		(at 231.0995 161.247999)
		(size 0.45)
		(drill 0.1)
		(layers "F.Cu" "B.Cu")
		(remove_unused_layers yes)
		(keep_end_layers yes)
		(zone_layer_connections)
		(net 152)
	)
	(via
		(at 231.0995 160.452001)
		(size 0.45)
		(drill 0.1)
		(layers "F.Cu" "B.Cu")
		(remove_unused_layers yes)
		(keep_end_layers yes)
		(zone_layer_connections)
		(net 152)
	)
	(via
		(at 242.924499 150.599)
		(size 0.45)
		(drill 0.1)
		(layers "F.Cu" "B.Cu")
		(remove_unused_layers yes)
		(keep_end_layers yes)
		(zone_layer_connections)
		(net 152)
	)
	(via
		(at 243.724499 150.599)
		(size 0.45)
		(drill 0.1)
		(layers "F.Cu" "B.Cu")
		(remove_unused_layers yes)
		(keep_end_layers yes)
		(zone_layer_connections)
		(net 152)
	)
	(via
		(at 245.824499 151.974)
		(size 0.45)
		(drill 0.1)
		(layers "F.Cu" "B.Cu")
		(remove_unused_layers yes)
		(keep_end_layers yes)
		(zone_layer_connections)
		(net 152)
	)
	(via
		(at 235.601168 148.225)
		(size 0.45)
		(drill 0.1)
		(layers "F.Cu" "B.Cu")
		(remove_unused_layers yes)
		(keep_end_layers yes)
		(zone_layer_connections)
		(net 152)
	)
	(via
		(at 243.724499 151.274)
		(size 0.45)
		(drill 0.1)
		(layers "F.Cu" "B.Cu")
		(remove_unused_layers yes)
		(keep_end_layers yes)
		(zone_layer_connections)
		(net 152)
	)
	(via
		(at 121.25 137.8)
		(size 0.45)
		(drill 0.1)
		(layers "F.Cu" "B.Cu")
		(remove_unused_layers yes)
		(keep_end_layers yes)
		(zone_layer_connections)
		(net 152)
	)
	(via
		(at 244.824499 151.974)
		(size 0.45)
		(drill 0.1)
		(layers "F.Cu" "B.Cu")
		(remove_unused_layers yes)
		(keep_end_layers yes)
		(zone_layer_connections)
		(net 152)
	)
	(via
		(at 243.724499 149.924)
		(size 0.45)
		(drill 0.1)
		(layers "F.Cu" "B.Cu")
		(remove_unused_layers yes)
		(keep_end_layers yes)
		(zone_layer_connections)
		(net 152)
	)
	(via
		(at 243.724499 151.949)
		(size 0.45)
		(drill 0.1)
		(layers "F.Cu" "B.Cu")
		(remove_unused_layers yes)
		(keep_end_layers yes)
		(zone_layer_connections)
		(net 152)
	)
	(via
		(at 117.300999 170.532)
		(size 0.45)
		(drill 0.1)
		(layers "F.Cu" "B.Cu")
		(remove_unused_layers yes)
		(keep_end_layers yes)
		(zone_layer_connections)
		(net 152)
	)
	(segment
		(start 231.75 138.05)
		(end 216 122.3)
		(width 2)
		(layer "B.Cu")
		(net 152)
	)
	(segment
		(start 243.749 150.599)
		(end 244.125 150.975)
		(width 2)
		(layer "B.Cu")
		(net 152)
	)
	(segment
		(start 243.724499 150.599)
		(end 241.350499 148.225)
		(width 2)
		(layer "B.Cu")
		(net 152)
	)
	(segment
		(start 124.435 135.175)
		(end 122.01 137.6)
		(width 2)
		(layer "B.Cu")
		(net 152)
	)
	(segment
		(start 235.601168 148.225)
		(end 231.75 144.373832)
		(width 2)
		(layer "B.Cu")
		(net 152)
	)
	(segment
		(start 243.724499 150.599)
		(end 243.749 150.599)
		(width 2)
		(layer "B.Cu")
		(net 152)
	)
	(segment
		(start 244.125 150.975)
		(end 244.125 151.325)
		(width 2)
		(layer "B.Cu")
		(net 152)
	)
	(segment
		(start 231.75 144.373832)
		(end 231.75 138.05)
		(width 2)
		(layer "B.Cu")
		(net 152)
	)
	(segment
		(start 157.425 122.3)
		(end 144.55 135.175)
		(width 2)
		(layer "B.Cu")
		(net 152)
	)
	(segment
		(start 144.55 135.175)
		(end 124.435 135.175)
		(width 2)
		(layer "B.Cu")
		(net 152)
	)
	(segment
		(start 216 122.3)
		(end 157.425 122.3)
		(width 2)
		(layer "B.Cu")
		(net 152)
	)
	(segment
		(start 241.350499 148.225)
		(end 235.601168 148.225)
		(width 2)
		(layer "B.Cu")
		(net 152)
	)
	(segment
		(start 236.15 148.225)
		(end 231.1 153.275)
		(width 2)
		(layer "In2.Cu")
		(net 152)
	)
	(segment
		(start 231.1 153.275)
		(end 231.1 160.45)
		(width 2)
		(layer "In2.Cu")
		(net 152)
	)
	(segment
		(start 121.3 145.059361)
		(end 121.3 138.45)
		(width 0.256)
		(layer "In8.Cu")
		(net 152)
	)
	(segment
		(start 121.663 145.422361)
		(end 121.3 145.059361)
		(width 0.256)
		(layer "In8.Cu")
		(net 152)
	)
	(segment
		(start 117.828 167.722)
		(end 117.828 159.503)
		(width 0.256)
		(layer "In8.Cu")
		(net 152)
	)
	(segment
		(start 117.300999 170.532)
		(end 117.218999 170.45)
		(width 0.256)
		(layer "In8.Cu")
		(net 152)
	)
	(segment
		(start 117.6 155.25)
		(end 116.8 154.45)
		(width 0.256)
		(layer "In8.Cu")
		(net 152)
	)
	(segment
		(start 117 170.231001)
		(end 117 170.2)
		(width 0.256)
		(layer "In8.Cu")
		(net 152)
	)
	(segment
		(start 121.95 138.4)
		(end 121.25 138.4)
		(width 0.256)
		(layer "In8.Cu")
		(net 152)
	)
	(segment
		(start 117.300999 170.532)
		(end 117 170.231001)
		(width 0.256)
		(layer "In8.Cu")
		(net 152)
	)
	(segment
		(start 116.8 150.85)
		(end 121.663 145.987)
		(width 0.256)
		(layer "In8.Cu")
		(net 152)
	)
	(segment
		(start 116.661 170.532)
		(end 116.668 170.532)
		(width 0.256)
		(layer "In8.Cu")
		(net 152)
	)
	(segment
		(start 117.828 159.503)
		(end 117.6 159.275)
		(width 0.256)
		(layer "In8.Cu")
		(net 152)
	)
	(segment
		(start 117.218999 170.45)
		(end 116.743 170.45)
		(width 0.256)
		(layer "In8.Cu")
		(net 152)
	)
	(segment
		(start 116.743 170.45)
		(end 116.661 170.532)
		(width 0.256)
		(layer "In8.Cu")
		(net 152)
	)
	(segment
		(start 116.8 154.45)
		(end 116.8 150.85)
		(width 0.256)
		(layer "In8.Cu")
		(net 152)
	)
	(segment
		(start 117.6 159.275)
		(end 117.6 155.25)
		(width 0.256)
		(layer "In8.Cu")
		(net 152)
	)
	(segment
		(start 121.663 145.987)
		(end 121.663 145.422361)
		(width 0.256)
		(layer "In8.Cu")
		(net 152)
	)
	(segment
		(start 116.668 170.532)
		(end 117 170.2)
		(width 0.256)
		(layer "In8.Cu")
		(net 152)
	)
	(segment
		(start 117 170.2)
		(end 117 168.55)
		(width 0.256)
		(layer "In8.Cu")
		(net 152)
	)
	(segment
		(start 117 168.55)
		(end 117.828 167.722)
		(width 0.256)
		(layer "In8.Cu")
		(net 152)
	)
	(segment
		(start 121.25 138.4)
		(end 121.25 137.8)
		(width 0.256)
		(layer "In8.Cu")
		(net 152)
	)
	(segment
		(start 121.3 138.45)
		(end 121.25 138.4)
		(width 0.256)
		(layer "In8.Cu")
		(net 152)
	)
	(segment
		(start 219.35 110.598)
		(end 219.35 111.75)
		(width 0.38)
		(layer "F.Cu")
		(net 153)
	)
	(segment
		(start 198.0005 144.9995)
		(end 198.5 144.5)
		(width 0.256)
		(layer "F.Cu")
		(net 153)
	)
	(via
		(at 198.5 144.5)
		(size 0.45)
		(drill 0.1)
		(layers "F.Cu" "B.Cu")
		(remove_unused_layers yes)
		(keep_end_layers yes)
		(zone_layer_connections)
		(net 153)
	)
	(via
		(at 219.35 111.75)
		(size 0.45)
		(drill 0.1)
		(layers "F.Cu" "B.Cu")
		(remove_unused_layers yes)
		(keep_end_layers yes)
		(zone_layer_connections)
		(net 153)
	)
	(segment
		(start 196 144.565685)
		(end 196.434315 145)
		(width 0.15)
		(layer "In2.Cu")
		(net 153)
	)
	(segment
		(start 188.626901 115.513478)
		(end 188.251108 115.137685)
		(width 0.15)
		(layer "In2.Cu")
		(net 153)
	)
	(segment
		(start 187.791488 115.597303)
		(end 187.791488 115.597304)
		(width 0.15)
		(layer "In2.Cu")
		(net 153)
	)
	(segment
		(start 187.325 123.275)
		(end 195.0005 130.9505)
		(width 0.15)
		(layer "In2.Cu")
		(net 153)
	)
	(segment
		(start 188.167282 116.432716)
		(end 187.325 117.275)
		(width 0.15)
		(layer "In2.Cu")
		(net 153)
	)
	(segment
		(start 219.3505 111.749499)
		(end 219.3505 112.5995)
		(width 0.15)
		(layer "In2.Cu")
		(net 153)
	)
	(segment
		(start 189.54614 114.594239)
		(end 189.170371 114.21847)
		(width 0.15)
		(layer "In2.Cu")
		(net 153)
	)
	(segment
		(start 196 144.2)
		(end 196 144.565685)
		(width 0.15)
		(layer "In2.Cu")
		(net 153)
	)
	(segment
		(start 190.005759 114.594237)
		(end 190.00576 114.594239)
		(width 0.15)
		(layer "In2.Cu")
		(net 153)
	)
	(segment
		(start 195.0005 143.8005)
		(end 195.2 144)
		(width 0.15)
		(layer "In2.Cu")
		(net 153)
	)
	(segment
		(start 188.710752 114.678088)
		(end 188.710752 114.678089)
		(width 0.15)
		(layer "In2.Cu")
		(net 153)
	)
	(segment
		(start 189.630014 113.758872)
		(end 189.630014 113.758873)
		(width 0.15)
		(layer "In2.Cu")
		(net 153)
	)
	(segment
		(start 195.2 144)
		(end 195.8 144)
		(width 0.15)
		(layer "In2.Cu")
		(net 153)
	)
	(segment
		(start 219.3505 112.5995)
		(end 218.8 113.15)
		(width 0.15)
		(layer "In2.Cu")
		(net 153)
	)
	(segment
		(start 188.710752 114.678089)
		(end 189.08652 115.053857)
		(width 0.15)
		(layer "In2.Cu")
		(net 153)
	)
	(segment
		(start 190.465379 113.675)
		(end 190.089633 113.299254)
		(width 0.15)
		(layer "In2.Cu")
		(net 153)
	)
	(segment
		(start 218.8 113.15)
		(end 191.449999 113.15)
		(width 0.15)
		(layer "In2.Cu")
		(net 153)
	)
	(segment
		(start 195.8 144)
		(end 196 144.2)
		(width 0.15)
		(layer "In2.Cu")
		(net 153)
	)
	(segment
		(start 187.791488 115.597304)
		(end 188.16728 115.973096)
		(width 0.15)
		(layer "In2.Cu")
		(net 153)
	)
	(segment
		(start 190.005758 114.594237)
		(end 190.005759 114.594237)
		(width 0.15)
		(layer "In2.Cu")
		(net 153)
	)
	(segment
		(start 189.08652 115.513477)
		(end 189.086521 115.513478)
		(width 0.15)
		(layer "In2.Cu")
		(net 153)
	)
	(segment
		(start 196.434315 145)
		(end 197.7 145)
		(width 0.15)
		(layer "In2.Cu")
		(net 153)
	)
	(segment
		(start 195.0005 130.9505)
		(end 195.0005 143.8005)
		(width 0.15)
		(layer "In2.Cu")
		(net 153)
	)
	(segment
		(start 198.200001 144.499999)
		(end 198.5 144.499999)
		(width 0.15)
		(layer "In2.Cu")
		(net 153)
	)
	(segment
		(start 188.710751 114.21847)
		(end 188.710752 114.21847)
		(width 0.15)
		(layer "In2.Cu")
		(net 153)
	)
	(segment
		(start 187.325 117.275)
		(end 187.325 123.275)
		(width 0.15)
		(layer "In2.Cu")
		(net 153)
	)
	(segment
		(start 191.449999 113.15)
		(end 190.924999 113.675)
		(width 0.15)
		(layer "In2.Cu")
		(net 153)
	)
	(segment
		(start 189.630014 113.299255)
		(end 189.630014 113.299254)
		(width 0.15)
		(layer "In2.Cu")
		(net 153)
	)
	(segment
		(start 188.16728 116.432716)
		(end 188.167282 116.432716)
		(width 0.15)
		(layer "In2.Cu")
		(net 153)
	)
	(segment
		(start 189.630014 113.758873)
		(end 190.005759 114.134618)
		(width 0.15)
		(layer "In2.Cu")
		(net 153)
	)
	(segment
		(start 197.7 145)
		(end 198.200001 144.499999)
		(width 0.15)
		(layer "In2.Cu")
		(net 153)
	)
	(arc
		(start 190.005759 114.134618)
		(mid 190.100949 114.364428)
		(end 190.005758 114.594237)
		(width 0.15)
		(layer "In2.Cu")
		(net 153)
	)
	(arc
		(start 188.710752 114.21847)
		(mid 188.615562 114.448279)
		(end 188.710752 114.678088)
		(width 0.15)
		(layer "In2.Cu")
		(net 153)
	)
	(arc
		(start 189.086521 115.513478)
		(mid 188.856711 115.608668)
		(end 188.626901 115.513478)
		(width 0.15)
		(layer "In2.Cu")
		(net 153)
	)
	(arc
		(start 189.630014 113.299254)
		(mid 189.534824 113.529063)
		(end 189.630014 113.758872)
		(width 0.15)
		(layer "In2.Cu")
		(net 153)
	)
	(arc
		(start 190.00576 114.594239)
		(mid 189.77595 114.689429)
		(end 189.54614 114.594239)
		(width 0.15)
		(layer "In2.Cu")
		(net 153)
	)
	(arc
		(start 188.251108 115.137685)
		(mid 188.021298 115.042495)
		(end 187.791488 115.137685)
		(width 0.15)
		(layer "In2.Cu")
		(net 153)
	)
	(arc
		(start 189.170371 114.21847)
		(mid 188.940561 114.12328)
		(end 188.710751 114.21847)
		(width 0.15)
		(layer "In2.Cu")
		(net 153)
	)
	(arc
		(start 189.08652 115.053857)
		(mid 189.18171 115.283667)
		(end 189.08652 115.513477)
		(width 0.15)
		(layer "In2.Cu")
		(net 153)
	)
	(arc
		(start 187.791488 115.137685)
		(mid 187.696298 115.367494)
		(end 187.791488 115.597303)
		(width 0.15)
		(layer "In2.Cu")
		(net 153)
	)
	(arc
		(start 188.16728 115.973096)
		(mid 188.26247 116.202906)
		(end 188.16728 116.432716)
		(width 0.15)
		(layer "In2.Cu")
		(net 153)
	)
	(arc
		(start 190.089633 113.299254)
		(mid 189.859823 113.204064)
		(end 189.630014 113.299255)
		(width 0.15)
		(layer "In2.Cu")
		(net 153)
	)
	(arc
		(start 190.924999 113.675)
		(mid 190.695189 113.77019)
		(end 190.465379 113.675)
		(width 0.15)
		(layer "In2.Cu")
		(net 153)
	)
	(segment
		(start 217.65 110.598)
		(end 217.65 111.75)
		(width 0.38)
		(layer "F.Cu")
		(net 154)
	)
	(segment
		(start 197.000499 139.9995)
		(end 197.5 139.5)
		(width 0.256)
		(layer "F.Cu")
		(net 154)
	)
	(via
		(at 197.5 139.5)
		(size 0.45)
		(drill 0.1)
		(layers "F.Cu" "B.Cu")
		(remove_unused_layers yes)
		(keep_end_layers yes)
		(zone_layer_connections)
		(net 154)
	)
	(via
		(at 217.65 111.75)
		(size 0.45)
		(drill 0.1)
		(layers "F.Cu" "B.Cu")
		(remove_unused_layers yes)
		(keep_end_layers yes)
		(zone_layer_connections)
		(net 154)
	)
	(segment
		(start 209.1 115.3)
		(end 211.1 113.3)
		(width 0.148)
		(layer "In6.Cu")
		(net 154)
	)
	(segment
		(start 211.7 107.1)
		(end 212.2 106.6)
		(width 0.148)
		(layer "In6.Cu")
		(net 154)
	)
	(segment
		(start 212.2 106.6)
		(end 215.4 106.6)
		(width 0.148)
		(layer "In6.Cu")
		(net 154)
	)
	(segment
		(start 201.575 115.3)
		(end 209.1 115.3)
		(width 0.148)
		(layer "In6.Cu")
		(net 154)
	)
	(segment
		(start 197.3 138.35)
		(end 197.3 136.925)
		(width 0.148)
		(layer "In6.Cu")
		(net 154)
	)
	(segment
		(start 211.1 113.3)
		(end 211.1 111.2)
		(width 0.148)
		(layer "In6.Cu")
		(net 154)
	)
	(segment
		(start 197.5 138.55)
		(end 197.3 138.35)
		(width 0.148)
		(layer "In6.Cu")
		(net 154)
	)
	(segment
		(start 211.7 110.6)
		(end 211.7 107.1)
		(width 0.148)
		(layer "In6.Cu")
		(net 154)
	)
	(segment
		(start 197.75 136.475)
		(end 197.75 119.125)
		(width 0.148)
		(layer "In6.Cu")
		(net 154)
	)
	(segment
		(start 197.5 139.5)
		(end 197.5 138.55)
		(width 0.148)
		(layer "In6.Cu")
		(net 154)
	)
	(segment
		(start 197.3 136.925)
		(end 197.75 136.475)
		(width 0.148)
		(layer "In6.Cu")
		(net 154)
	)
	(segment
		(start 197.75 119.125)
		(end 201.575 115.3)
		(width 0.148)
		(layer "In6.Cu")
		(net 154)
	)
	(segment
		(start 215.4 106.6)
		(end 217.65 108.85)
		(width 0.148)
		(layer "In6.Cu")
		(net 154)
	)
	(segment
		(start 211.1 111.2)
		(end 211.7 110.6)
		(width 0.148)
		(layer "In6.Cu")
		(net 154)
	)
	(segment
		(start 217.65 108.85)
		(end 217.65 111.75)
		(width 0.148)
		(layer "In6.Cu")
		(net 154)
	)
	(segment
		(start 215.95 110.598)
		(end 215.95 111.75)
		(width 0.38)
		(layer "F.Cu")
		(net 155)
	)
	(segment
		(start 201.0005 140.9995)
		(end 201.5 140.5)
		(width 0.256)
		(layer "F.Cu")
		(net 155)
	)
	(via
		(at 201.5 140.5)
		(size 0.45)
		(drill 0.1)
		(layers "F.Cu" "B.Cu")
		(remove_unused_layers yes)
		(keep_end_layers yes)
		(zone_layer_connections)
		(net 155)
	)
	(via
		(at 215.95 111.75)
		(size 0.45)
		(drill 0.1)
		(layers "F.Cu" "B.Cu")
		(remove_unused_layers yes)
		(keep_end_layers yes)
		(zone_layer_connections)
		(net 155)
	)
	(segment
		(start 216.926954 119.548043)
		(end 216.926955 119.548042)
		(width 0.148)
		(layer "In6.Cu")
		(net 155)
	)
	(segment
		(start 216.007715 120.467281)
		(end 216.007715 120.467282)
		(width 0.148)
		(layer "In6.Cu")
		(net 155)
	)
	(segment
		(start 215.088476 121.38652)
		(end 215.088476 121.386521)
		(width 0.148)
		(layer "In6.Cu")
		(net 155)
	)
	(segment
		(start 213.709619 123.225)
		(end 214.461042 123.976423)
		(width 0.148)
		(layer "In6.Cu")
		(net 155)
	)
	(segment
		(start 214.169237 122.30576)
		(end 214.169239 122.305761)
		(width 0.148)
		(layer "In6.Cu")
		(net 155)
	)
	(segment
		(start 204.125 127.975)
		(end 208.4875 123.6125)
		(width 0.148)
		(layer "In6.Cu")
		(net 155)
	)
	(segment
		(start 208.4875 123.6125)
		(end 212.8625 123.6125)
		(width 0.148)
		(layer "In6.Cu")
		(net 155)
	)
	(segment
		(start 212.8625 123.6125)
		(end 213.25 123.225)
		(width 0.148)
		(layer "In6.Cu")
		(net 155)
	)
	(segment
		(start 214.920661 123.516803)
		(end 214.169237 122.765379)
		(width 0.148)
		(layer "In6.Cu")
		(net 155)
	)
	(segment
		(start 213.709618 123.225)
		(end 213.709619 123.225)
		(width 0.148)
		(layer "In6.Cu")
		(net 155)
	)
	(segment
		(start 214.169238 122.30576)
		(end 214.169237 122.30576)
		(width 0.148)
		(layer "In6.Cu")
		(net 155)
	)
	(segment
		(start 214.920661 123.976422)
		(end 214.920661 123.976423)
		(width 0.148)
		(layer "In6.Cu")
		(net 155)
	)
	(segment
		(start 217.175 112.4)
		(end 216.525 111.75)
		(width 0.148)
		(layer "In6.Cu")
		(net 155)
	)
	(segment
		(start 216.007715 120.467282)
		(end 216.007717 120.467283)
		(width 0.148)
		(layer "In6.Cu")
		(net 155)
	)
	(segment
		(start 215.548096 121.386522)
		(end 215.548097 121.386522)
		(width 0.148)
		(layer "In6.Cu")
		(net 155)
	)
	(segment
		(start 215.839941 122.597605)
		(end 215.088476 121.84614)
		(width 0.148)
		(layer "In6.Cu")
		(net 155)
	)
	(segment
		(start 216.75918 121.678366)
		(end 216.007715 120.926901)
		(width 0.148)
		(layer "In6.Cu")
		(net 155)
	)
	(segment
		(start 217.678362 121.218691)
		(end 217.678363 121.21869)
		(width 0.148)
		(layer "In6.Cu")
		(net 155)
	)
	(segment
		(start 216.525 111.75)
		(end 215.95 111.75)
		(width 0.148)
		(layer "In6.Cu")
		(net 155)
	)
	(segment
		(start 216.759181 122.137986)
		(end 216.75918 122.137986)
		(width 0.148)
		(layer "In6.Cu")
		(net 155)
	)
	(segment
		(start 217.678363 120.75907)
		(end 216.926955 120.007662)
		(width 0.148)
		(layer "In6.Cu")
		(net 155)
	)
	(segment
		(start 216.926955 119.548042)
		(end 217.175 119.3)
		(width 0.148)
		(layer "In6.Cu")
		(net 155)
	)
	(segment
		(start 215.548097 121.386522)
		(end 216.299561 122.137986)
		(width 0.148)
		(layer "In6.Cu")
		(net 155)
	)
	(segment
		(start 214.628857 122.305761)
		(end 214.628858 122.305761)
		(width 0.148)
		(layer "In6.Cu")
		(net 155)
	)
	(segment
		(start 201.5 140.5)
		(end 204.125 137.875)
		(width 0.148)
		(layer "In6.Cu")
		(net 155)
	)
	(segment
		(start 214.628858 122.305761)
		(end 215.380322 123.057225)
		(width 0.148)
		(layer "In6.Cu")
		(net 155)
	)
	(segment
		(start 216.467335 120.467283)
		(end 216.467336 120.467283)
		(width 0.148)
		(layer "In6.Cu")
		(net 155)
	)
	(segment
		(start 204.125 137.875)
		(end 204.125 127.975)
		(width 0.148)
		(layer "In6.Cu")
		(net 155)
	)
	(segment
		(start 216.467336 120.467283)
		(end 217.218743 121.21869)
		(width 0.148)
		(layer "In6.Cu")
		(net 155)
	)
	(segment
		(start 215.839942 123.057225)
		(end 215.839941 123.057225)
		(width 0.148)
		(layer "In6.Cu")
		(net 155)
	)
	(segment
		(start 217.175 119.3)
		(end 217.175 112.4)
		(width 0.148)
		(layer "In6.Cu")
		(net 155)
	)
	(segment
		(start 215.088476 121.386521)
		(end 215.088478 121.386522)
		(width 0.148)
		(layer "In6.Cu")
		(net 155)
	)
	(arc
		(start 217.218743 121.21869)
		(mid 217.448552 121.313881)
		(end 217.678362 121.218691)
		(width 0.148)
		(layer "In6.Cu")
		(net 155)
	)
	(arc
		(start 215.839941 123.057225)
		(mid 215.935131 122.827415)
		(end 215.839941 122.597605)
		(width 0.148)
		(layer "In6.Cu")
		(net 155)
	)
	(arc
		(start 215.088476 121.84614)
		(mid 214.993286 121.61633)
		(end 215.088476 121.38652)
		(width 0.148)
		(layer "In6.Cu")
		(net 155)
	)
	(arc
		(start 216.299561 122.137986)
		(mid 216.529371 122.233176)
		(end 216.759181 122.137986)
		(width 0.148)
		(layer "In6.Cu")
		(net 155)
	)
	(arc
		(start 217.678363 121.21869)
		(mid 217.773553 120.98888)
		(end 217.678363 120.75907)
		(width 0.148)
		(layer "In6.Cu")
		(net 155)
	)
	(arc
		(start 215.380322 123.057225)
		(mid 215.610132 123.152415)
		(end 215.839942 123.057225)
		(width 0.148)
		(layer "In6.Cu")
		(net 155)
	)
	(arc
		(start 216.75918 122.137986)
		(mid 216.85437 121.908176)
		(end 216.75918 121.678366)
		(width 0.148)
		(layer "In6.Cu")
		(net 155)
	)
	(arc
		(start 215.088478 121.386522)
		(mid 215.318287 121.291332)
		(end 215.548096 121.386522)
		(width 0.148)
		(layer "In6.Cu")
		(net 155)
	)
	(arc
		(start 214.169237 122.765379)
		(mid 214.074047 122.535569)
		(end 214.169238 122.30576)
		(width 0.148)
		(layer "In6.Cu")
		(net 155)
	)
	(arc
		(start 216.926955 120.007662)
		(mid 216.831764 119.777853)
		(end 216.926954 119.548043)
		(width 0.148)
		(layer "In6.Cu")
		(net 155)
	)
	(arc
		(start 214.461042 123.976423)
		(mid 214.690852 124.071613)
		(end 214.920661 123.976422)
		(width 0.148)
		(layer "In6.Cu")
		(net 155)
	)
	(arc
		(start 216.007715 120.926901)
		(mid 215.912525 120.697091)
		(end 216.007715 120.467281)
		(width 0.148)
		(layer "In6.Cu")
		(net 155)
	)
	(arc
		(start 214.920661 123.976423)
		(mid 215.015851 123.746613)
		(end 214.920661 123.516803)
		(width 0.148)
		(layer "In6.Cu")
		(net 155)
	)
	(arc
		(start 216.007717 120.467283)
		(mid 216.237526 120.372093)
		(end 216.467335 120.467283)
		(width 0.148)
		(layer "In6.Cu")
		(net 155)
	)
	(arc
		(start 213.25 123.225)
		(mid 213.479809 123.12981)
		(end 213.709618 123.225)
		(width 0.148)
		(layer "In6.Cu")
		(net 155)
	)
	(arc
		(start 214.169239 122.305761)
		(mid 214.399048 122.210571)
		(end 214.628857 122.305761)
		(width 0.148)
		(layer "In6.Cu")
		(net 155)
	)
	(segment
		(start 130.95 106)
		(end 130.95 107.152)
		(width 0.38)
		(layer "F.Cu")
		(net 156)
	)
	(segment
		(start 179.9995 140.9995)
		(end 179.499999 140.5)
		(width 0.256)
		(layer "F.Cu")
		(net 156)
	)
	(via
		(at 130.95 107.152)
		(size 0.45)
		(drill 0.1)
		(layers "F.Cu" "B.Cu")
		(remove_unused_layers yes)
		(keep_end_layers yes)
		(zone_layer_connections)
		(net 156)
	)
	(via
		(at 179.499999 140.5)
		(size 0.45)
		(drill 0.1)
		(layers "F.Cu" "B.Cu")
		(remove_unused_layers yes)
		(keep_end_layers yes)
		(zone_layer_connections)
		(net 156)
	)
	(segment
		(start 139.209852 120.584464)
		(end 139.124998 120.669317)
		(width 0.13)
		(layer "In2.Cu")
		(net 156)
	)
	(segment
		(start 155.499706 137.28)
		(end 179.199706 137.28)
		(width 0.13)
		(layer "In2.Cu")
		(net 156)
	)
	(segment
		(start 130.799706 109.955)
		(end 131.424706 109.955)
		(width 0.13)
		(layer "In2.Cu")
		(net 156)
	)
	(segment
		(start 142.061848 122.642143)
		(end 153.57 134.150294)
		(width 0.13)
		(layer "In2.Cu")
		(net 156)
	)
	(segment
		(start 139.209852 120.584463)
		(end 139.209852 120.584464)
		(width 0.13)
		(layer "In2.Cu")
		(net 156)
	)
	(segment
		(start 141.182678 122.726997)
		(end 141.267531 122.642143)
		(width 0.13)
		(layer "In2.Cu")
		(net 156)
	)
	(segment
		(start 131.424706 109.955)
		(end 131.92 110.450294)
		(width 0.13)
		(layer "In2.Cu")
		(net 156)
	)
	(segment
		(start 179.499999 140.200001)
		(end 179.6 140.1)
		(width 0.1)
		(layer "In2.Cu")
		(net 156)
	)
	(segment
		(start 131.92 114.400294)
		(end 134.099706 116.58)
		(width 0.13)
		(layer "In2.Cu")
		(net 156)
	)
	(segment
		(start 180.1 139.082794)
		(end 180.113559 139.069235)
		(width 0.1)
		(layer "In2.Cu")
		(net 156)
	)
	(segment
		(start 179.6 140.1)
		(end 179.826831 140.1)
		(width 0.1)
		(layer "In2.Cu")
		(net 156)
	)
	(segment
		(start 137.649706 119.43)
		(end 138.460994 119.43)
		(width 0.13)
		(layer "In2.Cu")
		(net 156)
	)
	(segment
		(start 130.37 109.525294)
		(end 130.799706 109.955)
		(width 0.13)
		(layer "In2.Cu")
		(net 156)
	)
	(segment
		(start 179.826831 140.1)
		(end 180.1 139.826831)
		(width 0.1)
		(layer "In2.Cu")
		(net 156)
	)
	(segment
		(start 130.37 108.824706)
		(end 130.37 109.525294)
		(width 0.13)
		(layer "In2.Cu")
		(net 156)
	)
	(segment
		(start 139.124572 119.704866)
		(end 139.209852 119.790147)
		(width 0.13)
		(layer "In2.Cu")
		(net 156)
	)
	(segment
		(start 139.124998 121.124223)
		(end 139.242848 121.242073)
		(width 0.13)
		(layer "In2.Cu")
		(net 156)
	)
	(segment
		(start 142.061849 122.642143)
		(end 142.061848 122.642143)
		(width 0.13)
		(layer "In2.Cu")
		(net 156)
	)
	(segment
		(start 180.1 139.826831)
		(end 180.1 139.082794)
		(width 0.1)
		(layer "In2.Cu")
		(net 156)
	)
	(segment
		(start 140.576924 121.157219)
		(end 140.694776 121.275071)
		(width 0.13)
		(layer "In2.Cu")
		(net 156)
	)
	(segment
		(start 130.645 108.549706)
		(end 130.37 108.824706)
		(width 0.13)
		(layer "In2.Cu")
		(net 156)
	)
	(segment
		(start 179.199706 137.28)
		(end 180.113559 138.193853)
		(width 0.13)
		(layer "In2.Cu")
		(net 156)
	)
	(segment
		(start 134.799706 116.58)
		(end 137.649706 119.43)
		(width 0.13)
		(layer "In2.Cu")
		(net 156)
	)
	(segment
		(start 153.57 135.350294)
		(end 155.499706 137.28)
		(width 0.13)
		(layer "In2.Cu")
		(net 156)
	)
	(segment
		(start 153.57 134.150294)
		(end 153.57 135.350294)
		(width 0.13)
		(layer "In2.Cu")
		(net 156)
	)
	(segment
		(start 179.499999 140.5)
		(end 179.499999 140.200001)
		(width 0.1)
		(layer "In2.Cu")
		(net 156)
	)
	(segment
		(start 140.694776 122.069388)
		(end 140.609922 122.154241)
		(width 0.13)
		(layer "In2.Cu")
		(net 156)
	)
	(segment
		(start 140.576925 121.157219)
		(end 140.576924 121.157219)
		(width 0.13)
		(layer "In2.Cu")
		(net 156)
	)
	(segment
		(start 131.92 110.450294)
		(end 131.92 114.400294)
		(width 0.13)
		(layer "In2.Cu")
		(net 156)
	)
	(segment
		(start 130.95 107.152)
		(end 130.645 107.457)
		(width 0.13)
		(layer "In2.Cu")
		(net 156)
	)
	(segment
		(start 140.694776 122.069387)
		(end 140.694776 122.069388)
		(width 0.13)
		(layer "In2.Cu")
		(net 156)
	)
	(segment
		(start 140.609922 122.609147)
		(end 140.727772 122.726997)
		(width 0.13)
		(layer "In2.Cu")
		(net 156)
	)
	(segment
		(start 180.113559 138.193853)
		(end 180.113559 139.069235)
		(width 0.13)
		(layer "In2.Cu")
		(net 156)
	)
	(segment
		(start 130.645 107.457)
		(end 130.645 108.549706)
		(width 0.13)
		(layer "In2.Cu")
		(net 156)
	)
	(segment
		(start 139.697754 121.242073)
		(end 139.782607 121.157219)
		(width 0.13)
		(layer "In2.Cu")
		(net 156)
	)
	(segment
		(start 134.099706 116.58)
		(end 134.799706 116.58)
		(width 0.13)
		(layer "In2.Cu")
		(net 156)
	)
	(arc
		(start 138.460994 119.43)
		(mid 138.82012 119.501435)
		(end 139.124572 119.704866)
		(width 0.13)
		(layer "In2.Cu")
		(net 156)
	)
	(arc
		(start 140.694776 121.275071)
		(mid 140.859284 121.672229)
		(end 140.694776 122.069387)
		(width 0.13)
		(layer "In2.Cu")
		(net 156)
	)
	(arc
		(start 140.727772 122.726997)
		(mid 140.955225 122.821211)
		(end 141.182678 122.726997)
		(width 0.13)
		(layer "In2.Cu")
		(net 156)
	)
	(arc
		(start 141.267531 122.642143)
		(mid 141.66469 122.477634)
		(end 142.061849 122.642143)
		(width 0.13)
		(layer "In2.Cu")
		(net 156)
	)
	(arc
		(start 139.242848 121.242073)
		(mid 139.470301 121.336287)
		(end 139.697754 121.242073)
		(width 0.13)
		(layer "In2.Cu")
		(net 156)
	)
	(arc
		(start 139.782607 121.157219)
		(mid 140.179766 120.99271)
		(end 140.576925 121.157219)
		(width 0.13)
		(layer "In2.Cu")
		(net 156)
	)
	(arc
		(start 139.209852 119.790147)
		(mid 139.37436 120.187305)
		(end 139.209852 120.584463)
		(width 0.13)
		(layer "In2.Cu")
		(net 156)
	)
	(arc
		(start 140.609922 122.154241)
		(mid 140.515708 122.381694)
		(end 140.609922 122.609147)
		(width 0.13)
		(layer "In2.Cu")
		(net 156)
	)
	(arc
		(start 139.124998 120.669317)
		(mid 139.030784 120.89677)
		(end 139.124998 121.124223)
		(width 0.13)
		(layer "In2.Cu")
		(net 156)
	)
	(segment
		(start 253.010499 132.717)
		(end 252.227499 132.717)
		(width 0.15)
		(layer "F.Cu")
		(net 157)
	)
	(segment
		(start 252.227499 132.717)
		(end 252.174499 132.664)
		(width 0.15)
		(layer "F.Cu")
		(net 157)
	)
	(segment
		(start 241.001 139.101)
		(end 240 139.101)
		(width 0.256)
		(layer "F.Cu")
		(net 157)
	)
	(via
		(at 240 139.101)
		(size 0.45)
		(drill 0.1)
		(layers "F.Cu" "B.Cu")
		(remove_unused_layers yes)
		(keep_end_layers yes)
		(zone_layer_connections)
		(net 157)
	)
	(via
		(at 252.174499 132.664)
		(size 0.45)
		(drill 0.1)
		(layers "F.Cu" "B.Cu")
		(remove_unused_layers yes)
		(keep_end_layers yes)
		(zone_layer_connections)
		(net 157)
	)
	(segment
		(start 252.909499 132.684)
		(end 252.924499 132.684)
		(width 0.1)
		(layer "B.Cu")
		(net 157)
	)
	(segment
		(start 252.174499 132.664)
		(end 252.889499 132.664)
		(width 0.256)
		(layer "B.Cu")
		(net 157)
	)
	(segment
		(start 252.889499 132.664)
		(end 252.909499 132.684)
		(width 0.1)
		(layer "B.Cu")
		(net 157)
	)
	(segment
		(start 240.575 138.526)
		(end 245.167667 138.526)
		(width 0.1)
		(layer "In2.Cu")
		(net 157)
	)
	(segment
		(start 245.167667 138.526)
		(end 251.029667 132.664)
		(width 0.1)
		(layer "In2.Cu")
		(net 157)
	)
	(segment
		(start 240 139.101)
		(end 240.575 138.526)
		(width 0.1)
		(layer "In2.Cu")
		(net 157)
	)
	(segment
		(start 251.029667 132.664)
		(end 252.174499 132.664)
		(width 0.1)
		(layer "In2.Cu")
		(net 157)
	)
	(segment
		(start 258.174 148.15)
		(end 258.176 148.148)
		(width 0.1)
		(layer "F.Cu")
		(net 158)
	)
	(segment
		(start 257.393 148.15)
		(end 258.174 148.15)
		(width 0.1)
		(layer "F.Cu")
		(net 158)
	)
	(segment
		(start 258.624499 162.424)
		(end 257.853002 162.424)
		(width 0.1)
		(layer "F.Cu")
		(net 159)
	)
	(segment
		(start 257.853002 162.424)
		(end 257.853 162.423998)
		(width 0.1)
		(layer "F.Cu")
		(net 159)
	)
	(segment
		(start 206.341 149.9)
		(end 206.9815 149.9)
		(width 0.4)
		(layer "F.Cu")
		(net 160)
	)
	(segment
		(start 206.9815 149.9)
		(end 206.991 149.9095)
		(width 0.4)
		(layer "F.Cu")
		(net 160)
	)
	(via
		(at 206.991 149.9095)
		(size 0.45)
		(drill 0.1)
		(layers "F.Cu" "B.Cu")
		(remove_unused_layers yes)
		(keep_end_layers yes)
		(zone_layer_connections)
		(net 160)
	)
	(segment
		(start 206.991 150.139)
		(end 206.991 149.9095)
		(width 0.4)
		(layer "B.Cu")
		(net 160)
	)
	(segment
		(start 206.33 150.8)
		(end 206.64 150.49)
		(width 0.114)
		(layer "B.Cu")
		(net 160)
	)
	(segment
		(start 205.95 150.8)
		(end 206.33 150.8)
		(width 0.114)
		(layer "B.Cu")
		(net 160)
	)
	(segment
		(start 206.64 150.49)
		(end 206.991 150.139)
		(width 0.4)
		(layer "B.Cu")
		(net 160)
	)
	(segment
		(start 179.9995 139.9995)
		(end 179.5 139.5)
		(width 0.256)
		(layer "F.Cu")
		(net 161)
	)
	(segment
		(start 130.1 106)
		(end 130.1 107.152)
		(width 0.38)
		(layer "F.Cu")
		(net 161)
	)
	(via
		(at 130.1 107.152)
		(size 0.45)
		(drill 0.1)
		(layers "F.Cu" "B.Cu")
		(remove_unused_layers yes)
		(keep_end_layers yes)
		(zone_layer_connections)
		(net 161)
	)
	(via
		(at 179.5 139.5)
		(size 0.45)
		(drill 0.1)
		(layers "F.Cu" "B.Cu")
		(remove_unused_layers yes)
		(keep_end_layers yes)
		(zone_layer_connections)
		(net 161)
	)
	(segment
		(start 179.5 139.8)
		(end 179.6 139.9)
		(width 0.1)
		(layer "In2.Cu")
		(net 161)
	)
	(segment
		(start 139.040147 120.414758)
		(end 138.955293 120.499611)
		(width 0.13)
		(layer "In2.Cu")
		(net 161)
	)
	(segment
		(start 139.86746 121.411778)
		(end 139.952313 121.326924)
		(width 0.13)
		(layer "In2.Cu")
		(net 161)
	)
	(segment
		(start 179.685121 138.104827)
		(end 179.873559 138.293265)
		(width 0.13)
		(layer "In2.Cu")
		(net 161)
	)
	(segment
		(start 138.969964 119.889669)
		(end 139.040147 119.959852)
		(width 0.13)
		(layer "In2.Cu")
		(net 161)
	)
	(segment
		(start 153.33 135.449706)
		(end 155.400294 137.52)
		(width 0.13)
		(layer "In2.Cu")
		(net 161)
	)
	(segment
		(start 130.1 107.152)
		(end 130.405 107.457)
		(width 0.13)
		(layer "In2.Cu")
		(net 161)
	)
	(segment
		(start 141.352384 122.896702)
		(end 141.437237 122.811848)
		(width 0.13)
		(layer "In2.Cu")
		(net 161)
	)
	(segment
		(start 130.405 107.457)
		(end 130.405 108.450294)
		(width 0.13)
		(layer "In2.Cu")
		(net 161)
	)
	(segment
		(start 140.440217 122.778852)
		(end 140.558067 122.896702)
		(width 0.13)
		(layer "In2.Cu")
		(net 161)
	)
	(segment
		(start 131.325294 110.195)
		(end 131.68 110.549706)
		(width 0.13)
		(layer "In2.Cu")
		(net 161)
	)
	(segment
		(start 140.440217 122.778853)
		(end 140.440217 122.778852)
		(width 0.13)
		(layer "In2.Cu")
		(net 161)
	)
	(segment
		(start 179.5 139.5)
		(end 179.5 139.8)
		(width 0.1)
		(layer "In2.Cu")
		(net 161)
	)
	(segment
		(start 140.525071 121.444777)
		(end 140.525071 121.444776)
		(width 0.13)
		(layer "In2.Cu")
		(net 161)
	)
	(segment
		(start 179.743987 139.9)
		(end 179.9 139.743987)
		(width 0.1)
		(layer "In2.Cu")
		(net 161)
	)
	(segment
		(start 131.68 110.549706)
		(end 131.68 114.499706)
		(width 0.13)
		(layer "In2.Cu")
		(net 161)
	)
	(segment
		(start 139.86746 121.411779)
		(end 139.86746 121.411778)
		(width 0.13)
		(layer "In2.Cu")
		(net 161)
	)
	(segment
		(start 131.68 114.499706)
		(end 134.000294 116.82)
		(width 0.13)
		(layer "In2.Cu")
		(net 161)
	)
	(segment
		(start 179.190146 137.821986)
		(end 179.190147 137.821985)
		(width 0.13)
		(layer "In2.Cu")
		(net 161)
	)
	(segment
		(start 153.33 134.249706)
		(end 153.33 135.449706)
		(width 0.13)
		(layer "In2.Cu")
		(net 161)
	)
	(segment
		(start 130.13 108.725294)
		(end 130.13 109.624706)
		(width 0.13)
		(layer "In2.Cu")
		(net 161)
	)
	(segment
		(start 138.955293 121.293929)
		(end 138.955293 121.293928)
		(width 0.13)
		(layer "In2.Cu")
		(net 161)
	)
	(segment
		(start 134.700294 116.82)
		(end 137.550294 119.67)
		(width 0.13)
		(layer "In2.Cu")
		(net 161)
	)
	(segment
		(start 130.700294 110.195)
		(end 131.325294 110.195)
		(width 0.13)
		(layer "In2.Cu")
		(net 161)
	)
	(segment
		(start 179.190147 138.034117)
		(end 179.260857 138.104827)
		(width 0.13)
		(layer "In2.Cu")
		(net 161)
	)
	(segment
		(start 179.9 139.743987)
		(end 179.9 139.095676)
		(width 0.1)
		(layer "In2.Cu")
		(net 161)
	)
	(segment
		(start 141.892143 122.811848)
		(end 142.009995 122.929701)
		(width 0.13)
		(layer "In2.Cu")
		(net 161)
	)
	(segment
		(start 138.955293 121.293928)
		(end 139.073143 121.411778)
		(width 0.13)
		(layer "In2.Cu")
		(net 161)
	)
	(segment
		(start 137.550294 119.67)
		(end 138.439635 119.67)
		(width 0.13)
		(layer "In2.Cu")
		(net 161)
	)
	(segment
		(start 179.6 139.9)
		(end 179.743987 139.9)
		(width 0.1)
		(layer "In2.Cu")
		(net 161)
	)
	(segment
		(start 140.525071 121.899682)
		(end 140.440217 121.984535)
		(width 0.13)
		(layer "In2.Cu")
		(net 161)
	)
	(segment
		(start 155.400294 137.52)
		(end 179.100294 137.52)
		(width 0.13)
		(layer "In2.Cu")
		(net 161)
	)
	(segment
		(start 130.405 108.450294)
		(end 130.13 108.725294)
		(width 0.13)
		(layer "In2.Cu")
		(net 161)
	)
	(segment
		(start 140.407219 121.326924)
		(end 140.525071 121.444777)
		(width 0.13)
		(layer "In2.Cu")
		(net 161)
	)
	(segment
		(start 179.100294 137.52)
		(end 179.190147 137.609853)
		(width 0.13)
		(layer "In2.Cu")
		(net 161)
	)
	(segment
		(start 179.873559 138.293265)
		(end 179.873559 139.069235)
		(width 0.13)
		(layer "In2.Cu")
		(net 161)
	)
	(segment
		(start 179.9 139.095676)
		(end 179.873559 139.069235)
		(width 0.1)
		(layer "In2.Cu")
		(net 161)
	)
	(segment
		(start 142.009995 122.929701)
		(end 153.33 134.249706)
		(width 0.13)
		(layer "In2.Cu")
		(net 161)
	)
	(segment
		(start 141.352384 122.896703)
		(end 141.352384 122.896702)
		(width 0.13)
		(layer "In2.Cu")
		(net 161)
	)
	(segment
		(start 134.000294 116.82)
		(end 134.700294 116.82)
		(width 0.13)
		(layer "In2.Cu")
		(net 161)
	)
	(segment
		(start 130.13 109.624706)
		(end 130.700294 110.195)
		(width 0.13)
		(layer "In2.Cu")
		(net 161)
	)
	(arc
		(start 140.440217 121.984535)
		(mid 140.275708 122.381694)
		(end 140.440217 122.778853)
		(width 0.13)
		(layer "In2.Cu")
		(net 161)
	)
	(arc
		(start 138.439635 119.67)
		(mid 138.726647 119.72709)
		(end 138.969964 119.889669)
		(width 0.13)
		(layer "In2.Cu")
		(net 161)
	)
	(arc
		(start 139.073143 121.411778)
		(mid 139.470301 121.576287)
		(end 139.86746 121.411779)
		(width 0.13)
		(layer "In2.Cu")
		(net 161)
	)
	(arc
		(start 141.437237 122.811848)
		(mid 141.66469 122.717634)
		(end 141.892143 122.811848)
		(width 0.13)
		(layer "In2.Cu")
		(net 161)
	)
	(arc
		(start 140.558067 122.896702)
		(mid 140.955225 123.061211)
		(end 141.352384 122.896703)
		(width 0.13)
		(layer "In2.Cu")
		(net 161)
	)
	(arc
		(start 139.952313 121.326924)
		(mid 140.179766 121.23271)
		(end 140.407219 121.326924)
		(width 0.13)
		(layer "In2.Cu")
		(net 161)
	)
	(arc
		(start 179.190147 137.609853)
		(mid 179.234081 137.71592)
		(end 179.190146 137.821986)
		(width 0.13)
		(layer "In2.Cu")
		(net 161)
	)
	(arc
		(start 140.525071 121.444776)
		(mid 140.619285 121.672229)
		(end 140.525071 121.899682)
		(width 0.13)
		(layer "In2.Cu")
		(net 161)
	)
	(arc
		(start 138.955293 120.499611)
		(mid 138.790784 120.89677)
		(end 138.955293 121.293929)
		(width 0.13)
		(layer "In2.Cu")
		(net 161)
	)
	(arc
		(start 179.260857 138.104827)
		(mid 179.366923 138.148761)
		(end 179.472989 138.104827)
		(width 0.13)
		(layer "In2.Cu")
		(net 161)
	)
	(arc
		(start 179.190147 137.821985)
		(mid 179.146213 137.928051)
		(end 179.190147 138.034117)
		(width 0.13)
		(layer "In2.Cu")
		(net 161)
	)
	(arc
		(start 139.040147 119.959852)
		(mid 139.134361 120.187305)
		(end 139.040147 120.414758)
		(width 0.13)
		(layer "In2.Cu")
		(net 161)
	)
	(arc
		(start 179.472989 138.104827)
		(mid 179.579055 138.060893)
		(end 179.685121 138.104827)
		(width 0.13)
		(layer "In2.Cu")
		(net 161)
	)
	(segment
		(start 199.0005 140.9995)
		(end 199.5 140.5)
		(width 0.256)
		(layer "F.Cu")
		(net 162)
	)
	(segment
		(start 211.7 110.598)
		(end 211.7 111.75)
		(width 0.38)
		(layer "F.Cu")
		(net 162)
	)
	(via
		(at 211.7 111.75)
		(size 0.45)
		(drill 0.1)
		(layers "F.Cu" "B.Cu")
		(remove_unused_layers yes)
		(keep_end_layers yes)
		(zone_layer_connections)
		(net 162)
	)
	(via
		(at 199.5 140.5)
		(size 0.45)
		(drill 0.1)
		(layers "F.Cu" "B.Cu")
		(remove_unused_layers yes)
		(keep_end_layers yes)
		(zone_layer_connections)
		(net 162)
	)
	(segment
		(start 207.575 117.575)
		(end 207.575 116.975)
		(width 0.148)
		(layer "In6.Cu")
		(net 162)
	)
	(segment
		(start 201.231307 120.704961)
		(end 201.231306 120.704962)
		(width 0.148)
		(layer "In6.Cu")
		(net 162)
	)
	(segment
		(start 206.675 116.975)
		(end 206.675 117.575)
		(width 0.148)
		(layer "In6.Cu")
		(net 162)
	)
	(segment
		(start 201.231306 119.891789)
		(end 200.488843 119.149326)
		(width 0.148)
		(layer "In6.Cu")
		(net 162)
	)
	(segment
		(start 198 139.65)
		(end 198 137.5)
		(width 0.148)
		(layer "In6.Cu")
		(net 162)
	)
	(segment
		(start 201.302018 118.336154)
		(end 202.04448 119.078616)
		(width 0.148)
		(layer "In6.Cu")
		(net 162)
	)
	(segment
		(start 209.575 116.525)
		(end 212.1 114)
		(width 0.148)
		(layer "In6.Cu")
		(net 162)
	)
	(segment
		(start 212.1 112.15)
		(end 211.7 111.75)
		(width 0.148)
		(layer "In6.Cu")
		(net 162)
	)
	(segment
		(start 200.488844 118.336153)
		(end 200.488843 118.336154)
		(width 0.148)
		(layer "In6.Cu")
		(net 162)
	)
	(segment
		(start 199.275 121.475)
		(end 199.125 121.475)
		(width 0.148)
		(layer "In6.Cu")
		(net 162)
	)
	(segment
		(start 199.675672 119.9625)
		(end 200.418134 120.704962)
		(width 0.148)
		(layer "In6.Cu")
		(net 162)
	)
	(segment
		(start 199 140)
		(end 198.35 140)
		(width 0.148)
		(layer "In6.Cu")
		(net 162)
	)
	(segment
		(start 199.125 122.325)
		(end 199.275 122.325)
		(width 0.148)
		(layer "In6.Cu")
		(net 162)
	)
	(segment
		(start 200.488843 118.336154)
		(end 200.488846 118.336154)
		(width 0.148)
		(layer "In6.Cu")
		(net 162)
	)
	(segment
		(start 204.975 116.525)
		(end 206.225 116.525)
		(width 0.148)
		(layer "In6.Cu")
		(net 162)
	)
	(segment
		(start 208.025 116.525)
		(end 209.575 116.525)
		(width 0.148)
		(layer "In6.Cu")
		(net 162)
	)
	(segment
		(start 212.1 114)
		(end 212.1 112.15)
		(width 0.148)
		(layer "In6.Cu")
		(net 162)
	)
	(segment
		(start 198.7 136.8)
		(end 198.7 122.75)
		(width 0.148)
		(layer "In6.Cu")
		(net 162)
	)
	(segment
		(start 198.7 120.125)
		(end 198.8625 119.9625)
		(width 0.148)
		(layer "In6.Cu")
		(net 162)
	)
	(segment
		(start 202.857652 118.265443)
		(end 202.115189 117.52298)
		(width 0.148)
		(layer "In6.Cu")
		(net 162)
	)
	(segment
		(start 199.5 140.5)
		(end 199 140)
		(width 0.148)
		(layer "In6.Cu")
		(net 162)
	)
	(segment
		(start 198 137.5)
		(end 198.7 136.8)
		(width 0.148)
		(layer "In6.Cu")
		(net 162)
	)
	(segment
		(start 202.11519 116.709807)
		(end 202.3 116.525)
		(width 0.148)
		(layer "In6.Cu")
		(net 162)
	)
	(segment
		(start 198.35 140)
		(end 198 139.65)
		(width 0.148)
		(layer "In6.Cu")
		(net 162)
	)
	(segment
		(start 204.55 117.1)
		(end 204.55 116.95)
		(width 0.148)
		(layer "In6.Cu")
		(net 162)
	)
	(segment
		(start 202.857652 118.265442)
		(end 202.857652 118.265443)
		(width 0.148)
		(layer "In6.Cu")
		(net 162)
	)
	(segment
		(start 202.857653 119.078615)
		(end 202.857652 119.078616)
		(width 0.148)
		(layer "In6.Cu")
		(net 162)
	)
	(segment
		(start 201.231306 119.891788)
		(end 201.231306 119.891789)
		(width 0.148)
		(layer "In6.Cu")
		(net 162)
	)
	(segment
		(start 203.7 116.95)
		(end 203.7 117.1)
		(width 0.148)
		(layer "In6.Cu")
		(net 162)
	)
	(segment
		(start 198.7 121.05)
		(end 198.7 120.125)
		(width 0.148)
		(layer "In6.Cu")
		(net 162)
	)
	(segment
		(start 202.3 116.525)
		(end 203.275 116.525)
		(width 0.148)
		(layer "In6.Cu")
		(net 162)
	)
	(arc
		(start 198.7 122.75)
		(mid 198.82448 122.44948)
		(end 199.125 122.325)
		(width 0.148)
		(layer "In6.Cu")
		(net 162)
	)
	(arc
		(start 204.55 116.95)
		(mid 204.67448 116.64948)
		(end 204.975 116.525)
		(width 0.148)
		(layer "In6.Cu")
		(net 162)
	)
	(arc
		(start 203.7 117.1)
		(mid 203.82448 117.40052)
		(end 204.125 117.525)
		(width 0.148)
		(layer "In6.Cu")
		(net 162)
	)
	(arc
		(start 202.115189 117.52298)
		(mid 201.946776 117.116393)
		(end 202.11519 116.709807)
		(width 0.148)
		(layer "In6.Cu")
		(net 162)
	)
	(arc
		(start 203.275 116.525)
		(mid 203.57552 116.64948)
		(end 203.7 116.95)
		(width 0.148)
		(layer "In6.Cu")
		(net 162)
	)
	(arc
		(start 202.04448 119.078616)
		(mid 202.451067 119.247029)
		(end 202.857653 119.078615)
		(width 0.148)
		(layer "In6.Cu")
		(net 162)
	)
	(arc
		(start 199.125 121.475)
		(mid 198.82448 121.35052)
		(end 198.7 121.05)
		(width 0.148)
		(layer "In6.Cu")
		(net 162)
	)
	(arc
		(start 204.125 117.525)
		(mid 204.42552 117.40052)
		(end 204.55 117.1)
		(width 0.148)
		(layer "In6.Cu")
		(net 162)
	)
	(arc
		(start 207.575 116.975)
		(mid 207.706802 116.656802)
		(end 208.025 116.525)
		(width 0.148)
		(layer "In6.Cu")
		(net 162)
	)
	(arc
		(start 207.125 118.025)
		(mid 207.443198 117.893198)
		(end 207.575 117.575)
		(width 0.148)
		(layer "In6.Cu")
		(net 162)
	)
	(arc
		(start 200.488843 119.149326)
		(mid 200.32043 118.742739)
		(end 200.488844 118.336153)
		(width 0.148)
		(layer "In6.Cu")
		(net 162)
	)
	(arc
		(start 200.488846 118.336154)
		(mid 200.895432 118.167741)
		(end 201.302018 118.336154)
		(width 0.148)
		(layer "In6.Cu")
		(net 162)
	)
	(arc
		(start 202.857652 119.078616)
		(mid 203.026066 118.672029)
		(end 202.857652 118.265442)
		(width 0.148)
		(layer "In6.Cu")
		(net 162)
	)
	(arc
		(start 206.225 116.525)
		(mid 206.543198 116.656802)
		(end 206.675 116.975)
		(width 0.148)
		(layer "In6.Cu")
		(net 162)
	)
	(arc
		(start 199.275 122.325)
		(mid 199.57552 122.20052)
		(end 199.7 121.9)
		(width 0.148)
		(layer "In6.Cu")
		(net 162)
	)
	(arc
		(start 199.7 121.9)
		(mid 199.57552 121.59948)
		(end 199.275 121.475)
		(width 0.148)
		(layer "In6.Cu")
		(net 162)
	)
	(arc
		(start 198.8625 119.9625)
		(mid 199.269086 119.794087)
		(end 199.675672 119.9625)
		(width 0.148)
		(layer "In6.Cu")
		(net 162)
	)
	(arc
		(start 200.418134 120.704962)
		(mid 200.824721 120.873375)
		(end 201.231307 120.704961)
		(width 0.148)
		(layer "In6.Cu")
		(net 162)
	)
	(arc
		(start 206.675 117.575)
		(mid 206.806802 117.893198)
		(end 207.125 118.025)
		(width 0.148)
		(layer "In6.Cu")
		(net 162)
	)
	(arc
		(start 201.231306 120.704962)
		(mid 201.39972 120.298375)
		(end 201.231306 119.891788)
		(width 0.148)
		(layer "In6.Cu")
		(net 162)
	)
	(segment
		(start 225.889178 181.579408)
		(end 225.889178 181.138178)
		(width 0.4)
		(layer "F.Cu")
		(net 163)
	)
	(segment
		(start 223.53 180.255)
		(end 222.745001 180.255)
		(width 0.4)
		(layer "F.Cu")
		(net 163)
	)
	(segment
		(start 233.465001 180.245)
		(end 233.95 180.245)
		(width 0.4)
		(layer "F.Cu")
		(net 163)
	)
	(segment
		(start 223.535 180.26)
		(end 223.53 180.255)
		(width 0.4)
		(layer "F.Cu")
		(net 163)
	)
	(segment
		(start 225.889178 181.138178)
		(end 225.881 181.13)
		(width 0.4)
		(layer "F.Cu")
		(net 163)
	)
	(segment
		(start 215.194178 181.635)
		(end 215.194178 181.143178)
		(width 0.4)
		(layer "F.Cu")
		(net 163)
	)
	(via
		(at 215.075 186.31)
		(size 0.45)
		(drill 0.1)
		(layers "F.Cu" "B.Cu")
		(remove_unused_layers yes)
		(keep_end_layers yes)
		(zone_layer_connections)
		(net 163)
	)
	(via
		(at 223.535 180.26)
		(size 0.45)
		(drill 0.1)
		(layers "F.Cu" "B.Cu")
		(remove_unused_layers yes)
		(keep_end_layers yes)
		(zone_layer_connections)
		(net 163)
	)
	(via
		(at 225.889178 181.579408)
		(size 0.45)
		(drill 0.1)
		(layers "F.Cu" "B.Cu")
		(remove_unused_layers yes)
		(keep_end_layers yes)
		(zone_layer_connections)
		(net 163)
	)
	(via
		(at 215.194178 181.635)
		(size 0.45)
		(drill 0.1)
		(layers "F.Cu" "B.Cu")
		(remove_unused_layers yes)
		(keep_end_layers yes)
		(zone_layer_connections)
		(net 163)
	)
	(via
		(at 233.95 180.245)
		(size 0.45)
		(drill 0.1)
		(layers "F.Cu" "B.Cu")
		(remove_unused_layers yes)
		(keep_end_layers yes)
		(zone_layer_connections)
		(net 163)
	)
	(segment
		(start 215.075 186.31)
		(end 215.075 185.74)
		(width 0.182)
		(layer "B.Cu")
		(net 163)
	)
	(segment
		(start 234.25 181.625)
		(end 234.5 181.375)
		(width 0.198)
		(layer "B.Cu")
		(net 163)
	)
	(segment
		(start 234.5 180.725)
		(end 234.02 180.245)
		(width 0.198)
		(layer "B.Cu")
		(net 163)
	)
	(segment
		(start 234.5 181.375)
		(end 234.5 180.725)
		(width 0.198)
		(layer "B.Cu")
		(net 163)
	)
	(segment
		(start 234.02 180.245)
		(end 233.95 180.245)
		(width 0.198)
		(layer "B.Cu")
		(net 163)
	)
	(segment
		(start 215.075 185.74)
		(end 215.1 185.715)
		(width 0.114)
		(layer "B.Cu")
		(net 163)
	)
	(segment
		(start 234.25 182.025)
		(end 234.25 181.625)
		(width 0.198)
		(layer "B.Cu")
		(net 163)
	)
	(segment
		(start 233.95 180.245)
		(end 233.575 180.62)
		(width 0.4)
		(layer "In6.Cu")
		(net 163)
	)
	(segment
		(start 225.895 180.26)
		(end 222.24 180.26)
		(width 0.4)
		(layer "In6.Cu")
		(net 163)
	)
	(segment
		(start 221.71 180.79)
		(end 216.655 180.79)
		(width 0.4)
		(layer "In6.Cu")
		(net 163)
	)
	(segment
		(start 231.215 180.26)
		(end 225.895 180.26)
		(width 0.4)
		(layer "In6.Cu")
		(net 163)
	)
	(segment
		(start 215.525 180.43)
		(end 215.194178 180.760822)
		(width 0.4)
		(layer "In6.Cu")
		(net 163)
	)
	(segment
		(start 215.075 185.259178)
		(end 215.194178 185.14)
		(width 0.4)
		(layer "In6.Cu")
		(net 163)
	)
	(segment
		(start 222.24 180.26)
		(end 221.71 180.79)
		(width 0.4)
		(layer "In6.Cu")
		(net 163)
	)
	(segment
		(start 225.889178 181.579408)
		(end 225.889178 180.265822)
		(width 0.4)
		(layer "In6.Cu")
		(net 163)
	)
	(segment
		(start 215.194178 180.760822)
		(end 215.194178 181.635)
		(width 0.4)
		(layer "In6.Cu")
		(net 163)
	)
	(segment
		(start 216.655 180.79)
		(end 216.295 180.43)
		(width 0.4)
		(layer "In6.Cu")
		(net 163)
	)
	(segment
		(start 215.194178 181.635)
		(end 215.194178 185.14)
		(width 0.4)
		(layer "In6.Cu")
		(net 163)
	)
	(segment
		(start 225.889178 180.265822)
		(end 225.895 180.26)
		(width 0.4)
		(layer "In6.Cu")
		(net 163)
	)
	(segment
		(start 231.575 180.62)
		(end 231.215 180.26)
		(width 0.4)
		(layer "In6.Cu")
		(net 163)
	)
	(segment
		(start 233.575 180.62)
		(end 231.575 180.62)
		(width 0.4)
		(layer "In6.Cu")
		(net 163)
	)
	(segment
		(start 216.295 180.43)
		(end 215.525 180.43)
		(width 0.4)
		(layer "In6.Cu")
		(net 163)
	)
	(segment
		(start 215.075 185.259178)
		(end 215.075 186.31)
		(width 0.4)
		(layer "In6.Cu")
		(net 163)
	)
	(segment
		(start 197.0005 141.9995)
		(end 197.5 141.5)
		(width 0.256)
		(layer "F.Cu")
		(net 166)
	)
	(segment
		(start 210 110.598)
		(end 210 111.75)
		(width 0.38)
		(layer "F.Cu")
		(net 166)
	)
	(via
		(at 210 111.75)
		(size 0.45)
		(drill 0.1)
		(layers "F.Cu" "B.Cu")
		(remove_unused_layers yes)
		(keep_end_layers yes)
		(zone_layer_connections)
		(net 166)
	)
	(via
		(at 197.5 141.5)
		(size 0.45)
		(drill 0.1)
		(layers "F.Cu" "B.Cu")
		(remove_unused_layers yes)
		(keep_end_layers yes)
		(zone_layer_connections)
		(net 166)
	)
	(segment
		(start 210 111.8)
		(end 208.8 113)
		(width 0.148)
		(layer "In6.Cu")
		(net 166)
	)
	(segment
		(start 195.124999 114.007108)
		(end 195.250969 114.133078)
		(width 0.148)
		(layer "In6.Cu")
		(net 166)
	)
	(segment
		(start 194.543862 114.840187)
		(end 194.543863 114.840185)
		(width 0.148)
		(layer "In6.Cu")
		(net 166)
	)
	(segment
		(start 192.1 116.325)
		(end 192.1 117.375)
		(width 0.148)
		(layer "In6.Cu")
		(net 166)
	)
	(segment
		(start 192.6 117.875)
		(end 192.778198 117.875)
		(width 0.148)
		(layer "In6.Cu")
		(net 166)
	)
	(segment
		(start 193.710785 115.421323)
		(end 193.710784 115.421323)
		(width 0.148)
		(layer "In6.Cu")
		(net 166)
	)
	(segment
		(start 195.25097 114.840185)
		(end 195.250969 114.840186)
		(width 0.148)
		(layer "In6.Cu")
		(net 166)
	)
	(segment
		(start 196 140.7)
		(end 196.3 141)
		(width 0.148)
		(layer "In6.Cu")
		(net 166)
	)
	(segment
		(start 208.8 113)
		(end 195.425 113)
		(width 0.148)
		(layer "In6.Cu")
		(net 166)
	)
	(segment
		(start 193.710784 115.421323)
		(end 193.836758 115.547297)
		(width 0.148)
		(layer "In6.Cu")
		(net 166)
	)
	(segment
		(start 197 141)
		(end 197.5 141.5)
		(width 0.148)
		(layer "In6.Cu")
		(net 166)
	)
	(segment
		(start 195.125 114.007108)
		(end 195.124999 114.007108)
		(width 0.148)
		(layer "In6.Cu")
		(net 166)
	)
	(segment
		(start 193.129651 116.254404)
		(end 193.003678 116.128431)
		(width 0.148)
		(layer "In6.Cu")
		(net 166)
	)
	(segment
		(start 193.710787 114.714215)
		(end 193.710786 114.714217)
		(width 0.148)
		(layer "In6.Cu")
		(net 166)
	)
	(segment
		(start 194.543863 114.840185)
		(end 194.417894 114.714216)
		(width 0.148)
		(layer "In6.Cu")
		(net 166)
	)
	(segment
		(start 193.129652 116.254404)
		(end 193.129651 116.254404)
		(width 0.148)
		(layer "In6.Cu")
		(net 166)
	)
	(segment
		(start 192.778198 118.875)
		(end 192.6 118.875)
		(width 0.148)
		(layer "In6.Cu")
		(net 166)
	)
	(segment
		(start 192.778165 120.875)
		(end 192.6 120.875)
		(width 0.148)
		(layer "In6.Cu")
		(net 166)
	)
	(segment
		(start 192.296571 116.128432)
		(end 192.296572 116.128431)
		(width 0.148)
		(layer "In6.Cu")
		(net 166)
	)
	(segment
		(start 196 126.175)
		(end 196 140.7)
		(width 0.148)
		(layer "In6.Cu")
		(net 166)
	)
	(segment
		(start 196.3 141)
		(end 197 141)
		(width 0.148)
		(layer "In6.Cu")
		(net 166)
	)
	(segment
		(start 192.6 119.875)
		(end 192.778165 119.875)
		(width 0.148)
		(layer "In6.Cu")
		(net 166)
	)
	(segment
		(start 195.425 113)
		(end 195.125 113.3)
		(width 0.148)
		(layer "In6.Cu")
		(net 166)
	)
	(segment
		(start 192.296572 116.128431)
		(end 192.1 116.325)
		(width 0.148)
		(layer "In6.Cu")
		(net 166)
	)
	(segment
		(start 192.1 122.275)
		(end 196 126.175)
		(width 0.148)
		(layer "In6.Cu")
		(net 166)
	)
	(segment
		(start 210 111.75)
		(end 210 111.8)
		(width 0.148)
		(layer "In6.Cu")
		(net 166)
	)
	(segment
		(start 193.710786 114.714217)
		(end 193.710785 114.714215)
		(width 0.148)
		(layer "In6.Cu")
		(net 166)
	)
	(segment
		(start 192.1 121.375)
		(end 192.1 122.275)
		(width 0.148)
		(layer "In6.Cu")
		(net 166)
	)
	(segment
		(start 193.836757 116.254404)
		(end 193.836759 116.254403)
		(width 0.148)
		(layer "In6.Cu")
		(net 166)
	)
	(arc
		(start 195.125 113.3)
		(mid 194.978552 113.653555)
		(end 195.125 114.007108)
		(width 0.148)
		(layer "In6.Cu")
		(net 166)
	)
	(arc
		(start 193.836759 116.254403)
		(mid 193.483206 116.40085)
		(end 193.129652 116.254404)
		(width 0.148)
		(layer "In6.Cu")
		(net 166)
	)
	(arc
		(start 192.1 117.375)
		(mid 192.246447 117.728553)
		(end 192.6 117.875)
		(width 0.148)
		(layer "In6.Cu")
		(net 166)
	)
	(arc
		(start 194.417894 114.714216)
		(mid 194.064341 114.567769)
		(end 193.710787 114.714215)
		(width 0.148)
		(layer "In6.Cu")
		(net 166)
	)
	(arc
		(start 192.778165 119.875)
		(mid 193.131718 120.021447)
		(end 193.278165 120.375)
		(width 0.148)
		(layer "In6.Cu")
		(net 166)
	)
	(arc
		(start 193.278165 120.375)
		(mid 193.131718 120.728553)
		(end 192.778165 120.875)
		(width 0.148)
		(layer "In6.Cu")
		(net 166)
	)
	(arc
		(start 193.836758 115.547297)
		(mid 193.983204 115.900851)
		(end 193.836757 116.254404)
		(width 0.148)
		(layer "In6.Cu")
		(net 166)
	)
	(arc
		(start 193.003678 116.128431)
		(mid 192.650124 115.981985)
		(end 192.296571 116.128432)
		(width 0.148)
		(layer "In6.Cu")
		(net 166)
	)
	(arc
		(start 192.6 118.875)
		(mid 192.246447 119.021447)
		(end 192.1 119.375)
		(width 0.148)
		(layer "In6.Cu")
		(net 166)
	)
	(arc
		(start 195.250969 114.133078)
		(mid 195.397416 114.486631)
		(end 195.25097 114.840185)
		(width 0.148)
		(layer "In6.Cu")
		(net 166)
	)
	(arc
		(start 192.778198 117.875)
		(mid 193.131751 118.021447)
		(end 193.278198 118.375)
		(width 0.148)
		(layer "In6.Cu")
		(net 166)
	)
	(arc
		(start 192.1 119.375)
		(mid 192.246447 119.728553)
		(end 192.6 119.875)
		(width 0.148)
		(layer "In6.Cu")
		(net 166)
	)
	(arc
		(start 192.6 120.875)
		(mid 192.246447 121.021447)
		(end 192.1 121.375)
		(width 0.148)
		(layer "In6.Cu")
		(net 166)
	)
	(arc
		(start 195.250969 114.840186)
		(mid 194.897416 114.986633)
		(end 194.543862 114.840187)
		(width 0.148)
		(layer "In6.Cu")
		(net 166)
	)
	(arc
		(start 193.278198 118.375)
		(mid 193.131751 118.728553)
		(end 192.778198 118.875)
		(width 0.148)
		(layer "In6.Cu")
		(net 166)
	)
	(arc
		(start 193.710785 114.714215)
		(mid 193.564337 115.06777)
		(end 193.710785 115.421323)
		(width 0.148)
		(layer "In6.Cu")
		(net 166)
	)
	(segment
		(start 251.912998 141.25)
		(end 251.838998 141.324)
		(width 0.182)
		(layer "F.Cu")
		(net 168)
	)
	(segment
		(start 252.789499 141.25)
		(end 251.912998 141.25)
		(width 0.182)
		(layer "F.Cu")
		(net 168)
	)
	(via
		(at 251.838998 141.324)
		(size 0.45)
		(drill 0.1)
		(layers "F.Cu" "B.Cu")
		(remove_unused_layers yes)
		(keep_end_layers yes)
		(zone_layer_connections)
		(net 168)
	)
	(via
		(at 226.995001 182.240001)
		(size 0.45)
		(drill 0.1)
		(layers "F.Cu" "B.Cu")
		(remove_unused_layers yes)
		(keep_end_layers yes)
		(zone_layer_connections)
		(net 168)
	)
	(via
		(at 216.300001 182.245001)
		(size 0.45)
		(drill 0.1)
		(layers "F.Cu" "B.Cu")
		(remove_unused_layers yes)
		(keep_end_layers yes)
		(zone_layer_connections)
		(net 168)
	)
	(segment
		(start 252.554499 141.3)
		(end 251.862998 141.3)
		(width 0.256)
		(layer "B.Cu")
		(net 168)
	)
	(segment
		(start 251.862998 141.3)
		(end 251.838998 141.324)
		(width 0.256)
		(layer "B.Cu")
		(net 168)
	)
	(segment
		(start 222.735 181.385)
		(end 223.590001 182.240001)
		(width 0.114)
		(layer "In2.Cu")
		(net 168)
	)
	(segment
		(start 221.8 181.385)
		(end 222.735 181.385)
		(width 0.114)
		(layer "In2.Cu")
		(net 168)
	)
	(segment
		(start 216.300001 182.245001)
		(end 220.939999 182.245001)
		(width 0.114)
		(layer "In2.Cu")
		(net 168)
	)
	(segment
		(start 220.939999 182.245001)
		(end 221.8 181.385)
		(width 0.114)
		(layer "In2.Cu")
		(net 168)
	)
	(segment
		(start 223.590001 182.240001)
		(end 226.995001 182.240001)
		(width 0.114)
		(layer "In2.Cu")
		(net 168)
	)
	(segment
		(start 227.765 183.01)
		(end 231.1 183.01)
		(width 0.1)
		(layer "In4.Cu")
		(net 168)
	)
	(segment
		(start 226.995001 182.240001)
		(end 227.765 183.01)
		(width 0.1)
		(layer "In4.Cu")
		(net 168)
	)
	(segment
		(start 236.67 188.58)
		(end 253.176342 188.58)
		(width 0.1)
		(layer "In4.Cu")
		(net 168)
	)
	(segment
		(start 261.885 147.633245)
		(end 261.606752 147.354997)
		(width 0.1)
		(layer "In4.Cu")
		(net 168)
	)
	(segment
		(start 261.885 179.871342)
		(end 261.885 147.633245)
		(width 0.1)
		(layer "In4.Cu")
		(net 168)
	)
	(segment
		(start 260.504997 147.354997)
		(end 254.474 141.324)
		(width 0.1)
		(layer "In4.Cu")
		(net 168)
	)
	(segment
		(start 231.1 183.01)
		(end 236.67 188.58)
		(width 0.1)
		(layer "In4.Cu")
		(net 168)
	)
	(segment
		(start 254.474 141.324)
		(end 251.838998 141.324)
		(width 0.1)
		(layer "In4.Cu")
		(net 168)
	)
	(segment
		(start 261.606752 147.354997)
		(end 260.504997 147.354997)
		(width 0.1)
		(layer "In4.Cu")
		(net 168)
	)
	(segment
		(start 253.176342 188.58)
		(end 261.885 179.871342)
		(width 0.1)
		(layer "In4.Cu")
		(net 168)
	)
	(segment
		(start 255.32 175.8955)
		(end 255.32 176.92)
		(width 0.256)
		(layer "F.Cu")
		(net 169)
	)
	(segment
		(start 252.789499 140.3)
		(end 252 140.3)
		(width 0.182)
		(layer "F.Cu")
		(net 169)
	)
	(via
		(at 255.32 176.92)
		(size 0.45)
		(drill 0.1)
		(layers "F.Cu" "B.Cu")
		(remove_unused_layers yes)
		(keep_end_layers yes)
		(zone_layer_connections)
		(net 169)
	)
	(via
		(at 252 140.3)
		(size 0.45)
		(drill 0.1)
		(layers "F.Cu" "B.Cu")
		(remove_unused_layers yes)
		(keep_end_layers yes)
		(zone_layer_connections)
		(net 169)
	)
	(segment
		(start 252.554499 140.3)
		(end 252 140.3)
		(width 0.256)
		(layer "B.Cu")
		(net 169)
	)
	(segment
		(start 259.224499 148.92917)
		(end 259.224499 173.015501)
		(width 0.1)
		(layer "In2.Cu")
		(net 169)
	)
	(segment
		(start 259.224499 173.015501)
		(end 255.32 176.92)
		(width 0.1)
		(layer "In2.Cu")
		(net 169)
	)
	(segment
		(start 252.213998 141.918669)
		(end 259.224499 148.92917)
		(width 0.1)
		(layer "In2.Cu")
		(net 169)
	)
	(segment
		(start 252 140.3)
		(end 252.213998 140.513998)
		(width 0.1)
		(layer "In2.Cu")
		(net 169)
	)
	(segment
		(start 252.213998 140.513998)
		(end 252.213998 141.918669)
		(width 0.1)
		(layer "In2.Cu")
		(net 169)
	)
	(segment
		(start 255.293 159.393)
		(end 255.425 159.525)
		(width 0.256)
		(layer "F.Cu")
		(net 170)
	)
	(segment
		(start 255.293 158.4445)
		(end 255.293 159.393)
		(width 0.256)
		(layer "F.Cu")
		(net 170)
	)
	(segment
		(start 251.864998 139.35)
		(end 251.838998 139.324)
		(width 0.182)
		(layer "F.Cu")
		(net 170)
	)
	(segment
		(start 252.789499 139.35)
		(end 251.864998 139.35)
		(width 0.182)
		(layer "F.Cu")
		(net 170)
	)
	(via
		(at 251.838998 139.324)
		(size 0.45)
		(drill 0.1)
		(layers "F.Cu" "B.Cu")
		(remove_unused_layers yes)
		(keep_end_layers yes)
		(zone_layer_connections)
		(net 170)
	)
	(via
		(at 255.425 159.525)
		(size 0.45)
		(drill 0.1)
		(layers "F.Cu" "B.Cu")
		(remove_unused_layers yes)
		(keep_end_layers yes)
		(zone_layer_connections)
		(net 170)
	)
	(segment
		(start 252.554499 139.3)
		(end 251.862998 139.3)
		(width 0.256)
		(layer "B.Cu")
		(net 170)
	)
	(segment
		(start 251.862998 139.3)
		(end 251.838998 139.324)
		(width 0.256)
		(layer "B.Cu")
		(net 170)
	)
	(segment
		(start 253.375 151.1)
		(end 254.775 152.5)
		(width 0.1)
		(layer "In2.Cu")
		(net 170)
	)
	(segment
		(start 246.625 144.489379)
		(end 250.69281 148.55719)
		(width 0.1)
		(layer "In2.Cu")
		(net 170)
	)
	(segment
		(start 256.525 152.5)
		(end 258.025 154)
		(width 0.1)
		(layer "In2.Cu")
		(net 170)
	)
	(segment
		(start 246.625 142)
		(end 246.625 144.489379)
		(width 0.1)
		(layer "In2.Cu")
		(net 170)
	)
	(segment
		(start 253.375 149.85)
		(end 253.375 151.1)
		(width 0.1)
		(layer "In2.Cu")
		(net 170)
	)
	(segment
		(start 258.025 158.15)
		(end 257.25 158.925)
		(width 0.1)
		(layer "In2.Cu")
		(net 170)
	)
	(segment
		(start 247.149 141.476)
		(end 246.625 142)
		(width 0.1)
		(layer "In2.Cu")
		(net 170)
	)
	(segment
		(start 257.25 158.925)
		(end 256.025 158.925)
		(width 0.1)
		(layer "In2.Cu")
		(net 170)
	)
	(segment
		(start 252.08219 148.55719)
		(end 253.375 149.85)
		(width 0.1)
		(layer "In2.Cu")
		(net 170)
	)
	(segment
		(start 251.838998 139.324)
		(end 249.686998 141.476)
		(width 0.1)
		(layer "In2.Cu")
		(net 170)
	)
	(segment
		(start 249.686998 141.476)
		(end 247.149 141.476)
		(width 0.1)
		(layer "In2.Cu")
		(net 170)
	)
	(segment
		(start 250.69281 148.55719)
		(end 252.08219 148.55719)
		(width 0.1)
		(layer "In2.Cu")
		(net 170)
	)
	(segment
		(start 254.775 152.5)
		(end 256.525 152.5)
		(width 0.1)
		(layer "In2.Cu")
		(net 170)
	)
	(segment
		(start 258.025 154)
		(end 258.025 158.15)
		(width 0.1)
		(layer "In2.Cu")
		(net 170)
	)
	(segment
		(start 256.025 158.925)
		(end 255.425 159.525)
		(width 0.1)
		(layer "In2.Cu")
		(net 170)
	)
	(segment
		(start 208.3 110.598)
		(end 208.3 111.75)
		(width 0.38)
		(layer "F.Cu")
		(net 171)
	)
	(segment
		(start 191.0005 145.9995)
		(end 191.5 145.499999)
		(width 0.256)
		(layer "F.Cu")
		(net 171)
	)
	(via
		(at 191.5 145.499999)
		(size 0.45)
		(drill 0.1)
		(layers "F.Cu" "B.Cu")
		(remove_unused_layers yes)
		(keep_end_layers yes)
		(zone_layer_connections)
		(net 171)
	)
	(via
		(at 208.3 111.75)
		(size 0.45)
		(drill 0.1)
		(layers "F.Cu" "B.Cu")
		(remove_unused_layers yes)
		(keep_end_layers yes)
		(zone_layer_connections)
		(net 171)
	)
	(segment
		(start 194.238717 121.939759)
		(end 194.263958 121.965)
		(width 0.15)
		(layer "In4.Cu")
		(net 171)
	)
	(segment
		(start 189.25 138.8)
		(end 189.25 127.58)
		(width 0.15)
		(layer "In4.Cu")
		(net 171)
	)
	(segment
		(start 189 139.05)
		(end 189.25 138.8)
		(width 0.15)
		(layer "In4.Cu")
		(net 171)
	)
	(segment
		(start 202.74 115.07)
		(end 206.8 115.07)
		(width 0.15)
		(layer "In4.Cu")
		(net 171)
	)
	(segment
		(start 189 142.2)
		(end 189 139.05)
		(width 0.15)
		(layer "In4.Cu")
		(net 171)
	)
	(segment
		(start 193.662917 122.566039)
		(end 192.609388 121.51251)
		(width 0.15)
		(layer "In4.Cu")
		(net 171)
	)
	(segment
		(start 189 142.2)
		(end 190.0005 143.2005)
		(width 0.148)
		(layer "In4.Cu")
		(net 171)
	)
	(segment
		(start 193.662917 123.16708)
		(end 193.662918 123.16708)
		(width 0.15)
		(layer "In4.Cu")
		(net 171)
	)
	(segment
		(start 190.056671 126.773326)
		(end 190.056674 126.773326)
		(width 0.15)
		(layer "In4.Cu")
		(net 171)
	)
	(segment
		(start 190.056674 126.773326)
		(end 190.084338 126.745659)
		(width 0.15)
		(layer "In4.Cu")
		(net 171)
	)
	(segment
		(start 206.8 115.07)
		(end 207.86 114.01)
		(width 0.15)
		(layer "In4.Cu")
		(net 171)
	)
	(segment
		(start 190.95 144.17)
		(end 190.95 144.65)
		(width 0.148)
		(layer "In4.Cu")
		(net 171)
	)
	(segment
		(start 190.2405 143.99)
		(end 190.77 143.99)
		(width 0.148)
		(layer "In4.Cu")
		(net 171)
	)
	(segment
		(start 192.460836 124.369164)
		(end 192.460835 124.369162)
		(width 0.15)
		(layer "In4.Cu")
		(net 171)
	)
	(segment
		(start 191.5 145.2)
		(end 191.5 145.499999)
		(width 0.148)
		(layer "In4.Cu")
		(net 171)
	)
	(segment
		(start 194.865 121.965)
		(end 195.17 121.66)
		(width 0.15)
		(layer "In4.Cu")
		(net 171)
	)
	(segment
		(start 193.662918 123.167082)
		(end 193.662917 123.16708)
		(width 0.15)
		(layer "In4.Cu")
		(net 171)
	)
	(segment
		(start 191.407318 122.113564)
		(end 191.407318 122.113563)
		(width 0.15)
		(layer "In4.Cu")
		(net 171)
	)
	(segment
		(start 190.80627 123.315639)
		(end 191.859795 124.369164)
		(width 0.15)
		(layer "In4.Cu")
		(net 171)
	)
	(segment
		(start 190.084338 125.154669)
		(end 190.614669 125.685)
		(width 0.15)
		(layer "In4.Cu")
		(net 171)
	)
	(segment
		(start 190.0005 143.2005)
		(end 190.0005 143.75)
		(width 0.148)
		(layer "In4.Cu")
		(net 171)
	)
	(segment
		(start 190.77 143.99)
		(end 190.95 144.17)
		(width 0.148)
		(layer "In4.Cu")
		(net 171)
	)
	(segment
		(start 190.084338 126.215329)
		(end 189.554008 125.684999)
		(width 0.15)
		(layer "In4.Cu")
		(net 171)
	)
	(segment
		(start 192.609388 120.91147)
		(end 192.609388 120.911469)
		(width 0.15)
		(layer "In4.Cu")
		(net 171)
	)
	(segment
		(start 194.539961 121.178894)
		(end 194.539961 121.178893)
		(width 0.15)
		(layer "In4.Cu")
		(net 171)
	)
	(segment
		(start 190.0005 143.75)
		(end 190.2405 143.99)
		(width 0.148)
		(layer "In4.Cu")
		(net 171)
	)
	(segment
		(start 194.238717 121.939756)
		(end 194.238717 121.939759)
		(width 0.15)
		(layer "In4.Cu")
		(net 171)
	)
	(segment
		(start 192.460835 123.768121)
		(end 191.407318 122.714604)
		(width 0.15)
		(layer "In4.Cu")
		(net 171)
	)
	(segment
		(start 208.24 111.75)
		(end 208.3 111.75)
		(width 0.15)
		(layer "In4.Cu")
		(net 171)
	)
	(segment
		(start 190.95 144.65)
		(end 191.5 145.2)
		(width 0.148)
		(layer "In4.Cu")
		(net 171)
	)
	(segment
		(start 192.460835 124.369162)
		(end 192.460836 124.369162)
		(width 0.15)
		(layer "In4.Cu")
		(net 171)
	)
	(segment
		(start 191.145 125.685)
		(end 191.258754 125.571246)
		(width 0.15)
		(layer "In4.Cu")
		(net 171)
	)
	(segment
		(start 196.15 121.66)
		(end 202.74 115.07)
		(width 0.15)
		(layer "In4.Cu")
		(net 171)
	)
	(segment
		(start 207.86 114.01)
		(end 207.86 112.13)
		(width 0.15)
		(layer "In4.Cu")
		(net 171)
	)
	(segment
		(start 193.061877 123.167082)
		(end 193.061876 123.167082)
		(width 0.15)
		(layer "In4.Cu")
		(net 171)
	)
	(segment
		(start 190.20523 123.315639)
		(end 190.205229 123.31564)
		(width 0.15)
		(layer "In4.Cu")
		(net 171)
	)
	(segment
		(start 191.258754 124.970203)
		(end 190.20523 123.916679)
		(width 0.15)
		(layer "In4.Cu")
		(net 171)
	)
	(segment
		(start 190.614669 125.685)
		(end 190.614668 125.685)
		(width 0.15)
		(layer "In4.Cu")
		(net 171)
	)
	(segment
		(start 195.17 121.66)
		(end 196.15 121.66)
		(width 0.15)
		(layer "In4.Cu")
		(net 171)
	)
	(segment
		(start 194.539961 121.178893)
		(end 194.238716 121.480137)
		(width 0.15)
		(layer "In4.Cu")
		(net 171)
	)
	(segment
		(start 192.008359 122.113564)
		(end 193.061877 123.167082)
		(width 0.15)
		(layer "In4.Cu")
		(net 171)
	)
	(segment
		(start 193.779098 121.020519)
		(end 194.080344 120.719274)
		(width 0.15)
		(layer "In4.Cu")
		(net 171)
	)
	(segment
		(start 191.258754 125.571246)
		(end 191.258753 125.571244)
		(width 0.15)
		(layer "In4.Cu")
		(net 171)
	)
	(segment
		(start 207.86 112.13)
		(end 208.24 111.75)
		(width 0.15)
		(layer "In4.Cu")
		(net 171)
	)
	(segment
		(start 189.25 127.58)
		(end 190.056671 126.773326)
		(width 0.15)
		(layer "In4.Cu")
		(net 171)
	)
	(segment
		(start 191.859795 124.369164)
		(end 191.859794 124.369164)
		(width 0.15)
		(layer "In4.Cu")
		(net 171)
	)
	(segment
		(start 193.210429 120.91147)
		(end 193.319479 121.02052)
		(width 0.15)
		(layer "In4.Cu")
		(net 171)
	)
	(segment
		(start 194.539963 120.719275)
		(end 194.539962 120.719275)
		(width 0.15)
		(layer "In4.Cu")
		(net 171)
	)
	(arc
		(start 192.609388 121.51251)
		(mid 192.484909 121.21199)
		(end 192.609388 120.91147)
		(width 0.15)
		(layer "In4.Cu")
		(net 171)
	)
	(arc
		(start 190.205229 123.31564)
		(mid 190.505749 123.19116)
		(end 190.80627 123.315639)
		(width 0.15)
		(layer "In4.Cu")
		(net 171)
	)
	(arc
		(start 193.319479 121.02052)
		(mid 193.549289 121.11571)
		(end 193.779098 121.020519)
		(width 0.15)
		(layer "In4.Cu")
		(net 171)
	)
	(arc
		(start 190.614668 125.685)
		(mid 190.879834 125.794835)
		(end 191.145 125.685)
		(width 0.15)
		(layer "In4.Cu")
		(net 171)
	)
	(arc
		(start 191.258753 125.571244)
		(mid 191.383233 125.270724)
		(end 191.258754 124.970203)
		(width 0.15)
		(layer "In4.Cu")
		(net 171)
	)
	(arc
		(start 190.20523 123.916679)
		(mid 190.080751 123.616159)
		(end 190.20523 123.315639)
		(width 0.15)
		(layer "In4.Cu")
		(net 171)
	)
	(arc
		(start 191.407318 122.714604)
		(mid 191.282839 122.414084)
		(end 191.407318 122.113564)
		(width 0.15)
		(layer "In4.Cu")
		(net 171)
	)
	(arc
		(start 194.539962 120.719275)
		(mid 194.635152 120.949085)
		(end 194.539961 121.178894)
		(width 0.15)
		(layer "In4.Cu")
		(net 171)
	)
	(arc
		(start 194.263958 121.965)
		(mid 194.564479 122.08948)
		(end 194.865 121.965)
		(width 0.15)
		(layer "In4.Cu")
		(net 171)
	)
	(arc
		(start 189.554008 125.684999)
		(mid 189.444173 125.419834)
		(end 189.554008 125.154669)
		(width 0.15)
		(layer "In4.Cu")
		(net 171)
	)
	(arc
		(start 194.080344 120.719274)
		(mid 194.310154 120.624084)
		(end 194.539963 120.719275)
		(width 0.15)
		(layer "In4.Cu")
		(net 171)
	)
	(arc
		(start 193.061876 123.167082)
		(mid 193.362397 123.291562)
		(end 193.662918 123.167082)
		(width 0.15)
		(layer "In4.Cu")
		(net 171)
	)
	(arc
		(start 193.662918 123.16708)
		(mid 193.787397 122.866559)
		(end 193.662917 122.566039)
		(width 0.15)
		(layer "In4.Cu")
		(net 171)
	)
	(arc
		(start 192.460836 124.369162)
		(mid 192.585315 124.068641)
		(end 192.460835 123.768121)
		(width 0.15)
		(layer "In4.Cu")
		(net 171)
	)
	(arc
		(start 194.238716 121.480137)
		(mid 194.143526 121.709947)
		(end 194.238717 121.939756)
		(width 0.15)
		(layer "In4.Cu")
		(net 171)
	)
	(arc
		(start 191.407318 122.113563)
		(mid 191.707839 121.989084)
		(end 192.008359 122.113564)
		(width 0.15)
		(layer "In4.Cu")
		(net 171)
	)
	(arc
		(start 191.859794 124.369164)
		(mid 192.160315 124.493644)
		(end 192.460836 124.369164)
		(width 0.15)
		(layer "In4.Cu")
		(net 171)
	)
	(arc
		(start 189.554008 125.154669)
		(mid 189.819173 125.044834)
		(end 190.084338 125.154669)
		(width 0.15)
		(layer "In4.Cu")
		(net 171)
	)
	(arc
		(start 192.609388 120.911469)
		(mid 192.909909 120.78699)
		(end 193.210429 120.91147)
		(width 0.15)
		(layer "In4.Cu")
		(net 171)
	)
	(arc
		(start 190.084338 126.745659)
		(mid 190.194173 126.480494)
		(end 190.084338 126.215329)
		(width 0.15)
		(layer "In4.Cu")
		(net 171)
	)
	(segment
		(start 195.0005 161.0005)
		(end 195.5 161.5)
		(width 0.256)
		(layer "F.Cu")
		(net 172)
	)
	(segment
		(start 177.9995 159.0005)
		(end 177.5 159.5)
		(width 0.256)
		(layer "F.Cu")
		(net 172)
	)
	(segment
		(start 182.5005 161.4995)
		(end 183 161)
		(width 0.256)
		(layer "F.Cu")
		(net 172)
	)
	(segment
		(start 179.9995 159.0005)
		(end 179.5 159.5)
		(width 0.256)
		(layer "F.Cu")
		(net 172)
	)
	(segment
		(start 200.499501 159.4995)
		(end 200 159)
		(width 0.256)
		(layer "F.Cu")
		(net 172)
	)
	(segment
		(start 189.0005 161.0005)
		(end 189.5 161.5)
		(width 0.256)
		(layer "F.Cu")
		(net 172)
	)
	(segment
		(start 184.9995 161.0005)
		(end 184.5 161.5)
		(width 0.256)
		(layer "F.Cu")
		(net 172)
	)
	(segment
		(start 199.4995 158.4995)
		(end 199 158)
		(width 0.256)
		(layer "F.Cu")
		(net 172)
	)
	(segment
		(start 181.9995 159.0005)
		(end 181.5 159.500001)
		(width 0.256)
		(layer "F.Cu")
		(net 172)
	)
	(segment
		(start 193.0005 161.0005)
		(end 193.5 161.5)
		(width 0.256)
		(layer "F.Cu")
		(net 172)
	)
	(segment
		(start 197.0005 161.0005)
		(end 197.5 161.5)
		(width 0.256)
		(layer "F.Cu")
		(net 172)
	)
	(segment
		(start 180.9995 161.0005)
		(end 180.5 161.5)
		(width 0.256)
		(layer "F.Cu")
		(net 172)
	)
	(segment
		(start 191.0005 161.0005)
		(end 191.5 161.5)
		(width 0.256)
		(layer "F.Cu")
		(net 172)
	)
	(segment
		(start 175.9995 159.0005)
		(end 175.5 159.5)
		(width 0.256)
		(layer "F.Cu")
		(net 172)
	)
	(segment
		(start 186.9995 161.0005)
		(end 186.5 161.5)
		(width 0.256)
		(layer "F.Cu")
		(net 172)
	)
	(via
		(at 195.5 161.5)
		(size 0.45)
		(drill 0.1)
		(layers "F.Cu" "B.Cu")
		(remove_unused_layers yes)
		(keep_end_layers yes)
		(zone_layer_connections "In8.Cu")
		(net 172)
	)
	(via
		(at 189.5 161.5)
		(size 0.45)
		(drill 0.1)
		(layers "F.Cu" "B.Cu")
		(remove_unused_layers yes)
		(keep_end_layers yes)
		(zone_layer_connections "In8.Cu")
		(net 172)
	)
	(via
		(at 244.75 169.35)
		(size 0.45)
		(drill 0.1)
		(layers "F.Cu" "B.Cu")
		(remove_unused_layers yes)
		(keep_end_layers yes)
		(zone_layer_connections "In8.Cu")
		(net 172)
	)
	(via
		(at 244.2 169.6)
		(size 0.45)
		(drill 0.1)
		(layers "F.Cu" "B.Cu")
		(remove_unused_layers yes)
		(keep_end_layers yes)
		(zone_layer_connections "In8.Cu")
		(net 172)
	)
	(via
		(at 244.9 171.05)
		(size 0.45)
		(drill 0.1)
		(layers "F.Cu" "B.Cu")
		(remove_unused_layers yes)
		(keep_end_layers yes)
		(zone_layer_connections "In8.Cu")
		(net 172)
	)
	(via
		(at 181.5 159.500001)
		(size 0.45)
		(drill 0.1)
		(layers "F.Cu" "B.Cu")
		(remove_unused_layers yes)
		(keep_end_layers yes)
		(zone_layer_connections "In8.Cu")
		(net 172)
	)
	(via
		(at 179.5 159.5)
		(size 0.45)
		(drill 0.1)
		(layers "F.Cu" "B.Cu")
		(remove_unused_layers yes)
		(keep_end_layers yes)
		(zone_layer_connections "In8.Cu")
		(net 172)
	)
	(via
		(at 200.499501 159.4995)
		(size 0.45)
		(drill 0.1)
		(layers "F.Cu" "B.Cu")
		(remove_unused_layers yes)
		(keep_end_layers yes)
		(zone_layer_connections "In8.Cu")
		(net 172)
	)
	(via
		(at 245.4 169.05)
		(size 0.45)
		(drill 0.1)
		(layers "F.Cu" "B.Cu")
		(remove_unused_layers yes)
		(keep_end_layers yes)
		(zone_layer_connections "In8.Cu")
		(net 172)
	)
	(via
		(at 245.4 169.7)
		(size 0.45)
		(drill 0.1)
		(layers "F.Cu" "B.Cu")
		(remove_unused_layers yes)
		(keep_end_layers yes)
		(zone_layer_connections "In8.Cu")
		(net 172)
	)
	(via
		(at 243.65 169.2)
		(size 0.45)
		(drill 0.1)
		(layers "F.Cu" "B.Cu")
		(remove_unused_layers yes)
		(keep_end_layers yes)
		(zone_layer_connections "In8.Cu")
		(net 172)
	)
	(via
		(at 191.5 161.5)
		(size 0.45)
		(drill 0.1)
		(layers "F.Cu" "B.Cu")
		(remove_unused_layers yes)
		(keep_end_layers yes)
		(zone_layer_connections "In8.Cu")
		(net 172)
	)
	(via
		(at 244.4 171.55)
		(size 0.45)
		(drill 0.1)
		(layers "F.Cu" "B.Cu")
		(remove_unused_layers yes)
		(keep_end_layers yes)
		(zone_layer_connections "In8.Cu")
		(net 172)
	)
	(via
		(at 199.4995 158.4995)
		(size 0.45)
		(drill 0.1)
		(layers "F.Cu" "B.Cu")
		(remove_unused_layers yes)
		(keep_end_layers yes)
		(zone_layer_connections "In8.Cu")
		(net 172)
	)
	(via
		(at 180.5 161.5)
		(size 0.45)
		(drill 0.1)
		(layers "F.Cu" "B.Cu")
		(remove_unused_layers yes)
		(keep_end_layers yes)
		(zone_layer_connections "In8.Cu")
		(net 172)
	)
	(via
		(at 182.5005 161.4995)
		(size 0.45)
		(drill 0.1)
		(layers "F.Cu" "B.Cu")
		(remove_unused_layers yes)
		(keep_end_layers yes)
		(zone_layer_connections "In8.Cu")
		(net 172)
	)
	(via
		(at 175.5 159.5)
		(size 0.45)
		(drill 0.1)
		(layers "F.Cu" "B.Cu")
		(remove_unused_layers yes)
		(keep_end_layers yes)
		(zone_layer_connections "In8.Cu")
		(net 172)
	)
	(via
		(at 186.5 161.5)
		(size 0.45)
		(drill 0.1)
		(layers "F.Cu" "B.Cu")
		(remove_unused_layers yes)
		(keep_end_layers yes)
		(zone_layer_connections "In8.Cu")
		(net 172)
	)
	(via
		(at 244.95 170.1)
		(size 0.45)
		(drill 0.1)
		(layers "F.Cu" "B.Cu")
		(remove_unused_layers yes)
		(keep_end_layers yes)
		(zone_layer_connections "In8.Cu")
		(net 172)
	)
	(via
		(at 245.4 171.5)
		(size 0.45)
		(drill 0.1)
		(layers "F.Cu" "B.Cu")
		(remove_unused_layers yes)
		(keep_end_layers yes)
		(zone_layer_connections "In8.Cu")
		(net 172)
	)
	(via
		(at 184.5 161.5)
		(size 0.45)
		(drill 0.1)
		(layers "F.Cu" "B.Cu")
		(remove_unused_layers yes)
		(keep_end_layers yes)
		(zone_layer_connections "In8.Cu")
		(net 172)
	)
	(via
		(at 245.9 170.1)
		(size 0.45)
		(drill 0.1)
		(layers "F.Cu" "B.Cu")
		(remove_unused_layers yes)
		(keep_end_layers yes)
		(zone_layer_connections "In8.Cu")
		(net 172)
	)
	(via
		(at 245.9 171.05)
		(size 0.45)
		(drill 0.1)
		(layers "F.Cu" "B.Cu")
		(remove_unused_layers yes)
		(keep_end_layers yes)
		(zone_layer_connections "In8.Cu")
		(net 172)
	)
	(via
		(at 245.4 170.6)
		(size 0.45)
		(drill 0.1)
		(layers "F.Cu" "B.Cu")
		(remove_unused_layers yes)
		(keep_end_layers yes)
		(zone_layer_connections "In8.Cu")
		(net 172)
	)
	(via
		(at 243.7 171.55)
		(size 0.45)
		(drill 0.1)
		(layers "F.Cu" "B.Cu")
		(remove_unused_layers yes)
		(keep_end_layers yes)
		(zone_layer_connections "In8.Cu")
		(net 172)
	)
	(via
		(at 193.5 161.5)
		(size 0.45)
		(drill 0.1)
		(layers "F.Cu" "B.Cu")
		(remove_unused_layers yes)
		(keep_end_layers yes)
		(zone_layer_connections "In8.Cu")
		(net 172)
	)
	(via
		(at 177.5 159.5)
		(size 0.45)
		(drill 0.1)
		(layers "F.Cu" "B.Cu")
		(remove_unused_layers yes)
		(keep_end_layers yes)
		(zone_layer_connections "In8.Cu")
		(net 172)
	)
	(via
		(at 197.5 161.5)
		(size 0.45)
		(drill 0.1)
		(layers "F.Cu" "B.Cu")
		(remove_unused_layers yes)
		(keep_end_layers yes)
		(zone_layer_connections "In8.Cu")
		(net 172)
	)
	(via
		(at 244.2 168.9)
		(size 0.45)
		(drill 0.1)
		(layers "F.Cu" "B.Cu")
		(remove_unused_layers yes)
		(keep_end_layers yes)
		(zone_layer_connections "In8.Cu")
		(net 172)
	)
	(segment
		(start 180 162)
		(end 180.5 161.5)
		(width 0.256)
		(layer "B.Cu")
		(net 172)
	)
	(segment
		(start 180 159.998)
		(end 179.998 159.998)
		(width 0.256)
		(layer "B.Cu")
		(net 172)
	)
	(segment
		(start 182 162)
		(end 182.5005 161.4995)
		(width 0.256)
		(layer "B.Cu")
		(net 172)
	)
	(segment
		(start 184.5 161.502)
		(end 184 162.002)
		(width 0.256)
		(layer "B.Cu")
		(net 172)
	)
	(segment
		(start 200.499501 159.4995)
		(end 200.499501 159.498499)
		(width 0.256)
		(layer "B.Cu")
		(net 172)
	)
	(segment
		(start 195 162.002001)
		(end 195 162)
		(width 0.256)
		(layer "B.Cu")
		(net 172)
	)
	(segment
		(start 199.4995 158.4995)
		(end 199.4995 158.4985)
		(width 0.256)
		(layer "B.Cu")
		(net 172)
	)
	(segment
		(start 186 162.002)
		(end 186 162)
		(width 0.256)
		(layer "B.Cu")
		(net 172)
	)
	(segment
		(start 182 159.998)
		(end 181.997999 159.998)
		(width 0.256)
		(layer "B.Cu")
		(net 172)
	)
	(segment
		(start 189 162)
		(end 189.5 161.5)
		(width 0.256)
		(layer "B.Cu")
		(net 172)
	)
	(segment
		(start 177.502 159.5)
		(end 178 159.998)
		(width 0.256)
		(layer "B.Cu")
		(net 172)
	)
	(segment
		(start 193 162)
		(end 193.5 161.5)
		(width 0.256)
		(layer "B.Cu")
		(net 172)
	)
	(segment
		(start 175.502 159.5)
		(end 176 159.998)
		(width 0.256)
		(layer "B.Cu")
		(net 172)
	)
	(segment
		(start 179.998 159.998)
		(end 179.5 159.5)
		(width 0.256)
		(layer "B.Cu")
		(net 172)
	)
	(segment
		(start 193 162.002)
		(end 193 162)
		(width 0.256)
		(layer "B.Cu")
		(net 172)
	)
	(segment
		(start 174.6 160.2)
		(end 174.8 160.2)
		(width 0.4)
		(layer "B.Cu")
		(net 172)
	)
	(segment
		(start 191 162)
		(end 191.5 161.5)
		(width 0.256)
		(layer "B.Cu")
		(net 172)
	)
	(segment
		(start 197 162)
		(end 197.5 161.5)
		(width 0.256)
		(layer "B.Cu")
		(net 172)
	)
	(segment
		(start 197 162.002)
		(end 197 162)
		(width 0.256)
		(layer "B.Cu")
		(net 172)
	)
	(segment
		(start 199.4995 158.4985)
		(end 199 157.999)
		(width 0.256)
		(layer "B.Cu")
		(net 172)
	)
	(segment
		(start 180 162.002)
		(end 180 162)
		(width 0.256)
		(layer "B.Cu")
		(net 172)
	)
	(segment
		(start 175.5 159.5)
		(end 175.502 159.5)
		(width 0.256)
		(layer "B.Cu")
		(net 172)
	)
	(segment
		(start 195 162)
		(end 195.5 161.5)
		(width 0.256)
		(layer "B.Cu")
		(net 172)
	)
	(segment
		(start 177.5 159.5)
		(end 177.502 159.5)
		(width 0.256)
		(layer "B.Cu")
		(net 172)
	)
	(segment
		(start 184.5 161.5)
		(end 184.5 161.502)
		(width 0.256)
		(layer "B.Cu")
		(net 172)
	)
	(segment
		(start 200.499501 159.498499)
		(end 201 158.998)
		(width 0.256)
		(layer "B.Cu")
		(net 172)
	)
	(segment
		(start 181.997999 159.998)
		(end 181.5 159.500001)
		(width 0.256)
		(layer "B.Cu")
		(net 172)
	)
	(segment
		(start 174.8 160.2)
		(end 175.5 159.5)
		(width 0.4)
		(layer "B.Cu")
		(net 172)
	)
	(segment
		(start 182 162.002)
		(end 182 162)
		(width 0.256)
		(layer "B.Cu")
		(net 172)
	)
	(segment
		(start 186 162)
		(end 186.5 161.5)
		(width 0.256)
		(layer "B.Cu")
		(net 172)
	)
	(segment
		(start 192.0005 145.9995)
		(end 192.5 145.5)
		(width 0.256)
		(layer "F.Cu")
		(net 173)
	)
	(segment
		(start 206.6 110.598)
		(end 206.6 111.75)
		(width 0.38)
		(layer "F.Cu")
		(net 173)
	)
	(via
		(at 206.6 111.75)
		(size 0.45)
		(drill 0.1)
		(layers "F.Cu" "B.Cu")
		(remove_unused_layers yes)
		(keep_end_layers yes)
		(zone_layer_connections)
		(net 173)
	)
	(via
		(at 192.5 145.5)
		(size 0.45)
		(drill 0.1)
		(layers "F.Cu" "B.Cu")
		(remove_unused_layers yes)
		(keep_end_layers yes)
		(zone_layer_connections)
		(net 173)
	)
	(segment
		(start 195.52 119.99)
		(end 196 119.99)
		(width 0.15)
		(layer "In4.Cu")
		(net 173)
	)
	(segment
		(start 199.966249 116.023752)
		(end 201.65 114.34)
		(width 0.15)
		(layer "In4.Cu")
		(net 173)
	)
	(segment
		(start 190.25 145)
		(end 190 144.75)
		(width 0.148)
		(layer "In4.Cu")
		(net 173)
	)
	(segment
		(start 196 119.99)
		(end 196.36 119.63)
		(width 0.15)
		(layer "In4.Cu")
		(net 173)
	)
	(segment
		(start 198.764166 116.624794)
		(end 198.509143 116.369771)
		(width 0.15)
		(layer "In4.Cu")
		(net 173)
	)
	(segment
		(start 191.83 119.99)
		(end 192.12 119.99)
		(width 0.15)
		(layer "In4.Cu")
		(net 173)
	)
	(segment
		(start 207.01 112.159)
		(end 206.6005 111.7495)
		(width 0.15)
		(layer "In4.Cu")
		(net 173)
	)
	(segment
		(start 199.966251 116.023754)
		(end 199.96625 116.023754)
		(width 0.15)
		(layer "In4.Cu")
		(net 173)
	)
	(segment
		(start 189 143.25)
		(end 188.5 142.75)
		(width 0.15)
		(layer "In4.Cu")
		(net 173)
	)
	(segment
		(start 199.110186 115.768729)
		(end 199.36521 116.023753)
		(width 0.15)
		(layer "In4.Cu")
		(net 173)
	)
	(segment
		(start 192.5 145.5)
		(end 192.2 145.5)
		(width 0.148)
		(layer "In4.Cu")
		(net 173)
	)
	(segment
		(start 197.562083 117.826877)
		(end 197.307063 117.571857)
		(width 0.15)
		(layer "In4.Cu")
		(net 173)
	)
	(segment
		(start 197.307064 116.970816)
		(end 197.307065 116.970816)
		(width 0.15)
		(layer "In4.Cu")
		(net 173)
	)
	(segment
		(start 199.110185 115.768729)
		(end 199.110186 115.768729)
		(width 0.15)
		(layer "In4.Cu")
		(net 173)
	)
	(segment
		(start 194.245 119.565)
		(end 194.245 118.415)
		(width 0.15)
		(layer "In4.Cu")
		(net 173)
	)
	(segment
		(start 188.5 142.75)
		(end 188.5 123.32)
		(width 0.15)
		(layer "In4.Cu")
		(net 173)
	)
	(segment
		(start 189.25 143.95)
		(end 189 143.7)
		(width 0.148)
		(layer "In4.Cu")
		(net 173)
	)
	(segment
		(start 198.509144 115.768729)
		(end 198.509144 115.76873)
		(width 0.15)
		(layer "In4.Cu")
		(net 173)
	)
	(segment
		(start 207.01 113.28)
		(end 207.01 112.159)
		(width 0.15)
		(layer "In4.Cu")
		(net 173)
	)
	(segment
		(start 196.706022 118.1729)
		(end 196.961043 118.427921)
		(width 0.15)
		(layer "In4.Cu")
		(net 173)
	)
	(segment
		(start 197.908106 116.970815)
		(end 197.908105 116.970817)
		(width 0.15)
		(layer "In4.Cu")
		(net 173)
	)
	(segment
		(start 190 144.75)
		(end 190 144.3)
		(width 0.148)
		(layer "In4.Cu")
		(net 173)
	)
	(segment
		(start 197.562083 118.427921)
		(end 197.562083 118.427917)
		(width 0.15)
		(layer "In4.Cu")
		(net 173)
	)
	(segment
		(start 195.095 118.415)
		(end 195.095 119.565)
		(width 0.15)
		(layer "In4.Cu")
		(net 173)
	)
	(segment
		(start 191.3 146)
		(end 191 145.7)
		(width 0.148)
		(layer "In4.Cu")
		(net 173)
	)
	(segment
		(start 198.764166 117.225838)
		(end 198.764166 117.225834)
		(width 0.15)
		(layer "In4.Cu")
		(net 173)
	)
	(segment
		(start 192.545 119.565)
		(end 192.545 118.415)
		(width 0.15)
		(layer "In4.Cu")
		(net 173)
	)
	(segment
		(start 191.7 146)
		(end 191.3 146)
		(width 0.148)
		(layer "In4.Cu")
		(net 173)
	)
	(segment
		(start 196.706023 118.172898)
		(end 196.706022 118.1729)
		(width 0.15)
		(layer "In4.Cu")
		(net 173)
	)
	(segment
		(start 205.95 114.34)
		(end 207.01 113.28)
		(width 0.15)
		(layer "In4.Cu")
		(net 173)
	)
	(segment
		(start 189 143.6)
		(end 189 143.25)
		(width 0.15)
		(layer "In4.Cu")
		(net 173)
	)
	(segment
		(start 188.5 123.32)
		(end 191.83 119.99)
		(width 0.15)
		(layer "In4.Cu")
		(net 173)
	)
	(segment
		(start 190 144.3)
		(end 189.65 143.95)
		(width 0.148)
		(layer "In4.Cu")
		(net 173)
	)
	(segment
		(start 192.2 145.5)
		(end 191.7 146)
		(width 0.148)
		(layer "In4.Cu")
		(net 173)
	)
	(segment
		(start 198.509142 115.76873)
		(end 198.509144 115.768729)
		(width 0.15)
		(layer "In4.Cu")
		(net 173)
	)
	(segment
		(start 193.395 118.415)
		(end 193.395 119.565)
		(width 0.15)
		(layer "In4.Cu")
		(net 173)
	)
	(segment
		(start 189.65 143.95)
		(end 189.25 143.95)
		(width 0.148)
		(layer "In4.Cu")
		(net 173)
	)
	(segment
		(start 197.562084 118.42792)
		(end 197.562083 118.427921)
		(width 0.15)
		(layer "In4.Cu")
		(net 173)
	)
	(segment
		(start 190.7 145)
		(end 190.25 145)
		(width 0.148)
		(layer "In4.Cu")
		(net 173)
	)
	(segment
		(start 189 143.7)
		(end 189 143.6)
		(width 0.148)
		(layer "In4.Cu")
		(net 173)
	)
	(segment
		(start 191 145.7)
		(end 191 145.3)
		(width 0.148)
		(layer "In4.Cu")
		(net 173)
	)
	(segment
		(start 196.104981 118.172899)
		(end 196.104982 118.172899)
		(width 0.15)
		(layer "In4.Cu")
		(net 173)
	)
	(segment
		(start 201.65 114.34)
		(end 205.95 114.34)
		(width 0.15)
		(layer "In4.Cu")
		(net 173)
	)
	(segment
		(start 191 145.3)
		(end 190.7 145)
		(width 0.148)
		(layer "In4.Cu")
		(net 173)
	)
	(segment
		(start 196.36 119.02896)
		(end 196.10498 118.77394)
		(width 0.15)
		(layer "In4.Cu")
		(net 173)
	)
	(segment
		(start 199.96625 116.023754)
		(end 199.966249 116.023752)
		(width 0.15)
		(layer "In4.Cu")
		(net 173)
	)
	(segment
		(start 197.908105 116.970817)
		(end 198.163126 117.225838)
		(width 0.15)
		(layer "In4.Cu")
		(net 173)
	)
	(segment
		(start 198.764167 117.225837)
		(end 198.764166 117.225838)
		(width 0.15)
		(layer "In4.Cu")
		(net 173)
	)
	(arc
		(start 197.307065 116.970816)
		(mid 197.607585 116.846336)
		(end 197.908106 116.970815)
		(width 0.15)
		(layer "In4.Cu")
		(net 173)
	)
	(arc
		(start 199.36521 116.023753)
		(mid 199.66573 116.148233)
		(end 199.966251 116.023754)
		(width 0.15)
		(layer "In4.Cu")
		(net 173)
	)
	(arc
		(start 196.104982 118.172899)
		(mid 196.405502 118.048419)
		(end 196.706023 118.172898)
		(width 0.15)
		(layer "In4.Cu")
		(net 173)
	)
	(arc
		(start 196.10498 118.77394)
		(mid 195.980501 118.473419)
		(end 196.104981 118.172899)
		(width 0.15)
		(layer "In4.Cu")
		(net 173)
	)
	(arc
		(start 196.961043 118.427921)
		(mid 197.261564 118.5524)
		(end 197.562084 118.42792)
		(width 0.15)
		(layer "In4.Cu")
		(net 173)
	)
	(arc
		(start 194.67 117.99)
		(mid 194.97052 118.11448)
		(end 195.095 118.415)
		(width 0.15)
		(layer "In4.Cu")
		(net 173)
	)
	(arc
		(start 192.97 117.99)
		(mid 193.27052 118.11448)
		(end 193.395 118.415)
		(width 0.15)
		(layer "In4.Cu")
		(net 173)
	)
	(arc
		(start 198.509144 115.76873)
		(mid 198.809664 115.64425)
		(end 199.110185 115.768729)
		(width 0.15)
		(layer "In4.Cu")
		(net 173)
	)
	(arc
		(start 197.562083 118.427917)
		(mid 197.686563 118.127396)
		(end 197.562083 117.826877)
		(width 0.15)
		(layer "In4.Cu")
		(net 173)
	)
	(arc
		(start 195.095 119.565)
		(mid 195.21948 119.86552)
		(end 195.52 119.99)
		(width 0.15)
		(layer "In4.Cu")
		(net 173)
	)
	(arc
		(start 194.245 118.415)
		(mid 194.36948 118.11448)
		(end 194.67 117.99)
		(width 0.15)
		(layer "In4.Cu")
		(net 173)
	)
	(arc
		(start 198.509143 116.369771)
		(mid 198.384663 116.069251)
		(end 198.509142 115.76873)
		(width 0.15)
		(layer "In4.Cu")
		(net 173)
	)
	(arc
		(start 197.307063 117.571857)
		(mid 197.182584 117.271336)
		(end 197.307064 116.970816)
		(width 0.15)
		(layer "In4.Cu")
		(net 173)
	)
	(arc
		(start 193.82 119.99)
		(mid 194.12052 119.86552)
		(end 194.245 119.565)
		(width 0.15)
		(layer "In4.Cu")
		(net 173)
	)
	(arc
		(start 198.764166 117.225834)
		(mid 198.888646 116.925313)
		(end 198.764166 116.624794)
		(width 0.15)
		(layer "In4.Cu")
		(net 173)
	)
	(arc
		(start 193.395 119.565)
		(mid 193.51948 119.86552)
		(end 193.82 119.99)
		(width 0.15)
		(layer "In4.Cu")
		(net 173)
	)
	(arc
		(start 192.12 119.99)
		(mid 192.42052 119.86552)
		(end 192.545 119.565)
		(width 0.15)
		(layer "In4.Cu")
		(net 173)
	)
	(arc
		(start 192.545 118.415)
		(mid 192.66948 118.11448)
		(end 192.97 117.99)
		(width 0.15)
		(layer "In4.Cu")
		(net 173)
	)
	(arc
		(start 196.36 119.63)
		(mid 196.48448 119.329479)
		(end 196.36 119.02896)
		(width 0.15)
		(layer "In4.Cu")
		(net 173)
	)
	(arc
		(start 198.163126 117.225838)
		(mid 198.463647 117.350317)
		(end 198.764167 117.225837)
		(width 0.15)
		(layer "In4.Cu")
		(net 173)
	)
	(segment
		(start 145.212963 180.937037)
		(end 145.4 180.75)
		(width 0.177)
		(layer "F.Cu")
		(net 174)
	)
	(segment
		(start 145.212963 182.7)
		(end 145.212963 181.75)
		(width 0.177)
		(layer "F.Cu")
		(net 174)
	)
	(segment
		(start 145.259963 182.747)
		(end 145.212963 182.7)
		(width 0.177)
		(layer "F.Cu")
		(net 174)
	)
	(segment
		(start 145.4 180.75)
		(end 146.401 180.75)
		(width 0.177)
		(layer "F.Cu")
		(net 174)
	)
	(segment
		(start 145.212963 181.75)
		(end 145.212963 180.937037)
		(width 0.177)
		(layer "F.Cu")
		(net 174)
	)
	(segment
		(start 146.401 182.747)
		(end 145.4 182.747)
		(width 0.177)
		(layer "F.Cu")
		(net 174)
	)
	(segment
		(start 146.401 181.75)
		(end 145.212963 181.75)
		(width 0.177)
		(layer "F.Cu")
		(net 174)
	)
	(segment
		(start 145.4 182.747)
		(end 145.259963 182.747)
		(width 0.177)
		(layer "F.Cu")
		(net 174)
	)
	(via
		(at 145.212963 182.7)
		(size 0.45)
		(drill 0.1)
		(layers "F.Cu" "B.Cu")
		(remove_unused_layers yes)
		(keep_end_layers yes)
		(zone_layer_connections)
		(net 174)
	)
	(via
		(at 145.65 194.849501)
		(size 0.45)
		(drill 0.1)
		(layers "F.Cu" "B.Cu")
		(remove_unused_layers yes)
		(keep_end_layers yes)
		(zone_layer_connections)
		(net 174)
	)
	(segment
		(start 145.65 194.849501)
		(end 145.65 198.755)
		(width 0.256)
		(layer "B.Cu")
		(net 174)
	)
	(segment
		(start 149.024499 182.449)
		(end 151.1 184.524501)
		(width 0.1)
		(layer "In2.Cu")
		(net 174)
	)
	(segment
		(start 151.1 189.399501)
		(end 145.65 194.849501)
		(width 0.1)
		(layer "In2.Cu")
		(net 174)
	)
	(segment
		(start 151.1 184.524501)
		(end 151.1 189.399501)
		(width 0.1)
		(layer "In2.Cu")
		(net 174)
	)
	(segment
		(start 145.463963 182.449)
		(end 149.024499 182.449)
		(width 0.1)
		(layer "In2.Cu")
		(net 174)
	)
	(segment
		(start 145.212963 182.7)
		(end 145.463963 182.449)
		(width 0.1)
		(layer "In2.Cu")
		(net 174)
	)
	(segment
		(start 163.3495 194.649501)
		(end 163.3495 195.749501)
		(width 0.256)
		(layer "F.Cu")
		(net 175)
	)
	(segment
		(start 153.45 180.75)
		(end 152.299 180.75)
		(width 0.177)
		(layer "F.Cu")
		(net 175)
	)
	(segment
		(start 164.5995 194.449501)
		(end 164.2995 194.149501)
		(width 0.256)
		(layer "F.Cu")
		(net 175)
	)
	(segment
		(start 164.2995 194.149501)
		(end 163.8495 194.149501)
		(width 0.256)
		(layer "F.Cu")
		(net 175)
	)
	(segment
		(start 154.2 179.71)
		(end 154.2 180)
		(width 0.177)
		(layer "F.Cu")
		(net 175)
	)
	(segment
		(start 163.3495 195.749501)
		(end 163.65 196.050001)
		(width 0.256)
		(layer "F.Cu")
		(net 175)
	)
	(segment
		(start 154.2 180)
		(end 153.45 180.75)
		(width 0.177)
		(layer "F.Cu")
		(net 175)
	)
	(segment
		(start 163.65 196.050001)
		(end 163.65 198.755)
		(width 0.256)
		(layer "F.Cu")
		(net 175)
	)
	(segment
		(start 163.8495 194.149501)
		(end 163.3495 194.649501)
		(width 0.256)
		(layer "F.Cu")
		(net 175)
	)
	(via
		(at 154.2 179.71)
		(size 0.45)
		(drill 0.1)
		(layers "F.Cu" "B.Cu")
		(remove_unused_layers yes)
		(keep_end_layers yes)
		(zone_layer_connections)
		(net 175)
	)
	(via
		(at 164.5995 194.449501)
		(size 0.45)
		(drill 0.1)
		(layers "F.Cu" "B.Cu")
		(remove_unused_layers yes)
		(keep_end_layers yes)
		(zone_layer_connections)
		(net 175)
	)
	(segment
		(start 154.19 179.71)
		(end 151.524499 182.375501)
		(width 0.1)
		(layer "In2.Cu")
		(net 175)
	)
	(segment
		(start 151.524499 190.349)
		(end 153.874499 192.699)
		(width 0.1)
		(layer "In2.Cu")
		(net 175)
	)
	(segment
		(start 154.2 179.71)
		(end 154.19 179.71)
		(width 0.1)
		(layer "In2.Cu")
		(net 175)
	)
	(segment
		(start 153.874499 192.699)
		(end 162.848999 192.699)
		(width 0.1)
		(layer "In2.Cu")
		(net 175)
	)
	(segment
		(start 151.524499 182.375501)
		(end 151.524499 190.349)
		(width 0.1)
		(layer "In2.Cu")
		(net 175)
	)
	(segment
		(start 162.848999 192.699)
		(end 164.5995 194.449501)
		(width 0.1)
		(layer "In2.Cu")
		(net 175)
	)
	(segment
		(start 153.2 181.75)
		(end 152.299 181.75)
		(width 0.177)
		(layer "F.Cu")
		(net 176)
	)
	(segment
		(start 153.294019 181.844019)
		(end 153.45 182)
		(width 0.177)
		(layer "F.Cu")
		(net 176)
	)
	(segment
		(start 153.45 182)
		(end 153.45 182.05)
		(width 0.177)
		(layer "F.Cu")
		(net 176)
	)
	(segment
		(start 153.294019 181.844019)
		(end 153.2 181.75)
		(width 0.177)
		(layer "F.Cu")
		(net 176)
	)
	(segment
		(start 177.65 194.399001)
		(end 177.65 198.755)
		(width 0.256)
		(layer "F.Cu")
		(net 176)
	)
	(via
		(at 153.45 182.05)
		(size 0.45)
		(drill 0.1)
		(layers "F.Cu" "B.Cu")
		(remove_unused_layers yes)
		(keep_end_layers yes)
		(zone_layer_connections)
		(net 176)
	)
	(via
		(at 177.65 194.399001)
		(size 0.45)
		(drill 0.1)
		(layers "F.Cu" "B.Cu")
		(remove_unused_layers yes)
		(keep_end_layers yes)
		(zone_layer_connections)
		(net 176)
	)
	(segment
		(start 152.524499 182.975501)
		(end 152.524499 189.149)
		(width 0.1)
		(layer "In2.Cu")
		(net 176)
	)
	(segment
		(start 174.224499 189.749)
		(end 177.65 193.174501)
		(width 0.1)
		(layer "In2.Cu")
		(net 176)
	)
	(segment
		(start 153.45 182.05)
		(end 152.524499 182.975501)
		(width 0.1)
		(layer "In2.Cu")
		(net 176)
	)
	(segment
		(start 153.124499 189.749)
		(end 174.224499 189.749)
		(width 0.1)
		(layer "In2.Cu")
		(net 176)
	)
	(segment
		(start 177.65 193.174501)
		(end 177.65 194.399001)
		(width 0.1)
		(layer "In2.Cu")
		(net 176)
	)
	(segment
		(start 152.524499 189.149)
		(end 153.124499 189.749)
		(width 0.1)
		(layer "In2.Cu")
		(net 176)
	)
	(segment
		(start 242.301 111.749)
		(end 242.3 111.75)
		(width 0.256)
		(layer "F.Cu")
		(net 177)
	)
	(segment
		(start 242.301 110.598)
		(end 242.301 111.749)
		(width 0.256)
		(layer "F.Cu")
		(net 177)
	)
	(segment
		(start 198.0005 148.9995)
		(end 198.5 148.5)
		(width 0.256)
		(layer "F.Cu")
		(net 177)
	)
	(via
		(at 198.5 148.5)
		(size 0.45)
		(drill 0.1)
		(layers "F.Cu" "B.Cu")
		(remove_unused_layers yes)
		(keep_end_layers yes)
		(zone_layer_connections)
		(net 177)
	)
	(via
		(at 242.3 111.75)
		(size 0.45)
		(drill 0.1)
		(layers "F.Cu" "B.Cu")
		(remove_unused_layers yes)
		(keep_end_layers yes)
		(zone_layer_connections)
		(net 177)
	)
	(segment
		(start 199.25265 148.9)
		(end 199.35 148.9)
		(width 0.1)
		(layer "In2.Cu")
		(net 177)
	)
	(segment
		(start 235.089443 119.648938)
		(end 235.089443 119.648937)
		(width 0.13)
		(layer "In2.Cu")
		(net 177)
	)
	(segment
		(start 198.1 148.5)
		(end 198.05 148.55)
		(width 0.1)
		(layer "In2.Cu")
		(net 177)
	)
	(segment
		(start 222.650294 129.73)
		(end 216.23 136.150294)
		(width 0.13)
		(layer "In2.Cu")
		(net 177)
	)
	(segment
		(start 236.505106 120.187789)
		(end 235.966254 119.648937)
		(width 0.13)
		(layer "In2.Cu")
		(net 177)
	)
	(segment
		(start 239.870934 117.359359)
		(end 239.870935 117.359362)
		(width 0.13)
		(layer "In2.Cu")
		(net 177)
	)
	(segment
		(start 228.557225 128.673068)
		(end 228.557226 128.673067)
		(width 0.13)
		(layer "In2.Cu")
		(net 177)
	)
	(segment
		(start 232.260969 123.354127)
		(end 232.799867 123.893025)
		(width 0.13)
		(layer "In2.Cu")
		(net 177)
	)
	(segment
		(start 237.042507 120.187787)
		(end 237.042508 120.187789)
		(width 0.13)
		(layer "In2.Cu")
		(net 177)
	)
	(segment
		(start 233.675247 121.063167)
		(end 233.675247 121.063168)
		(width 0.13)
		(layer "In2.Cu")
		(net 177)
	)
	(segment
		(start 230.846748 123.891524)
		(end 230.846748 123.891523)
		(width 0.13)
		(layer "In2.Cu")
		(net 177)
	)
	(segment
		(start 203.550294 148.88)
		(end 201.855 148.88)
		(width 0.13)
		(layer "In2.Cu")
		(net 177)
	)
	(segment
		(start 247.38 106.899706)
		(end 247.38 107.91)
		(width 0.13)
		(layer "In2.Cu")
		(net 177)
	)
	(segment
		(start 229.432571 125.305774)
		(end 229.432571 125.305773)
		(width 0.13)
		(layer "In2.Cu")
		(net 177)
	)
	(segment
		(start 216.23 136.150294)
		(end 216.23 138.150294)
		(width 0.13)
		(layer "In2.Cu")
		(net 177)
	)
	(segment
		(start 199.151325 148.798674)
		(end 199.151325 148.798675)
		(width 0.1)
		(layer "In2.Cu")
		(net 177)
	)
	(segment
		(start 198.05 148.660011)
		(end 198.289989 148.9)
		(width 0.1)
		(layer "In2.Cu")
		(net 177)
	)
	(segment
		(start 198.05 148.55)
		(end 198.05 148.660011)
		(width 0.1)
		(layer "In2.Cu")
		(net 177)
	)
	(segment
		(start 241.950294 115.28)
		(end 241.285148 115.945148)
		(width 0.13)
		(layer "In2.Cu")
		(net 177)
	)
	(segment
		(start 198.289989 148.9)
		(end 198.75 148.9)
		(width 0.1)
		(layer "In2.Cu")
		(net 177)
	)
	(segment
		(start 231.385653 125.84464)
		(end 231.385654 125.844643)
		(width 0.13)
		(layer "In2.Cu")
		(net 177)
	)
	(segment
		(start 234.21408 123.016214)
		(end 234.214081 123.016216)
		(width 0.13)
		(layer "In2.Cu")
		(net 177)
	)
	(segment
		(start 244.850294 115.28)
		(end 241.950294 115.28)
		(width 0.13)
		(layer "In2.Cu")
		(net 177)
	)
	(segment
		(start 244.12 107.7)
		(end 244.12 107.049706)
		(width 0.13)
		(layer "In2.Cu")
		(net 177)
	)
	(segment
		(start 236.503642 118.234708)
		(end 236.503642 118.234709)
		(width 0.13)
		(layer "In2.Cu")
		(net 177)
	)
	(segment
		(start 237.917852 117.697302)
		(end 238.456721 118.236171)
		(width 0.13)
		(layer "In2.Cu")
		(net 177)
	)
	(segment
		(start 241.995 111.445)
		(end 241.995 110.899706)
		(width 0.13)
		(layer "In2.Cu")
		(net 177)
	)
	(segment
		(start 239.333533 117.359362)
		(end 238.794663 116.820492)
		(width 0.13)
		(layer "In2.Cu")
		(net 177)
	)
	(segment
		(start 231.385652 125.844641)
		(end 231.385653 125.84464)
		(width 0.13)
		(layer "In2.Cu")
		(net 177)
	)
	(segment
		(start 229.434038 127.258856)
		(end 228.895161 126.719979)
		(width 0.13)
		(layer "In2.Cu")
		(net 177)
	)
	(segment
		(start 244.45 107.9)
		(end 244.32 107.9)
		(width 0.13)
		(layer "In2.Cu")
		(net 177)
	)
	(segment
		(start 228.557226 128.673067)
		(end 228.557227 128.67307)
		(width 0.13)
		(layer "In2.Cu")
		(net 177)
	)
	(segment
		(start 246.950294 106.47)
		(end 247.38 106.899706)
		(width 0.13)
		(layer "In2.Cu")
		(net 177)
	)
	(segment
		(start 212.800294 138.68)
		(end 208.68 142.800294)
		(width 0.13)
		(layer "In2.Cu")
		(net 177)
	)
	(segment
		(start 244.12 107.049706)
		(end 244.699706 106.47)
		(width 0.13)
		(layer "In2.Cu")
		(net 177)
	)
	(segment
		(start 235.628295 121.602003)
		(end 235.628294 121.602002)
		(width 0.13)
		(layer "In2.Cu")
		(net 177)
	)
	(segment
		(start 242.3 111.75)
		(end 241.995 111.445)
		(width 0.13)
		(layer "In2.Cu")
		(net 177)
	)
	(segment
		(start 239.332065 115.406279)
		(end 239.332065 115.406278)
		(width 0.13)
		(layer "In2.Cu")
		(net 177)
	)
	(segment
		(start 198.95265 148.697349)
		(end 199.05 148.697349)
		(width 0.1)
		(layer "In2.Cu")
		(net 177)
	)
	(segment
		(start 234.214081 123.016214)
		(end 234.21408 123.016214)
		(width 0.13)
		(layer "In2.Cu")
		(net 177)
	)
	(segment
		(start 233.676679 123.016216)
		(end 233.13778 122.477317)
		(width 0.13)
		(layer "In2.Cu")
		(net 177)
	)
	(segment
		(start 244.699706 106.47)
		(end 246.950294 106.47)
		(width 0.13)
		(layer "In2.Cu")
		(net 177)
	)
	(segment
		(start 198.5 148.5)
		(end 198.1 148.5)
		(width 0.1)
		(layer "In2.Cu")
		(net 177)
	)
	(segment
		(start 230.846748 124.768333)
		(end 231.385653 125.307238)
		(width 0.13)
		(layer "In2.Cu")
		(net 177)
	)
	(segment
		(start 228.01835 127.596789)
		(end 228.557226 128.135665)
		(width 0.13)
		(layer "In2.Cu")
		(net 177)
	)
	(segment
		(start 216.23 138.150294)
		(end 215.700294 138.68)
		(width 0.13)
		(layer "In2.Cu")
		(net 177)
	)
	(segment
		(start 239.870933 117.35936)
		(end 239.870934 117.359359)
		(width 0.13)
		(layer "In2.Cu")
		(net 177)
	)
	(segment
		(start 237.919319 118.773575)
		(end 237.380453 118.234709)
		(width 0.13)
		(layer "In2.Cu")
		(net 177)
	)
	(segment
		(start 240.747746 115.945148)
		(end 240.208876 115.406278)
		(width 0.13)
		(layer "In2.Cu")
		(net 177)
	)
	(segment
		(start 199.35 148.9)
		(end 201.835 148.9)
		(width 0.1)
		(layer "In2.Cu")
		(net 177)
	)
	(segment
		(start 235.089443 120.525747)
		(end 235.628294 121.064598)
		(width 0.13)
		(layer "In2.Cu")
		(net 177)
	)
	(segment
		(start 243.399706 110.545)
		(end 244.12 109.824706)
		(width 0.13)
		(layer "In2.Cu")
		(net 177)
	)
	(segment
		(start 246.98 108.31)
		(end 246.98 108.41)
		(width 0.13)
		(layer "In2.Cu")
		(net 177)
	)
	(segment
		(start 237.917852 116.820493)
		(end 237.917852 116.820492)
		(width 0.13)
		(layer "In2.Cu")
		(net 177)
	)
	(segment
		(start 228.01835 126.71998)
		(end 228.01835 126.719979)
		(width 0.13)
		(layer "In2.Cu")
		(net 177)
	)
	(segment
		(start 235.090892 121.602002)
		(end 234.552058 121.063168)
		(width 0.13)
		(layer "In2.Cu")
		(net 177)
	)
	(segment
		(start 230.848252 125.844643)
		(end 230.309382 125.305773)
		(width 0.13)
		(layer "In2.Cu")
		(net 177)
	)
	(segment
		(start 239.332065 116.283088)
		(end 239.870934 116.821957)
		(width 0.13)
		(layer "In2.Cu")
		(net 177)
	)
	(segment
		(start 215.700294 138.68)
		(end 212.800294 138.68)
		(width 0.13)
		(layer "In2.Cu")
		(net 177)
	)
	(segment
		(start 242.349706 110.545)
		(end 243.399706 110.545)
		(width 0.13)
		(layer "In2.Cu")
		(net 177)
	)
	(segment
		(start 208.68 142.800294)
		(end 208.68 143.750294)
		(width 0.13)
		(layer "In2.Cu")
		(net 177)
	)
	(segment
		(start 244.12 109.824706)
		(end 244.12 108.55)
		(width 0.13)
		(layer "In2.Cu")
		(net 177)
	)
	(segment
		(start 247.38 112.750294)
		(end 244.850294 115.28)
		(width 0.13)
		(layer "In2.Cu")
		(net 177)
	)
	(segment
		(start 229.432571 126.182583)
		(end 229.97144 126.721452)
		(width 0.13)
		(layer "In2.Cu")
		(net 177)
	)
	(segment
		(start 201.835 148.9)
		(end 201.855 148.88)
		(width 0.1)
		(layer "In2.Cu")
		(net 177)
	)
	(segment
		(start 232.260969 122.477318)
		(end 232.260969 122.477317)
		(width 0.13)
		(layer "In2.Cu")
		(net 177)
	)
	(segment
		(start 198.851325 148.798675)
		(end 198.851325 148.798674)
		(width 0.1)
		(layer "In2.Cu")
		(net 177)
	)
	(segment
		(start 244.32 108.35)
		(end 244.45 108.35)
		(width 0.13)
		(layer "In2.Cu")
		(net 177)
	)
	(segment
		(start 208.68 143.750294)
		(end 203.550294 148.88)
		(width 0.13)
		(layer "In2.Cu")
		(net 177)
	)
	(segment
		(start 237.042507 120.187786)
		(end 237.042507 120.187787)
		(width 0.13)
		(layer "In2.Cu")
		(net 177)
	)
	(segment
		(start 227.500295 129.73)
		(end 222.650294 129.73)
		(width 0.13)
		(layer "In2.Cu")
		(net 177)
	)
	(segment
		(start 232.262465 124.430429)
		(end 231.723559 123.891523)
		(width 0.13)
		(layer "In2.Cu")
		(net 177)
	)
	(segment
		(start 235.628294 121.602)
		(end 235.628295 121.602003)
		(width 0.13)
		(layer "In2.Cu")
		(net 177)
	)
	(segment
		(start 236.503642 119.111519)
		(end 237.042507 119.650384)
		(width 0.13)
		(layer "In2.Cu")
		(net 177)
	)
	(segment
		(start 233.675247 121.939978)
		(end 234.21408 122.478811)
		(width 0.13)
		(layer "In2.Cu")
		(net 177)
	)
	(segment
		(start 241.995 110.899706)
		(end 242.349706 110.545)
		(width 0.13)
		(layer "In2.Cu")
		(net 177)
	)
	(segment
		(start 244.65 108.15)
		(end 244.65 108.1)
		(width 0.13)
		(layer "In2.Cu")
		(net 177)
	)
	(segment
		(start 228.557227 128.67307)
		(end 227.500295 129.73)
		(width 0.13)
		(layer "In2.Cu")
		(net 177)
	)
	(segment
		(start 247.38 108.81)
		(end 247.38 112.750294)
		(width 0.13)
		(layer "In2.Cu")
		(net 177)
	)
	(arc
		(start 239.332065 115.406278)
		(mid 239.150472 115.844683)
		(end 239.332065 116.283088)
		(width 0.13)
		(layer "In2.Cu")
		(net 177)
	)
	(arc
		(start 229.432571 125.305773)
		(mid 229.250978 125.744178)
		(end 229.432571 126.182583)
		(width 0.13)
		(layer "In2.Cu")
		(net 177)
	)
	(arc
		(start 234.552058 121.063168)
		(mid 234.113653 120.881574)
		(end 233.675247 121.063167)
		(width 0.13)
		(layer "In2.Cu")
		(net 177)
	)
	(arc
		(start 244.65 108.1)
		(mid 244.591421 107.958579)
		(end 244.45 107.9)
		(width 0.13)
		(layer "In2.Cu")
		(net 177)
	)
	(arc
		(start 238.456721 118.773575)
		(mid 238.18802 118.884875)
		(end 237.919319 118.773575)
		(width 0.13)
		(layer "In2.Cu")
		(net 177)
	)
	(arc
		(start 230.846748 123.891523)
		(mid 230.665155 124.329928)
		(end 230.846748 124.768333)
		(width 0.13)
		(layer "In2.Cu")
		(net 177)
	)
	(arc
		(start 232.799867 124.430429)
		(mid 232.531166 124.541729)
		(end 232.262465 124.430429)
		(width 0.13)
		(layer "In2.Cu")
		(net 177)
	)
	(arc
		(start 199.151325 148.798675)
		(mid 199.181002 148.870323)
		(end 199.25265 148.9)
		(width 0.1)
		(layer "In2.Cu")
		(net 177)
	)
	(arc
		(start 244.45 108.35)
		(mid 244.591421 108.291421)
		(end 244.65 108.15)
		(width 0.13)
		(layer "In2.Cu")
		(net 177)
	)
	(arc
		(start 228.895161 126.719979)
		(mid 228.456755 126.538386)
		(end 228.01835 126.71998)
		(width 0.13)
		(layer "In2.Cu")
		(net 177)
	)
	(arc
		(start 237.042508 120.187789)
		(mid 236.773807 120.299089)
		(end 236.505106 120.187789)
		(width 0.13)
		(layer "In2.Cu")
		(net 177)
	)
	(arc
		(start 234.214081 123.016216)
		(mid 233.94538 123.127516)
		(end 233.676679 123.016216)
		(width 0.13)
		(layer "In2.Cu")
		(net 177)
	)
	(arc
		(start 230.309382 125.305773)
		(mid 229.870976 125.12418)
		(end 229.432571 125.305774)
		(width 0.13)
		(layer "In2.Cu")
		(net 177)
	)
	(arc
		(start 198.851325 148.798674)
		(mid 198.881002 148.727026)
		(end 198.95265 148.697349)
		(width 0.1)
		(layer "In2.Cu")
		(net 177)
	)
	(arc
		(start 235.089443 119.648937)
		(mid 234.90785 120.087342)
		(end 235.089443 120.525747)
		(width 0.13)
		(layer "In2.Cu")
		(net 177)
	)
	(arc
		(start 241.285148 115.945148)
		(mid 241.016447 116.056448)
		(end 240.747746 115.945148)
		(width 0.13)
		(layer "In2.Cu")
		(net 177)
	)
	(arc
		(start 236.503642 118.234709)
		(mid 236.322049 118.673114)
		(end 236.503642 119.111519)
		(width 0.13)
		(layer "In2.Cu")
		(net 177)
	)
	(arc
		(start 244.32 107.9)
		(mid 244.178579 107.841421)
		(end 244.12 107.7)
		(width 0.13)
		(layer "In2.Cu")
		(net 177)
	)
	(arc
		(start 233.13778 122.477317)
		(mid 232.699374 122.295724)
		(end 232.260969 122.477318)
		(width 0.13)
		(layer "In2.Cu")
		(net 177)
	)
	(arc
		(start 199.05 148.697349)
		(mid 199.121648 148.727026)
		(end 199.151325 148.798674)
		(width 0.1)
		(layer "In2.Cu")
		(net 177)
	)
	(arc
		(start 247.38 107.91)
		(mid 247.321421 108.051421)
		(end 247.18 108.11)
		(width 0.13)
		(layer "In2.Cu")
		(net 177)
	)
	(arc
		(start 234.21408 122.478811)
		(mid 234.32538 122.747512)
		(end 234.214081 123.016214)
		(width 0.13)
		(layer "In2.Cu")
		(net 177)
	)
	(arc
		(start 247.18 108.11)
		(mid 247.038579 108.168579)
		(end 246.98 108.31)
		(width 0.13)
		(layer "In2.Cu")
		(net 177)
	)
	(arc
		(start 237.917852 116.820492)
		(mid 237.736259 117.258897)
		(end 237.917852 117.697302)
		(width 0.13)
		(layer "In2.Cu")
		(net 177)
	)
	(arc
		(start 235.628294 121.602002)
		(mid 235.359593 121.713302)
		(end 235.090892 121.602002)
		(width 0.13)
		(layer "In2.Cu")
		(net 177)
	)
	(arc
		(start 235.966254 119.648937)
		(mid 235.527848 119.467344)
		(end 235.089443 119.648938)
		(width 0.13)
		(layer "In2.Cu")
		(net 177)
	)
	(arc
		(start 239.870935 117.359362)
		(mid 239.602234 117.470662)
		(end 239.333533 117.359362)
		(width 0.13)
		(layer "In2.Cu")
		(net 177)
	)
	(arc
		(start 244.12 108.55)
		(mid 244.178579 108.408579)
		(end 244.32 108.35)
		(width 0.13)
		(layer "In2.Cu")
		(net 177)
	)
	(arc
		(start 233.675247 121.063168)
		(mid 233.493654 121.501573)
		(end 233.675247 121.939978)
		(width 0.13)
		(layer "In2.Cu")
		(net 177)
	)
	(arc
		(start 247.18 108.61)
		(mid 247.321421 108.668579)
		(end 247.38 108.81)
		(width 0.13)
		(layer "In2.Cu")
		(net 177)
	)
	(arc
		(start 237.380453 118.234709)
		(mid 236.942048 118.053115)
		(end 236.503642 118.234708)
		(width 0.13)
		(layer "In2.Cu")
		(net 177)
	)
	(arc
		(start 229.97144 126.721452)
		(mid 230.082739 126.990154)
		(end 229.971439 127.258855)
		(width 0.13)
		(layer "In2.Cu")
		(net 177)
	)
	(arc
		(start 240.208876 115.406278)
		(mid 239.77047 115.224685)
		(end 239.332065 115.406279)
		(width 0.13)
		(layer "In2.Cu")
		(net 177)
	)
	(arc
		(start 231.723559 123.891523)
		(mid 231.285153 123.70993)
		(end 230.846748 123.891524)
		(width 0.13)
		(layer "In2.Cu")
		(net 177)
	)
	(arc
		(start 239.870934 116.821957)
		(mid 239.982233 117.090659)
		(end 239.870933 117.35936)
		(width 0.13)
		(layer "In2.Cu")
		(net 177)
	)
	(arc
		(start 246.98 108.41)
		(mid 247.038579 108.551421)
		(end 247.18 108.61)
		(width 0.13)
		(layer "In2.Cu")
		(net 177)
	)
	(arc
		(start 232.260969 122.477317)
		(mid 232.079376 122.915722)
		(end 232.260969 123.354127)
		(width 0.13)
		(layer "In2.Cu")
		(net 177)
	)
	(arc
		(start 238.794663 116.820492)
		(mid 238.356257 116.638899)
		(end 237.917852 116.820493)
		(width 0.13)
		(layer "In2.Cu")
		(net 177)
	)
	(arc
		(start 229.97144 127.258856)
		(mid 229.702739 127.370156)
		(end 229.434038 127.258856)
		(width 0.13)
		(layer "In2.Cu")
		(net 177)
	)
	(arc
		(start 238.456721 118.236171)
		(mid 238.56802 118.504873)
		(end 238.45672 118.773574)
		(width 0.13)
		(layer "In2.Cu")
		(net 177)
	)
	(arc
		(start 232.799867 123.893025)
		(mid 232.911166 124.161727)
		(end 232.799866 124.430428)
		(width 0.13)
		(layer "In2.Cu")
		(net 177)
	)
	(arc
		(start 235.628294 121.064598)
		(mid 235.739594 121.333299)
		(end 235.628294 121.602)
		(width 0.13)
		(layer "In2.Cu")
		(net 177)
	)
	(arc
		(start 198.75 148.9)
		(mid 198.821648 148.870323)
		(end 198.851325 148.798675)
		(width 0.1)
		(layer "In2.Cu")
		(net 177)
	)
	(arc
		(start 231.385653 125.307238)
		(mid 231.496952 125.57594)
		(end 231.385652 125.844641)
		(width 0.13)
		(layer "In2.Cu")
		(net 177)
	)
	(arc
		(start 228.557226 128.135665)
		(mid 228.668525 128.404367)
		(end 228.557225 128.673068)
		(width 0.13)
		(layer "In2.Cu")
		(net 177)
	)
	(arc
		(start 237.042507 119.650384)
		(mid 237.153807 119.919085)
		(end 237.042507 120.187786)
		(width 0.13)
		(layer "In2.Cu")
		(net 177)
	)
	(arc
		(start 228.01835 126.719979)
		(mid 227.836757 127.158384)
		(end 228.01835 127.596789)
		(width 0.13)
		(layer "In2.Cu")
		(net 177)
	)
	(arc
		(start 231.385654 125.844643)
		(mid 231.116953 125.955943)
		(end 230.848252 125.844643)
		(width 0.13)
		(layer "In2.Cu")
		(net 177)
	)
	(segment
		(start 241.45 110.598)
		(end 241.45 111.75)
		(width 0.38)
		(layer "F.Cu")
		(net 178)
	)
	(segment
		(start 197.000499 148.9995)
		(end 197.5 148.5)
		(width 0.256)
		(layer "F.Cu")
		(net 178)
	)
	(via
		(at 241.45 111.75)
		(size 0.45)
		(drill 0.1)
		(layers "F.Cu" "B.Cu")
		(remove_unused_layers yes)
		(keep_end_layers yes)
		(zone_layer_connections)
		(net 178)
	)
	(via
		(at 197.5 148.5)
		(size 0.45)
		(drill 0.1)
		(layers "F.Cu" "B.Cu")
		(remove_unused_layers yes)
		(keep_end_layers yes)
		(zone_layer_connections)
		(net 178)
	)
	(segment
		(start 237.212211 120.357492)
		(end 237.212213 120.357494)
		(width 0.13)
		(layer "In2.Cu")
		(net 178)
	)
	(segment
		(start 212.899706 138.92)
		(end 208.92 142.899706)
		(width 0.13)
		(layer "In2.Cu")
		(net 178)
	)
	(segment
		(start 197.8 148.5)
		(end 197.85 148.55)
		(width 0.1)
		(layer "In2.Cu")
		(net 178)
	)
	(segment
		(start 237.212212 120.357492)
		(end 237.212211 120.357492)
		(width 0.13)
		(layer "In2.Cu")
		(net 178)
	)
	(segment
		(start 233.506975 123.185921)
		(end 232.968076 122.647022)
		(width 0.13)
		(layer "In2.Cu")
		(net 178)
	)
	(segment
		(start 238.087556 116.990198)
		(end 238.087557 116.990197)
		(width 0.13)
		(layer "In2.Cu")
		(net 178)
	)
	(segment
		(start 230.141144 127.42856)
		(end 230.141145 127.42856)
		(width 0.13)
		(layer "In2.Cu")
		(net 178)
	)
	(segment
		(start 201.835 149.1)
		(end 201.855 149.12)
		(width 0.1)
		(layer "In2.Cu")
		(net 178)
	)
	(segment
		(start 230.141145 127.42856)
		(end 230.141145 127.428561)
		(width 0.13)
		(layer "In2.Cu")
		(net 178)
	)
	(segment
		(start 243.300294 110.305)
		(end 243.88 109.725294)
		(width 0.13)
		(layer "In2.Cu")
		(net 178)
	)
	(segment
		(start 240.040639 117.529065)
		(end 240.04064 117.529067)
		(width 0.13)
		(layer "In2.Cu")
		(net 178)
	)
	(segment
		(start 228.188055 127.427086)
		(end 228.726931 127.965962)
		(width 0.13)
		(layer "In2.Cu")
		(net 178)
	)
	(segment
		(start 241.45 111.75)
		(end 241.755 111.445)
		(width 0.13)
		(layer "In2.Cu")
		(net 178)
	)
	(segment
		(start 232.430674 123.184424)
		(end 232.969572 123.723322)
		(width 0.13)
		(layer "In2.Cu")
		(net 178)
	)
	(segment
		(start 229.264333 127.428561)
		(end 229.264334 127.428561)
		(width 0.13)
		(layer "In2.Cu")
		(net 178)
	)
	(segment
		(start 234.383785 123.185919)
		(end 234.383784 123.185919)
		(width 0.13)
		(layer "In2.Cu")
		(net 178)
	)
	(segment
		(start 239.163828 117.529067)
		(end 239.163829 117.529067)
		(width 0.13)
		(layer "In2.Cu")
		(net 178)
	)
	(segment
		(start 231.016453 124.59863)
		(end 231.555358 125.137535)
		(width 0.13)
		(layer "In2.Cu")
		(net 178)
	)
	(segment
		(start 240.040638 117.529065)
		(end 240.040639 117.529065)
		(width 0.13)
		(layer "In2.Cu")
		(net 178)
	)
	(segment
		(start 229.264334 127.428561)
		(end 228.725457 126.889684)
		(width 0.13)
		(layer "In2.Cu")
		(net 178)
	)
	(segment
		(start 243.88 109.725294)
		(end 243.88 106.950294)
		(width 0.13)
		(layer "In2.Cu")
		(net 178)
	)
	(segment
		(start 228.72693 128.842773)
		(end 228.726931 128.842773)
		(width 0.13)
		(layer "In2.Cu")
		(net 178)
	)
	(segment
		(start 197.85 148.742855)
		(end 198.207145 149.1)
		(width 0.1)
		(layer "In2.Cu")
		(net 178)
	)
	(segment
		(start 232.092761 124.600134)
		(end 231.553855 124.061228)
		(width 0.13)
		(layer "In2.Cu")
		(net 178)
	)
	(segment
		(start 238.626425 118.943279)
		(end 238.626426 118.943279)
		(width 0.13)
		(layer "In2.Cu")
		(net 178)
	)
	(segment
		(start 230.678548 126.014348)
		(end 230.139678 125.475478)
		(width 0.13)
		(layer "In2.Cu")
		(net 178)
	)
	(segment
		(start 243.88 106.950294)
		(end 244.600294 106.23)
		(width 0.13)
		(layer "In2.Cu")
		(net 178)
	)
	(segment
		(start 236.335402 120.357494)
		(end 235.79655 119.818642)
		(width 0.13)
		(layer "In2.Cu")
		(net 178)
	)
	(segment
		(start 216.47 136.249706)
		(end 216.47 138.249706)
		(width 0.13)
		(layer "In2.Cu")
		(net 178)
	)
	(segment
		(start 236.673347 118.404414)
		(end 236.673346 118.404414)
		(width 0.13)
		(layer "In2.Cu")
		(net 178)
	)
	(segment
		(start 227.599706 129.97)
		(end 222.749706 129.97)
		(width 0.13)
		(layer "In2.Cu")
		(net 178)
	)
	(segment
		(start 239.163829 117.529067)
		(end 238.624959 116.990197)
		(width 0.13)
		(layer "In2.Cu")
		(net 178)
	)
	(segment
		(start 208.92 142.899706)
		(end 208.92 143.849706)
		(width 0.13)
		(layer "In2.Cu")
		(net 178)
	)
	(segment
		(start 229.602275 125.475479)
		(end 229.602276 125.475478)
		(width 0.13)
		(layer "In2.Cu")
		(net 178)
	)
	(segment
		(start 235.797997 121.771706)
		(end 235.797998 121.771706)
		(width 0.13)
		(layer "In2.Cu")
		(net 178)
	)
	(segment
		(start 232.969572 124.600133)
		(end 232.969572 124.600134)
		(width 0.13)
		(layer "In2.Cu")
		(net 178)
	)
	(segment
		(start 229.602276 126.01288)
		(end 230.141145 126.551749)
		(width 0.13)
		(layer "In2.Cu")
		(net 178)
	)
	(segment
		(start 237.749615 118.94328)
		(end 237.210749 118.404414)
		(width 0.13)
		(layer "In2.Cu")
		(net 178)
	)
	(segment
		(start 239.50177 116.113385)
		(end 240.040639 116.652254)
		(width 0.13)
		(layer "In2.Cu")
		(net 178)
	)
	(segment
		(start 231.555357 126.014346)
		(end 231.555358 126.014346)
		(width 0.13)
		(layer "In2.Cu")
		(net 178)
	)
	(segment
		(start 233.844951 121.232872)
		(end 233.844951 121.232873)
		(width 0.13)
		(layer "In2.Cu")
		(net 178)
	)
	(segment
		(start 233.844951 121.770275)
		(end 234.383784 122.309108)
		(width 0.13)
		(layer "In2.Cu")
		(net 178)
	)
	(segment
		(start 236.673346 118.941816)
		(end 237.212211 119.480681)
		(width 0.13)
		(layer "In2.Cu")
		(net 178)
	)
	(segment
		(start 232.09276 124.600134)
		(end 232.092761 124.600134)
		(width 0.13)
		(layer "In2.Cu")
		(net 178)
	)
	(segment
		(start 233.506974 123.185921)
		(end 233.506975 123.185921)
		(width 0.13)
		(layer "In2.Cu")
		(net 178)
	)
	(segment
		(start 242.049706 115.52)
		(end 241.454853 116.114853)
		(width 0.13)
		(layer "In2.Cu")
		(net 178)
	)
	(segment
		(start 239.501769 115.575984)
		(end 239.50177 115.575983)
		(width 0.13)
		(layer "In2.Cu")
		(net 178)
	)
	(segment
		(start 228.059853 129.509853)
		(end 227.599706 129.97)
		(width 0.13)
		(layer "In2.Cu")
		(net 178)
	)
	(segment
		(start 238.087557 117.527599)
		(end 238.626426 118.066468)
		(width 0.13)
		(layer "In2.Cu")
		(net 178)
	)
	(segment
		(start 236.335401 120.357494)
		(end 236.335402 120.357494)
		(width 0.13)
		(layer "In2.Cu")
		(net 178)
	)
	(segment
		(start 230.678547 126.014348)
		(end 230.678548 126.014348)
		(width 0.13)
		(layer "In2.Cu")
		(net 178)
	)
	(segment
		(start 228.726931 128.842773)
		(end 228.059856 129.509853)
		(width 0.13)
		(layer "In2.Cu")
		(net 178)
	)
	(segment
		(start 240.578042 116.114853)
		(end 240.039172 115.575983)
		(width 0.13)
		(layer "In2.Cu")
		(net 178)
	)
	(segment
		(start 222.749706 129.97)
		(end 216.47 136.249706)
		(width 0.13)
		(layer "In2.Cu")
		(net 178)
	)
	(segment
		(start 234.921188 121.771707)
		(end 234.382354 121.232873)
		(width 0.13)
		(layer "In2.Cu")
		(net 178)
	)
	(segment
		(start 237.749614 118.94328)
		(end 237.749615 118.94328)
		(width 0.13)
		(layer "In2.Cu")
		(net 178)
	)
	(segment
		(start 231.016452 124.061229)
		(end 231.016453 124.061228)
		(width 0.13)
		(layer "In2.Cu")
		(net 178)
	)
	(segment
		(start 216.47 138.249706)
		(end 215.799706 138.92)
		(width 0.13)
		(layer "In2.Cu")
		(net 178)
	)
	(segment
		(start 234.921187 121.771707)
		(end 234.921188 121.771707)
		(width 0.13)
		(layer "In2.Cu")
		(net 178)
	)
	(segment
		(start 234.383784 123.185919)
		(end 234.383786 123.185921)
		(width 0.13)
		(layer "In2.Cu")
		(net 178)
	)
	(segment
		(start 208.92 143.849706)
		(end 203.649706 149.12)
		(width 0.13)
		(layer "In2.Cu")
		(net 178)
	)
	(segment
		(start 235.259148 119.818642)
		(end 235.259147 119.818642)
		(width 0.13)
		(layer "In2.Cu")
		(net 178)
	)
	(segment
		(start 241.755 110.800294)
		(end 242.250294 110.305)
		(width 0.13)
		(layer "In2.Cu")
		(net 178)
	)
	(segment
		(start 247.62 106.800294)
		(end 247.62 112.849706)
		(width 0.13)
		(layer "In2.Cu")
		(net 178)
	)
	(segment
		(start 235.797998 121.771706)
		(end 235.797999 121.771707)
		(width 0.13)
		(layer "In2.Cu")
		(net 178)
	)
	(segment
		(start 242.250294 110.305)
		(end 243.300294 110.305)
		(width 0.13)
		(layer "In2.Cu")
		(net 178)
	)
	(segment
		(start 241.755 111.445)
		(end 241.755 110.800294)
		(width 0.13)
		(layer "In2.Cu")
		(net 178)
	)
	(segment
		(start 244.600294 106.23)
		(end 247.049706 106.23)
		(width 0.13)
		(layer "In2.Cu")
		(net 178)
	)
	(segment
		(start 232.430673 122.647023)
		(end 232.430674 122.647022)
		(width 0.13)
		(layer "In2.Cu")
		(net 178)
	)
	(segment
		(start 231.555358 126.014346)
		(end 231.555359 126.014348)
		(width 0.13)
		(layer "In2.Cu")
		(net 178)
	)
	(segment
		(start 247.049706 106.23)
		(end 247.62 106.800294)
		(width 0.13)
		(layer "In2.Cu")
		(net 178)
	)
	(segment
		(start 197.85 148.55)
		(end 197.85 148.742855)
		(width 0.1)
		(layer "In2.Cu")
		(net 178)
	)
	(segment
		(start 228.188054 126.889685)
		(end 228.188055 126.889684)
		(width 0.13)
		(layer "In2.Cu")
		(net 178)
	)
	(segment
		(start 240.578041 116.114853)
		(end 240.578042 116.114853)
		(width 0.13)
		(layer "In2.Cu")
		(net 178)
	)
	(segment
		(start 244.949706 115.52)
		(end 242.049706 115.52)
		(width 0.13)
		(layer "In2.Cu")
		(net 178)
	)
	(segment
		(start 228.059856 129.509853)
		(end 228.059853 129.509853)
		(width 0.13)
		(layer "In2.Cu")
		(net 178)
	)
	(segment
		(start 235.259147 120.356044)
		(end 235.797998 120.894895)
		(width 0.13)
		(layer "In2.Cu")
		(net 178)
	)
	(segment
		(start 232.969571 124.600133)
		(end 232.969572 124.600133)
		(width 0.13)
		(layer "In2.Cu")
		(net 178)
	)
	(segment
		(start 197.5 148.5)
		(end 197.8 148.5)
		(width 0.1)
		(layer "In2.Cu")
		(net 178)
	)
	(segment
		(start 238.626426 118.943279)
		(end 238.626426 118.94328)
		(width 0.13)
		(layer "In2.Cu")
		(net 178)
	)
	(segment
		(start 203.649706 149.12)
		(end 201.855 149.12)
		(width 0.13)
		(layer "In2.Cu")
		(net 178)
	)
	(segment
		(start 247.62 112.849706)
		(end 244.949706 115.52)
		(width 0.13)
		(layer "In2.Cu")
		(net 178)
	)
	(segment
		(start 198.207145 149.1)
		(end 201.835 149.1)
		(width 0.1)
		(layer "In2.Cu")
		(net 178)
	)
	(segment
		(start 215.799706 138.92)
		(end 212.899706 138.92)
		(width 0.13)
		(layer "In2.Cu")
		(net 178)
	)
	(arc
		(start 232.969572 123.723322)
		(mid 233.151165 124.161728)
		(end 232.969571 124.600133)
		(width 0.13)
		(layer "In2.Cu")
		(net 178)
	)
	(arc
		(start 231.555359 126.014348)
		(mid 231.116953 126.195942)
		(end 230.678547 126.014348)
		(width 0.13)
		(layer "In2.Cu")
		(net 178)
	)
	(arc
		(start 232.430674 122.647022)
		(mid 232.319374 122.915723)
		(end 232.430674 123.184424)
		(width 0.13)
		(layer "In2.Cu")
		(net 178)
	)
	(arc
		(start 232.969572 124.600134)
		(mid 232.531166 124.781728)
		(end 232.09276 124.600134)
		(width 0.13)
		(layer "In2.Cu")
		(net 178)
	)
	(arc
		(start 234.382354 121.232873)
		(mid 234.113653 121.121573)
		(end 233.844951 121.232872)
		(width 0.13)
		(layer "In2.Cu")
		(net 178)
	)
	(arc
		(start 229.602276 125.475478)
		(mid 229.490976 125.744179)
		(end 229.602276 126.01288)
		(width 0.13)
		(layer "In2.Cu")
		(net 178)
	)
	(arc
		(start 231.016453 124.061228)
		(mid 230.905153 124.329929)
		(end 231.016453 124.59863)
		(width 0.13)
		(layer "In2.Cu")
		(net 178)
	)
	(arc
		(start 230.141145 127.428561)
		(mid 229.702739 127.610155)
		(end 229.264333 127.428561)
		(width 0.13)
		(layer "In2.Cu")
		(net 178)
	)
	(arc
		(start 239.50177 115.575983)
		(mid 239.39047 115.844684)
		(end 239.50177 116.113385)
		(width 0.13)
		(layer "In2.Cu")
		(net 178)
	)
	(arc
		(start 235.79655 119.818642)
		(mid 235.527849 119.707342)
		(end 235.259148 119.818642)
		(width 0.13)
		(layer "In2.Cu")
		(net 178)
	)
	(arc
		(start 236.673346 118.404414)
		(mid 236.562046 118.673115)
		(end 236.673346 118.941816)
		(width 0.13)
		(layer "In2.Cu")
		(net 178)
	)
	(arc
		(start 240.039172 115.575983)
		(mid 239.77047 115.464684)
		(end 239.501769 115.575984)
		(width 0.13)
		(layer "In2.Cu")
		(net 178)
	)
	(arc
		(start 238.624959 116.990197)
		(mid 238.356257 116.878898)
		(end 238.087556 116.990198)
		(width 0.13)
		(layer "In2.Cu")
		(net 178)
	)
	(arc
		(start 235.797999 121.771707)
		(mid 235.359593 121.953301)
		(end 234.921187 121.771707)
		(width 0.13)
		(layer "In2.Cu")
		(net 178)
	)
	(arc
		(start 240.04064 117.529067)
		(mid 239.602234 117.710661)
		(end 239.163828 117.529067)
		(width 0.13)
		(layer "In2.Cu")
		(net 178)
	)
	(arc
		(start 230.139678 125.475478)
		(mid 229.870976 125.364179)
		(end 229.602275 125.475479)
		(width 0.13)
		(layer "In2.Cu")
		(net 178)
	)
	(arc
		(start 238.626426 118.066468)
		(mid 238.808019 118.504874)
		(end 238.626425 118.943279)
		(width 0.13)
		(layer "In2.Cu")
		(net 178)
	)
	(arc
		(start 240.040639 116.652254)
		(mid 240.222232 117.09066)
		(end 240.040638 117.529065)
		(width 0.13)
		(layer "In2.Cu")
		(net 178)
	)
	(arc
		(start 238.626426 118.94328)
		(mid 238.18802 119.124874)
		(end 237.749614 118.94328)
		(width 0.13)
		(layer "In2.Cu")
		(net 178)
	)
	(arc
		(start 238.087557 116.990197)
		(mid 237.976257 117.258898)
		(end 238.087557 117.527599)
		(width 0.13)
		(layer "In2.Cu")
		(net 178)
	)
	(arc
		(start 228.726931 127.965962)
		(mid 228.908524 128.404368)
		(end 228.72693 128.842773)
		(width 0.13)
		(layer "In2.Cu")
		(net 178)
	)
	(arc
		(start 235.259147 119.818642)
		(mid 235.147847 120.087343)
		(end 235.259147 120.356044)
		(width 0.13)
		(layer "In2.Cu")
		(net 178)
	)
	(arc
		(start 235.797998 120.894895)
		(mid 235.979591 121.333301)
		(end 235.797997 121.771706)
		(width 0.13)
		(layer "In2.Cu")
		(net 178)
	)
	(arc
		(start 237.212213 120.357494)
		(mid 236.773807 120.539088)
		(end 236.335401 120.357494)
		(width 0.13)
		(layer "In2.Cu")
		(net 178)
	)
	(arc
		(start 232.968076 122.647022)
		(mid 232.699374 122.535723)
		(end 232.430673 122.647023)
		(width 0.13)
		(layer "In2.Cu")
		(net 178)
	)
	(arc
		(start 241.454853 116.114853)
		(mid 241.016447 116.296447)
		(end 240.578041 116.114853)
		(width 0.13)
		(layer "In2.Cu")
		(net 178)
	)
	(arc
		(start 230.141145 126.551749)
		(mid 230.322738 126.990155)
		(end 230.141144 127.42856)
		(width 0.13)
		(layer "In2.Cu")
		(net 178)
	)
	(arc
		(start 228.188055 126.889684)
		(mid 228.076755 127.158385)
		(end 228.188055 127.427086)
		(width 0.13)
		(layer "In2.Cu")
		(net 178)
	)
	(arc
		(start 234.383784 122.309108)
		(mid 234.565378 122.747513)
		(end 234.383785 123.185919)
		(width 0.13)
		(layer "In2.Cu")
		(net 178)
	)
	(arc
		(start 231.553855 124.061228)
		(mid 231.285153 123.949929)
		(end 231.016452 124.061229)
		(width 0.13)
		(layer "In2.Cu")
		(net 178)
	)
	(arc
		(start 237.210749 118.404414)
		(mid 236.942048 118.293114)
		(end 236.673347 118.404414)
		(width 0.13)
		(layer "In2.Cu")
		(net 178)
	)
	(arc
		(start 234.383786 123.185921)
		(mid 233.94538 123.367515)
		(end 233.506974 123.185921)
		(width 0.13)
		(layer "In2.Cu")
		(net 178)
	)
	(arc
		(start 228.725457 126.889684)
		(mid 228.456755 126.778385)
		(end 228.188054 126.889685)
		(width 0.13)
		(layer "In2.Cu")
		(net 178)
	)
	(arc
		(start 237.212211 119.480681)
		(mid 237.393805 119.919086)
		(end 237.212212 120.357492)
		(width 0.13)
		(layer "In2.Cu")
		(net 178)
	)
	(arc
		(start 233.844951 121.232873)
		(mid 233.733651 121.501574)
		(end 233.844951 121.770275)
		(width 0.13)
		(layer "In2.Cu")
		(net 178)
	)
	(arc
		(start 231.555358 125.137535)
		(mid 231.736951 125.575941)
		(end 231.555357 126.014346)
		(width 0.13)
		(layer "In2.Cu")
		(net 178)
	)
	(segment
		(start 248.625 145.35)
		(end 249.223499 145.35)
		(width 0.177)
		(layer "F.Cu")
		(net 179)
	)
	(segment
		(start 201.5 151.5)
		(end 201.0005 151.9995)
		(width 0.256)
		(layer "F.Cu")
		(net 179)
	)
	(via
		(at 248.625 145.35)
		(size 0.45)
		(drill 0.1)
		(layers "F.Cu" "B.Cu")
		(remove_unused_layers yes)
		(keep_end_layers yes)
		(zone_layer_connections)
		(net 179)
	)
	(via
		(at 201.5 151.5)
		(size 0.45)
		(drill 0.1)
		(layers "F.Cu" "B.Cu")
		(remove_unused_layers yes)
		(keep_end_layers yes)
		(zone_layer_connections)
		(net 179)
	)
	(segment
		(start 248.45 145.35)
		(end 248.625 145.35)
		(width 0.1)
		(layer "In6.Cu")
		(net 179)
	)
	(segment
		(start 201.88 151.5)
		(end 203.86574 149.51426)
		(width 0.1)
		(layer "In6.Cu")
		(net 179)
	)
	(segment
		(start 222.81 149.81)
		(end 223.2 150.2)
		(width 0.1)
		(layer "In6.Cu")
		(net 179)
	)
	(segment
		(start 241.01 150.2)
		(end 244.01 147.2)
		(width 0.1)
		(layer "In6.Cu")
		(net 179)
	)
	(segment
		(start 210.67 148.24)
		(end 217 148.24)
		(width 0.1)
		(layer "In6.Cu")
		(net 179)
	)
	(segment
		(start 203.86574 149.51426)
		(end 209.39574 149.51426)
		(width 0.1)
		(layer "In6.Cu")
		(net 179)
	)
	(segment
		(start 244.01 147.2)
		(end 246.6 147.2)
		(width 0.1)
		(layer "In6.Cu")
		(net 179)
	)
	(segment
		(start 217 148.24)
		(end 218.57 149.81)
		(width 0.1)
		(layer "In6.Cu")
		(net 179)
	)
	(segment
		(start 209.39574 149.51426)
		(end 210.67 148.24)
		(width 0.1)
		(layer "In6.Cu")
		(net 179)
	)
	(segment
		(start 218.57 149.81)
		(end 222.81 149.81)
		(width 0.1)
		(layer "In6.Cu")
		(net 179)
	)
	(segment
		(start 223.2 150.2)
		(end 241.01 150.2)
		(width 0.1)
		(layer "In6.Cu")
		(net 179)
	)
	(segment
		(start 201.5 151.5)
		(end 201.88 151.5)
		(width 0.1)
		(layer "In6.Cu")
		(net 179)
	)
	(segment
		(start 246.6 147.2)
		(end 248.45 145.35)
		(width 0.1)
		(layer "In6.Cu")
		(net 179)
	)
	(segment
		(start 248.675 139.95)
		(end 249.223499 139.95)
		(width 0.1)
		(layer "F.Cu")
		(net 180)
	)
	(segment
		(start 200.0005 153.0005)
		(end 200.500001 153.5)
		(width 0.256)
		(layer "F.Cu")
		(net 180)
	)
	(via
		(at 200.500001 153.5)
		(size 0.45)
		(drill 0.1)
		(layers "F.Cu" "B.Cu")
		(remove_unused_layers yes)
		(keep_end_layers yes)
		(zone_layer_connections)
		(net 180)
	)
	(via
		(at 248.675 139.95)
		(size 0.45)
		(drill 0.1)
		(layers "F.Cu" "B.Cu")
		(remove_unused_layers yes)
		(keep_end_layers yes)
		(zone_layer_connections)
		(net 180)
	)
	(segment
		(start 206.55 153.65)
		(end 206.071079 153.171079)
		(width 0.1)
		(layer "In2.Cu")
		(net 180)
	)
	(segment
		(start 206.071079 153.171079)
		(end 205.246079 153.171079)
		(width 0.1)
		(layer "In2.Cu")
		(net 180)
	)
	(segment
		(start 245.849 138.726)
		(end 244.975 139.6)
		(width 0.1)
		(layer "In2.Cu")
		(net 180)
	)
	(segment
		(start 216.5 148)
		(end 214.7 149.8)
		(width 0.1)
		(layer "In2.Cu")
		(net 180)
	)
	(segment
		(start 204.035 152.865)
		(end 203.65 153.25)
		(width 0.1)
		(layer "In2.Cu")
		(net 180)
	)
	(segment
		(start 209.6 153.3)
		(end 208.55 153.3)
		(width 0.1)
		(layer "In2.Cu")
		(net 180)
	)
	(segment
		(start 200.875001 153.125)
		(end 200.500001 153.5)
		(width 0.1)
		(layer "In2.Cu")
		(net 180)
	)
	(segment
		(start 248.675 139.341669)
		(end 248.059331 138.726)
		(width 0.1)
		(layer "In2.Cu")
		(net 180)
	)
	(segment
		(start 205.246079 153.171079)
		(end 204.94 152.865)
		(width 0.1)
		(layer "In2.Cu")
		(net 180)
	)
	(segment
		(start 235.2 141.3)
		(end 231.15 145.35)
		(width 0.1)
		(layer "In2.Cu")
		(net 180)
	)
	(segment
		(start 208.2 153.65)
		(end 206.55 153.65)
		(width 0.1)
		(layer "In2.Cu")
		(net 180)
	)
	(segment
		(start 217.375 147.525)
		(end 216.9 148)
		(width 0.1)
		(layer "In2.Cu")
		(net 180)
	)
	(segment
		(start 210.075584 152.024416)
		(end 210.075584 152.824416)
		(width 0.1)
		(layer "In2.Cu")
		(net 180)
	)
	(segment
		(start 237.935335 141.3)
		(end 235.2 141.3)
		(width 0.1)
		(layer "In2.Cu")
		(net 180)
	)
	(segment
		(start 231.15 145.35)
		(end 218.55 145.35)
		(width 0.1)
		(layer "In2.Cu")
		(net 180)
	)
	(segment
		(start 214.7 150.9)
		(end 214.2 151.4)
		(width 0.1)
		(layer "In2.Cu")
		(net 180)
	)
	(segment
		(start 208.55 153.3)
		(end 208.2 153.65)
		(width 0.1)
		(layer "In2.Cu")
		(net 180)
	)
	(segment
		(start 204.94 152.865)
		(end 204.035 152.865)
		(width 0.1)
		(layer "In2.Cu")
		(net 180)
	)
	(segment
		(start 248.675 139.95)
		(end 248.675 139.341669)
		(width 0.1)
		(layer "In2.Cu")
		(net 180)
	)
	(segment
		(start 214.2 151.4)
		(end 210.7 151.4)
		(width 0.1)
		(layer "In2.Cu")
		(net 180)
	)
	(segment
		(start 201.780331 153.25)
		(end 201.655331 153.125)
		(width 0.1)
		(layer "In2.Cu")
		(net 180)
	)
	(segment
		(start 214.7 149.8)
		(end 214.7 150.9)
		(width 0.1)
		(layer "In2.Cu")
		(net 180)
	)
	(segment
		(start 210.7 151.4)
		(end 210.075584 152.024416)
		(width 0.1)
		(layer "In2.Cu")
		(net 180)
	)
	(segment
		(start 244.975 139.6)
		(end 239.635335 139.6)
		(width 0.1)
		(layer "In2.Cu")
		(net 180)
	)
	(segment
		(start 216.9 148)
		(end 216.5 148)
		(width 0.1)
		(layer "In2.Cu")
		(net 180)
	)
	(segment
		(start 203.65 153.25)
		(end 201.780331 153.25)
		(width 0.1)
		(layer "In2.Cu")
		(net 180)
	)
	(segment
		(start 210.075584 152.824416)
		(end 209.6 153.3)
		(width 0.1)
		(layer "In2.Cu")
		(net 180)
	)
	(segment
		(start 239.635335 139.6)
		(end 237.935335 141.3)
		(width 0.1)
		(layer "In2.Cu")
		(net 180)
	)
	(segment
		(start 217.375 146.525)
		(end 217.375 147.525)
		(width 0.1)
		(layer "In2.Cu")
		(net 180)
	)
	(segment
		(start 218.55 145.35)
		(end 217.375 146.525)
		(width 0.1)
		(layer "In2.Cu")
		(net 180)
	)
	(segment
		(start 201.655331 153.125)
		(end 200.875001 153.125)
		(width 0.1)
		(layer "In2.Cu")
		(net 180)
	)
	(segment
		(start 248.059331 138.726)
		(end 245.849 138.726)
		(width 0.1)
		(layer "In2.Cu")
		(net 180)
	)
	(segment
		(start 199.0005 147.9995)
		(end 199.5 147.5)
		(width 0.256)
		(layer "F.Cu")
		(net 181)
	)
	(segment
		(start 232.95 110.598)
		(end 232.95 111.75)
		(width 0.38)
		(layer "F.Cu")
		(net 181)
	)
	(via
		(at 199.5 147.5)
		(size 0.45)
		(drill 0.1)
		(layers "F.Cu" "B.Cu")
		(remove_unused_layers yes)
		(keep_end_layers yes)
		(zone_layer_connections)
		(net 181)
	)
	(via
		(at 232.95 111.75)
		(size 0.45)
		(drill 0.1)
		(layers "F.Cu" "B.Cu")
		(remove_unused_layers yes)
		(keep_end_layers yes)
		(zone_layer_connections)
		(net 181)
	)
	(segment
		(start 226.01 117.275)
		(end 226.01 119.957738)
		(width 0.13)
		(layer "In4.Cu")
		(net 181)
	)
	(segment
		(start 198.09 144.359422)
		(end 198.09 146.716578)
		(width 0.1)
		(layer "In4.Cu")
		(net 181)
	)
	(segment
		(start 199.1 147.4)
		(end 199.1985 147.4985)
		(width 0.1)
		(layer "In4.Cu")
		(net 181)
	)
	(segment
		(start 221.81 117.275)
		(end 221.81 119.957738)
		(width 0.13)
		(layer "In4.Cu")
		(net 181)
	)
	(segment
		(start 228.397636 116.865)
		(end 232.645 112.617636)
		(width 0.13)
		(layer "In4.Cu")
		(net 181)
	)
	(segment
		(start 232.645 112.055)
		(end 232.95 111.75)
		(width 0.13)
		(layer "In4.Cu")
		(net 181)
	)
	(segment
		(start 198.341422 144.108)
		(end 198.09 144.359422)
		(width 0.1)
		(layer "In4.Cu")
		(net 181)
	)
	(segment
		(start 213.397636 135.965)
		(end 216.565 132.797636)
		(width 0.13)
		(layer "In4.Cu")
		(net 181)
	)
	(segment
		(start 198.261422 146.888)
		(end 198.791422 146.888)
		(width 0.1)
		(layer "In4.Cu")
		(net 181)
	)
	(segment
		(start 199.1985 147.4985)
		(end 199.4995 147.4985)
		(width 0.1)
		(layer "In4.Cu")
		(net 181)
	)
	(segment
		(start 232.645 112.617636)
		(end 232.645 112.055)
		(width 0.13)
		(layer "In4.Cu")
		(net 181)
	)
	(segment
		(start 201.7 144.12)
		(end 203.999706 144.12)
		(width 0.13)
		(layer "In4.Cu")
		(net 181)
	)
	(segment
		(start 199.1 147.196578)
		(end 199.1 147.4)
		(width 0.1)
		(layer "In4.Cu")
		(net 181)
	)
	(segment
		(start 201.688 144.108)
		(end 198.341422 144.108)
		(width 0.1)
		(layer "In4.Cu")
		(net 181)
	)
	(segment
		(start 223.09 119.957738)
		(end 223.09 117.275)
		(width 0.13)
		(layer "In4.Cu")
		(net 181)
	)
	(segment
		(start 220.165 117.897636)
		(end 221.197636 116.865)
		(width 0.13)
		(layer "In4.Cu")
		(net 181)
	)
	(segment
		(start 203.999706 144.12)
		(end 205.965 142.154706)
		(width 0.13)
		(layer "In4.Cu")
		(net 181)
	)
	(segment
		(start 220.165 120.997636)
		(end 220.165 117.897636)
		(width 0.13)
		(layer "In4.Cu")
		(net 181)
	)
	(segment
		(start 198.791422 146.888)
		(end 199.1 147.196578)
		(width 0.1)
		(layer "In4.Cu")
		(net 181)
	)
	(segment
		(start 201.7 144.12)
		(end 201.688 144.108)
		(width 0.1)
		(layer "In4.Cu")
		(net 181)
	)
	(segment
		(start 216.565 124.597636)
		(end 220.165 120.997636)
		(width 0.13)
		(layer "In4.Cu")
		(net 181)
	)
	(segment
		(start 216.565 132.797636)
		(end 216.565 124.597636)
		(width 0.13)
		(layer "In4.Cu")
		(net 181)
	)
	(segment
		(start 198.09 146.716578)
		(end 198.261422 146.888)
		(width 0.1)
		(layer "In4.Cu")
		(net 181)
	)
	(segment
		(start 225.19 119.957738)
		(end 225.19 117.275)
		(width 0.13)
		(layer "In4.Cu")
		(net 181)
	)
	(segment
		(start 221.197636 116.865)
		(end 221.4 116.865)
		(width 0.13)
		(layer "In4.Cu")
		(net 181)
	)
	(segment
		(start 207.497636 135.965)
		(end 213.397636 135.965)
		(width 0.13)
		(layer "In4.Cu")
		(net 181)
	)
	(segment
		(start 205.965 137.497636)
		(end 207.497636 135.965)
		(width 0.13)
		(layer "In4.Cu")
		(net 181)
	)
	(segment
		(start 205.965 142.154706)
		(end 205.965 137.497636)
		(width 0.13)
		(layer "In4.Cu")
		(net 181)
	)
	(segment
		(start 228.046837 116.865)
		(end 228.397636 116.865)
		(width 0.13)
		(layer "In4.Cu")
		(net 181)
	)
	(segment
		(start 227.29 119.957738)
		(end 227.29 117.275)
		(width 0.13)
		(layer "In4.Cu")
		(net 181)
	)
	(segment
		(start 227.7 116.865)
		(end 228.046837 116.865)
		(width 0.13)
		(layer "In4.Cu")
		(net 181)
	)
	(segment
		(start 223.91 117.275)
		(end 223.91 119.957738)
		(width 0.13)
		(layer "In4.Cu")
		(net 181)
	)
	(arc
		(start 226.01 119.957738)
		(mid 226.197452 120.410286)
		(end 226.65 120.597738)
		(width 0.13)
		(layer "In4.Cu")
		(net 181)
	)
	(arc
		(start 221.4 116.865)
		(mid 221.689914 116.985086)
		(end 221.81 117.275)
		(width 0.13)
		(layer "In4.Cu")
		(net 181)
	)
	(arc
		(start 223.09 117.275)
		(mid 223.210086 116.985086)
		(end 223.5 116.865)
		(width 0.13)
		(layer "In4.Cu")
		(net 181)
	)
	(arc
		(start 223.91 119.957738)
		(mid 224.097452 120.410286)
		(end 224.55 120.597738)
		(width 0.13)
		(layer "In4.Cu")
		(net 181)
	)
	(arc
		(start 222.45 120.597738)
		(mid 222.902548 120.410286)
		(end 223.09 119.957738)
		(width 0.13)
		(layer "In4.Cu")
		(net 181)
	)
	(arc
		(start 221.81 119.957738)
		(mid 221.997452 120.410286)
		(end 222.45 120.597738)
		(width 0.13)
		(layer "In4.Cu")
		(net 181)
	)
	(arc
		(start 223.5 116.865)
		(mid 223.789914 116.985086)
		(end 223.91 117.275)
		(width 0.13)
		(layer "In4.Cu")
		(net 181)
	)
	(arc
		(start 226.65 120.597738)
		(mid 227.102548 120.410286)
		(end 227.29 119.957738)
		(width 0.13)
		(layer "In4.Cu")
		(net 181)
	)
	(arc
		(start 227.29 117.275)
		(mid 227.410086 116.985086)
		(end 227.7 116.865)
		(width 0.13)
		(layer "In4.Cu")
		(net 181)
	)
	(arc
		(start 225.19 117.275)
		(mid 225.310086 116.985086)
		(end 225.6 116.865)
		(width 0.13)
		(layer "In4.Cu")
		(net 181)
	)
	(arc
		(start 225.6 116.865)
		(mid 225.889914 116.985086)
		(end 226.01 117.275)
		(width 0.13)
		(layer "In4.Cu")
		(net 181)
	)
	(arc
		(start 224.55 120.597738)
		(mid 225.002548 120.410286)
		(end 225.19 119.957738)
		(width 0.13)
		(layer "In4.Cu")
		(net 181)
	)
	(segment
		(start 232.1 110.598)
		(end 232.1 111.75)
		(width 0.38)
		(layer "F.Cu")
		(net 182)
	)
	(segment
		(start 198.0005 147.9995)
		(end 198.5 147.499999)
		(width 0.256)
		(layer "F.Cu")
		(net 182)
	)
	(via
		(at 198.5 147.499999)
		(size 0.45)
		(drill 0.1)
		(layers "F.Cu" "B.Cu")
		(remove_unused_layers yes)
		(keep_end_layers yes)
		(zone_layer_connections)
		(net 182)
	)
	(via
		(at 232.1 111.75)
		(size 0.45)
		(drill 0.1)
		(layers "F.Cu" "B.Cu")
		(remove_unused_layers yes)
		(keep_end_layers yes)
		(zone_layer_connections)
		(net 182)
	)
	(segment
		(start 219.935 117.802364)
		(end 221.102364 116.635)
		(width 0.13)
		(layer "In4.Cu")
		(net 182)
	)
	(segment
		(start 198.9 147.388)
		(end 198.9 147.279422)
		(width 0.1)
		(layer "In4.Cu")
		(net 182)
	)
	(segment
		(start 222.86 119.957738)
		(end 222.86 117.275)
		(width 0.13)
		(layer "In4.Cu")
		(net 182)
	)
	(segment
		(start 207.402364 135.735)
		(end 213.302364 135.735)
		(width 0.13)
		(layer "In4.Cu")
		(net 182)
	)
	(segment
		(start 197.89 146.799422)
		(end 197.89 144.276578)
		(width 0.1)
		(layer "In4.Cu")
		(net 182)
	)
	(segment
		(start 219.935 120.902364)
		(end 219.935 117.802364)
		(width 0.13)
		(layer "In4.Cu")
		(net 182)
	)
	(segment
		(start 222.04 117.275)
		(end 222.04 119.957738)
		(width 0.13)
		(layer "In4.Cu")
		(net 182)
	)
	(segment
		(start 224.14 117.275)
		(end 224.14 119.957738)
		(width 0.13)
		(layer "In4.Cu")
		(net 182)
	)
	(segment
		(start 198.56423 147.4985)
		(end 198.56473 147.498)
		(width 0.1)
		(layer "In4.Cu")
		(net 182)
	)
	(segment
		(start 216.335 132.702364)
		(end 216.335 124.502364)
		(width 0.13)
		(layer "In4.Cu")
		(net 182)
	)
	(segment
		(start 232.405 112.532364)
		(end 232.405 112.055)
		(width 0.13)
		(layer "In4.Cu")
		(net 182)
	)
	(segment
		(start 213.302364 135.735)
		(end 216.335 132.702364)
		(width 0.13)
		(layer "In4.Cu")
		(net 182)
	)
	(segment
		(start 205.735 137.402364)
		(end 207.402364 135.735)
		(width 0.13)
		(layer "In4.Cu")
		(net 182)
	)
	(segment
		(start 198.258578 143.908)
		(end 201.607944 143.908)
		(width 0.1)
		(layer "In4.Cu")
		(net 182)
	)
	(segment
		(start 198.4995 147.4985)
		(end 198.56423 147.4985)
		(width 0.1)
		(layer "In4.Cu")
		(net 182)
	)
	(segment
		(start 198.79 147.498)
		(end 198.9 147.388)
		(width 0.1)
		(layer "In4.Cu")
		(net 182)
	)
	(segment
		(start 198.708578 147.088)
		(end 198.178578 147.088)
		(width 0.1)
		(layer "In4.Cu")
		(net 182)
	)
	(segment
		(start 201.607944 143.908)
		(end 201.610944 143.905)
		(width 0.1)
		(layer "In4.Cu")
		(net 182)
	)
	(segment
		(start 201.610944 143.905)
		(end 201.675 143.905)
		(width 0.1)
		(layer "In4.Cu")
		(net 182)
	)
	(segment
		(start 221.102364 116.635)
		(end 221.4 116.635)
		(width 0.13)
		(layer "In4.Cu")
		(net 182)
	)
	(segment
		(start 224.96 119.957738)
		(end 224.96 117.275)
		(width 0.13)
		(layer "In4.Cu")
		(net 182)
	)
	(segment
		(start 198.9 147.279422)
		(end 198.708578 147.088)
		(width 0.1)
		(layer "In4.Cu")
		(net 182)
	)
	(segment
		(start 197.89 144.276578)
		(end 198.258578 143.908)
		(width 0.1)
		(layer "In4.Cu")
		(net 182)
	)
	(segment
		(start 232.405 112.055)
		(end 232.1 111.75)
		(width 0.13)
		(layer "In4.Cu")
		(net 182)
	)
	(segment
		(start 228.046837 116.635)
		(end 228.302364 116.635)
		(width 0.13)
		(layer "In4.Cu")
		(net 182)
	)
	(segment
		(start 205.735 142.045294)
		(end 205.735 137.402364)
		(width 0.13)
		(layer "In4.Cu")
		(net 182)
	)
	(segment
		(start 198.56473 147.498)
		(end 198.79 147.498)
		(width 0.1)
		(layer "In4.Cu")
		(net 182)
	)
	(segment
		(start 227.06 119.957738)
		(end 227.06 117.275)
		(width 0.13)
		(layer "In4.Cu")
		(net 182)
	)
	(segment
		(start 201.675 143.905)
		(end 201.7 143.88)
		(width 0.1)
		(layer "In4.Cu")
		(net 182)
	)
	(segment
		(start 201.7 143.88)
		(end 203.900294 143.88)
		(width 0.13)
		(layer "In4.Cu")
		(net 182)
	)
	(segment
		(start 226.24 117.275)
		(end 226.24 119.957738)
		(width 0.13)
		(layer "In4.Cu")
		(net 182)
	)
	(segment
		(start 198.178578 147.088)
		(end 197.89 146.799422)
		(width 0.1)
		(layer "In4.Cu")
		(net 182)
	)
	(segment
		(start 203.900294 143.88)
		(end 205.735 142.045294)
		(width 0.13)
		(layer "In4.Cu")
		(net 182)
	)
	(segment
		(start 216.335 124.502364)
		(end 219.935 120.902364)
		(width 0.13)
		(layer "In4.Cu")
		(net 182)
	)
	(segment
		(start 227.7 116.635)
		(end 228.046837 116.635)
		(width 0.13)
		(layer "In4.Cu")
		(net 182)
	)
	(segment
		(start 228.302364 116.635)
		(end 232.405 112.532364)
		(width 0.13)
		(layer "In4.Cu")
		(net 182)
	)
	(arc
		(start 221.4 116.635)
		(mid 221.852548 116.822452)
		(end 222.04 117.275)
		(width 0.13)
		(layer "In4.Cu")
		(net 182)
	)
	(arc
		(start 222.86 117.275)
		(mid 223.047452 116.822452)
		(end 223.5 116.635)
		(width 0.13)
		(layer "In4.Cu")
		(net 182)
	)
	(arc
		(start 222.45 120.367738)
		(mid 222.739914 120.247652)
		(end 222.86 119.957738)
		(width 0.13)
		(layer "In4.Cu")
		(net 182)
	)
	(arc
		(start 225.6 116.635)
		(mid 226.052548 116.822452)
		(end 226.24 117.275)
		(width 0.13)
		(layer "In4.Cu")
		(net 182)
	)
	(arc
		(start 224.55 120.367738)
		(mid 224.839914 120.247652)
		(end 224.96 119.957738)
		(width 0.13)
		(layer "In4.Cu")
		(net 182)
	)
	(arc
		(start 226.65 120.367738)
		(mid 226.939914 120.247652)
		(end 227.06 119.957738)
		(width 0.13)
		(layer "In4.Cu")
		(net 182)
	)
	(arc
		(start 226.24 119.957738)
		(mid 226.360086 120.247652)
		(end 226.65 120.367738)
		(width 0.13)
		(layer "In4.Cu")
		(net 182)
	)
	(arc
		(start 223.5 116.635)
		(mid 223.952548 116.822452)
		(end 224.14 117.275)
		(width 0.13)
		(layer "In4.Cu")
		(net 182)
	)
	(arc
		(start 222.04 119.957738)
		(mid 222.160086 120.247652)
		(end 222.45 120.367738)
		(width 0.13)
		(layer "In4.Cu")
		(net 182)
	)
	(arc
		(start 227.06 117.275)
		(mid 227.247452 116.822452)
		(end 227.7 116.635)
		(width 0.13)
		(layer "In4.Cu")
		(net 182)
	)
	(arc
		(start 224.14 119.957738)
		(mid 224.260086 120.247652)
		(end 224.55 120.367738)
		(width 0.13)
		(layer "In4.Cu")
		(net 182)
	)
	(arc
		(start 224.96 117.275)
		(mid 225.147452 116.822452)
		(end 225.6 116.635)
		(width 0.13)
		(layer "In4.Cu")
		(net 182)
	)
	(segment
		(start 120.4 117.15)
		(end 120.4 116.487461)
		(width 0.15)
		(layer "F.Cu")
		(net 183)
	)
	(via
		(at 120.4 117.15)
		(size 0.45)
		(drill 0.1)
		(layers "F.Cu" "B.Cu")
		(remove_unused_layers yes)
		(keep_end_layers yes)
		(zone_layer_connections)
		(net 183)
	)
	(segment
		(start 245.35 150.05)
		(end 240.8 145.5)
		(width 0.15)
		(layer "B.Cu")
		(net 183)
	)
	(segment
		(start 237.954499 166.235)
		(end 237.954499 163.170501)
		(width 0.15)
		(layer "B.Cu")
		(net 183)
	)
	(segment
		(start 234.825 137.075)
		(end 217.85 120.1)
		(width 0.15)
		(layer "B.Cu")
		(net 183)
	)
	(segment
		(start 237.954499 163.170501)
		(end 242.525 158.6)
		(width 0.15)
		(layer "B.Cu")
		(net 183)
	)
	(segment
		(start 246.3 154.75)
		(end 245.35 153.8)
		(width 0.15)
		(layer "B.Cu")
		(net 183)
	)
	(segment
		(start 217.85 120.1)
		(end 152.01 120.1)
		(width 0.15)
		(layer "B.Cu")
		(net 183)
	)
	(segment
		(start 245.35 153.8)
		(end 245.35 150.05)
		(width 0.15)
		(layer "B.Cu")
		(net 183)
	)
	(segment
		(start 246.3 157.65)
		(end 246.3 154.75)
		(width 0.15)
		(layer "B.Cu")
		(net 183)
	)
	(segment
		(start 237.6 145.5)
		(end 234.825 142.725)
		(width 0.15)
		(layer "B.Cu")
		(net 183)
	)
	(segment
		(start 123.94 113.61)
		(end 120.4 117.15)
		(width 0.15)
		(layer "B.Cu")
		(net 183)
	)
	(segment
		(start 245.35 158.6)
		(end 246.3 157.65)
		(width 0.15)
		(layer "B.Cu")
		(net 183)
	)
	(segment
		(start 240.8 145.5)
		(end 237.6 145.5)
		(width 0.15)
		(layer "B.Cu")
		(net 183)
	)
	(segment
		(start 152.01 120.1)
		(end 145.52 113.61)
		(width 0.15)
		(layer "B.Cu")
		(net 183)
	)
	(segment
		(start 234.825 142.725)
		(end 234.825 137.075)
		(width 0.15)
		(layer "B.Cu")
		(net 183)
	)
	(segment
		(start 145.52 113.61)
		(end 123.94 113.61)
		(width 0.15)
		(layer "B.Cu")
		(net 183)
	)
	(segment
		(start 242.525 158.6)
		(end 245.35 158.6)
		(width 0.15)
		(layer "B.Cu")
		(net 183)
	)
	(segment
		(start 248.169499 134.709)
		(end 248.254499 134.624)
		(width 0.201)
		(layer "F.Cu")
		(net 184)
	)
	(segment
		(start 247.514499 134.709)
		(end 247.499499 134.724)
		(width 0.201)
		(layer "F.Cu")
		(net 184)
	)
	(segment
		(start 249.049499 134.624)
		(end 249.174499 134.499)
		(width 0.201)
		(layer "F.Cu")
		(net 184)
	)
	(segment
		(start 196.0005 150.9995)
		(end 196.5 150.5)
		(width 0.256)
		(layer "F.Cu")
		(net 184)
	)
	(segment
		(start 248.254499 134.624)
		(end 249.049499 134.624)
		(width 0.201)
		(layer "F.Cu")
		(net 184)
	)
	(segment
		(start 248.169499 134.709)
		(end 247.514499 134.709)
		(width 0.201)
		(layer "F.Cu")
		(net 184)
	)
	(via
		(at 196.5 150.5)
		(size 0.45)
		(drill 0.1)
		(layers "F.Cu" "B.Cu")
		(remove_unused_layers yes)
		(keep_end_layers yes)
		(zone_layer_connections)
		(net 184)
	)
	(via
		(at 247.499499 134.724)
		(size 0.45)
		(drill 0.1)
		(layers "F.Cu" "B.Cu")
		(remove_unused_layers yes)
		(keep_end_layers yes)
		(zone_layer_connections)
		(net 184)
	)
	(segment
		(start 201.935 148.975)
		(end 204.585 146.325)
		(width 0.1)
		(layer "In6.Cu")
		(net 184)
	)
	(segment
		(start 230.615 146.325)
		(end 236.37 140.57)
		(width 0.1)
		(layer "In6.Cu")
		(net 184)
	)
	(segment
		(start 196.2 148.975)
		(end 201.935 148.975)
		(width 0.1)
		(layer "In6.Cu")
		(net 184)
	)
	(segment
		(start 196 150.05)
		(end 196 149.175)
		(width 0.1)
		(layer "In6.Cu")
		(net 184)
	)
	(segment
		(start 196.5 150.5)
		(end 196.45 150.5)
		(width 0.1)
		(layer "In6.Cu")
		(net 184)
	)
	(segment
		(start 236.37 140.57)
		(end 236.37 139.19)
		(width 0.1)
		(layer "In6.Cu")
		(net 184)
	)
	(segment
		(start 204.585 146.325)
		(end 230.615 146.325)
		(width 0.1)
		(layer "In6.Cu")
		(net 184)
	)
	(segment
		(start 196 149.175)
		(end 196.2 148.975)
		(width 0.1)
		(layer "In6.Cu")
		(net 184)
	)
	(segment
		(start 236.37 139.19)
		(end 240.836 134.724)
		(width 0.1)
		(layer "In6.Cu")
		(net 184)
	)
	(segment
		(start 240.836 134.724)
		(end 247.499499 134.724)
		(width 0.1)
		(layer "In6.Cu")
		(net 184)
	)
	(segment
		(start 196.45 150.5)
		(end 196 150.05)
		(width 0.1)
		(layer "In6.Cu")
		(net 184)
	)
	(segment
		(start 195.0005 150.9995)
		(end 195.5 150.5)
		(width 0.256)
		(layer "F.Cu")
		(net 185)
	)
	(segment
		(start 249.218499 131.744)
		(end 248.289499 131.744)
		(width 0.256)
		(layer "F.Cu")
		(net 185)
	)
	(segment
		(start 247.409499 131.864)
		(end 247.399499 131.874)
		(width 0.256)
		(layer "F.Cu")
		(net 185)
	)
	(segment
		(start 248.289499 131.744)
		(end 248.169499 131.864)
		(width 0.256)
		(layer "F.Cu")
		(net 185)
	)
	(segment
		(start 248.169499 131.864)
		(end 247.409499 131.864)
		(width 0.256)
		(layer "F.Cu")
		(net 185)
	)
	(via
		(at 247.399499 131.874)
		(size 0.45)
		(drill 0.1)
		(layers "F.Cu" "B.Cu")
		(remove_unused_layers yes)
		(keep_end_layers yes)
		(zone_layer_connections)
		(net 185)
	)
	(via
		(at 195.5 150.5)
		(size 0.45)
		(drill 0.1)
		(layers "F.Cu" "B.Cu")
		(remove_unused_layers yes)
		(keep_end_layers yes)
		(zone_layer_connections)
		(net 185)
	)
	(segment
		(start 246.875499 131.35)
		(end 237.07 131.35)
		(width 0.1)
		(layer "In6.Cu")
		(net 185)
	)
	(segment
		(start 195.35 148.025)
		(end 195.05 148.325)
		(width 0.1)
		(layer "In6.Cu")
		(net 185)
	)
	(segment
		(start 195.05 149.69)
		(end 195.5 150.14)
		(width 0.1)
		(layer "In6.Cu")
		(net 185)
	)
	(segment
		(start 237.07 131.35)
		(end 233.3 135.12)
		(width 0.1)
		(layer "In6.Cu")
		(net 185)
	)
	(segment
		(start 227.45 145.525)
		(end 204.55 145.525)
		(width 0.1)
		(layer "In6.Cu")
		(net 185)
	)
	(segment
		(start 233.3 135.12)
		(end 233.3 139.675)
		(width 0.1)
		(layer "In6.Cu")
		(net 185)
	)
	(segment
		(start 204.55 145.525)
		(end 202.05 148.025)
		(width 0.1)
		(layer "In6.Cu")
		(net 185)
	)
	(segment
		(start 195.05 148.325)
		(end 195.05 149.69)
		(width 0.1)
		(layer "In6.Cu")
		(net 185)
	)
	(segment
		(start 233.3 139.675)
		(end 227.45 145.525)
		(width 0.1)
		(layer "In6.Cu")
		(net 185)
	)
	(segment
		(start 202.05 148.025)
		(end 195.35 148.025)
		(width 0.1)
		(layer "In6.Cu")
		(net 185)
	)
	(segment
		(start 195.5 150.14)
		(end 195.5 150.5)
		(width 0.1)
		(layer "In6.Cu")
		(net 185)
	)
	(segment
		(start 247.399499 131.874)
		(end 246.875499 131.35)
		(width 0.1)
		(layer "In6.Cu")
		(net 185)
	)
	(segment
		(start 191.0005 143.9995)
		(end 191.5 143.5)
		(width 0.256)
		(layer "F.Cu")
		(net 186)
	)
	(segment
		(start 202.35 110.598)
		(end 202.35 111.75)
		(width 0.38)
		(layer "F.Cu")
		(net 186)
	)
	(via
		(at 202.35 111.75)
		(size 0.45)
		(drill 0.1)
		(layers "F.Cu" "B.Cu")
		(remove_unused_layers yes)
		(keep_end_layers yes)
		(zone_layer_connections)
		(net 186)
	)
	(via
		(at 191.5 143.5)
		(size 0.45)
		(drill 0.1)
		(layers "F.Cu" "B.Cu")
		(remove_unused_layers yes)
		(keep_end_layers yes)
		(zone_layer_connections)
		(net 186)
	)
	(segment
		(start 202.89 113.71)
		(end 202.35 113.17)
		(width 0.15)
		(layer "In4.Cu")
		(net 186)
	)
	(segment
		(start 203.215441 117.314563)
		(end 203.21544 117.31456)
		(width 0.15)
		(layer "In4.Cu")
		(net 186)
	)
	(segment
		(start 201.37696 119.153042)
		(end 201.376961 119.153042)
		(width 0.15)
		(layer "In4.Cu")
		(net 186)
	)
	(segment
		(start 206 111)
		(end 206 113)
		(width 0.15)
		(layer "In4.Cu")
		(net 186)
	)
	(segment
		(start 198.619241 121.910762)
		(end 198.619242 121.910761)
		(width 0.15)
		(layer "In4.Cu")
		(net 186)
	)
	(segment
		(start 199.538481 120.991523)
		(end 199.53848 120.99152)
		(width 0.15)
		(layer "In4.Cu")
		(net 186)
	)
	(segment
		(start 201.37696 118.693422)
		(end 201.376961 118.69342)
		(width 0.15)
		(layer "In4.Cu")
		(net 186)
	)
	(segment
		(start 191 143)
		(end 190.4 143)
		(width 0.15)
		(layer "In4.Cu")
		(net 186)
	)
	(segment
		(start 201.376961 119.153042)
		(end 201.37696 119.15304)
		(width 0.15)
		(layer "In4.Cu")
		(net 186)
	)
	(segment
		(start 202.296201 118.233803)
		(end 202.2962 118.2338)
		(width 0.15)
		(layer "In4.Cu")
		(net 186)
	)
	(segment
		(start 207.38 115.86)
		(end 208.9 114.34)
		(width 0.15)
		(layer "In4.Cu")
		(net 186)
	)
	(segment
		(start 197.966282 121.717421)
		(end 198.159622 121.910761)
		(width 0.15)
		(layer "In4.Cu")
		(net 186)
	)
	(segment
		(start 198.61924 121.451142)
		(end 198.619241 121.45114)
		(width 0.15)
		(layer "In4.Cu")
		(net 186)
	)
	(segment
		(start 200.457721 119.61266)
		(end 200.264418 119.419357)
		(width 0.15)
		(layer "In4.Cu")
		(net 186)
	)
	(segment
		(start 202.2962 117.774182)
		(end 202.296201 117.77418)
		(width 0.15)
		(layer "In4.Cu")
		(net 186)
	)
	(segment
		(start 206.5 110.5)
		(end 206 111)
		(width 0.15)
		(layer "In4.Cu")
		(net 186)
	)
	(segment
		(start 206 113)
		(end 205.29 113.71)
		(width 0.15)
		(layer "In4.Cu")
		(net 186)
	)
	(segment
		(start 204.67 115.86)
		(end 207.38 115.86)
		(width 0.15)
		(layer "In4.Cu")
		(net 186)
	)
	(segment
		(start 208.9 114.34)
		(end 208.9 110.9)
		(width 0.15)
		(layer "In4.Cu")
		(net 186)
	)
	(segment
		(start 197.506661 121.717422)
		(end 197.506662 121.717421)
		(width 0.15)
		(layer "In4.Cu")
		(net 186)
	)
	(segment
		(start 202.35 113.17)
		(end 202.35 111.75)
		(width 0.15)
		(layer "In4.Cu")
		(net 186)
	)
	(segment
		(start 208.5 110.5)
		(end 206.5 110.5)
		(width 0.15)
		(layer "In4.Cu")
		(net 186)
	)
	(segment
		(start 203.481685 116.201944)
		(end 203.675062 116.395321)
		(width 0.15)
		(layer "In4.Cu")
		(net 186)
	)
	(segment
		(start 190 128.89)
		(end 195.65 123.24)
		(width 0.15)
		(layer "In4.Cu")
		(net 186)
	)
	(segment
		(start 203.022064 116.201945)
		(end 203.022065 116.201944)
		(width 0.15)
		(layer "In4.Cu")
		(net 186)
	)
	(segment
		(start 205.29 113.71)
		(end 202.89 113.71)
		(width 0.15)
		(layer "In4.Cu")
		(net 186)
	)
	(segment
		(start 200.45772 119.612662)
		(end 200.457721 119.61266)
		(width 0.15)
		(layer "In4.Cu")
		(net 186)
	)
	(segment
		(start 208.9 110.9)
		(end 208.5 110.5)
		(width 0.15)
		(layer "In4.Cu")
		(net 186)
	)
	(segment
		(start 198.425874 120.798153)
		(end 198.425873 120.798155)
		(width 0.15)
		(layer "In4.Cu")
		(net 186)
	)
	(segment
		(start 190.4 143)
		(end 190 142.6)
		(width 0.15)
		(layer "In4.Cu")
		(net 186)
	)
	(segment
		(start 204.134682 116.395321)
		(end 204.67 115.86)
		(width 0.15)
		(layer "In4.Cu")
		(net 186)
	)
	(segment
		(start 203.21544 116.854942)
		(end 203.215441 116.85494)
		(width 0.15)
		(layer "In4.Cu")
		(net 186)
	)
	(segment
		(start 200.264419 118.959738)
		(end 200.264417 118.959739)
		(width 0.15)
		(layer "In4.Cu")
		(net 186)
	)
	(segment
		(start 200.45772 120.072281)
		(end 200.45772 120.07228)
		(width 0.15)
		(layer "In4.Cu")
		(net 186)
	)
	(segment
		(start 199.804761 119.87894)
		(end 199.998102 120.072281)
		(width 0.15)
		(layer "In4.Cu")
		(net 186)
	)
	(segment
		(start 198.619241 121.45114)
		(end 198.425874 121.257773)
		(width 0.15)
		(layer "In4.Cu")
		(net 186)
	)
	(segment
		(start 195.65 123.24)
		(end 197.29 123.24)
		(width 0.15)
		(layer "In4.Cu")
		(net 186)
	)
	(segment
		(start 200.724037 118.959739)
		(end 200.917341 119.153043)
		(width 0.15)
		(layer "In4.Cu")
		(net 186)
	)
	(segment
		(start 198.885493 120.798155)
		(end 199.078861 120.991523)
		(width 0.15)
		(layer "In4.Cu")
		(net 186)
	)
	(segment
		(start 197.7 122.370382)
		(end 197.700001 122.37038)
		(width 0.15)
		(layer "In4.Cu")
		(net 186)
	)
	(segment
		(start 199.53848 120.531902)
		(end 199.538481 120.5319)
		(width 0.15)
		(layer "In4.Cu")
		(net 186)
	)
	(segment
		(start 200.457722 120.072281)
		(end 200.45772 120.072281)
		(width 0.15)
		(layer "In4.Cu")
		(net 186)
	)
	(segment
		(start 202.102843 117.121202)
		(end 202.102842 117.121204)
		(width 0.15)
		(layer "In4.Cu")
		(net 186)
	)
	(segment
		(start 204.134681 116.395322)
		(end 204.134682 116.395321)
		(width 0.15)
		(layer "In4.Cu")
		(net 186)
	)
	(segment
		(start 199.538481 120.5319)
		(end 199.345141 120.33856)
		(width 0.15)
		(layer "In4.Cu")
		(net 186)
	)
	(segment
		(start 202.296201 117.77418)
		(end 202.102843 117.580822)
		(width 0.15)
		(layer "In4.Cu")
		(net 186)
	)
	(segment
		(start 198.619242 121.910761)
		(end 198.61924 121.91076)
		(width 0.15)
		(layer "In4.Cu")
		(net 186)
	)
	(segment
		(start 191.5 143.5)
		(end 191 143)
		(width 0.15)
		(layer "In4.Cu")
		(net 186)
	)
	(segment
		(start 197.700001 122.37038)
		(end 197.506662 122.177041)
		(width 0.15)
		(layer "In4.Cu")
		(net 186)
	)
	(segment
		(start 201.183601 118.04044)
		(end 201.1836 118.040442)
		(width 0.15)
		(layer "In4.Cu")
		(net 186)
	)
	(segment
		(start 190 142.6)
		(end 190 128.89)
		(width 0.15)
		(layer "In4.Cu")
		(net 186)
	)
	(segment
		(start 203.215441 116.85494)
		(end 203.022065 116.661564)
		(width 0.15)
		(layer "In4.Cu")
		(net 186)
	)
	(segment
		(start 197.29 123.24)
		(end 197.7 122.83)
		(width 0.15)
		(layer "In4.Cu")
		(net 186)
	)
	(segment
		(start 201.376961 118.69342)
		(end 201.183601 118.50006)
		(width 0.15)
		(layer "In4.Cu")
		(net 186)
	)
	(segment
		(start 201.64322 118.040442)
		(end 201.836581 118.233803)
		(width 0.15)
		(layer "In4.Cu")
		(net 186)
	)
	(segment
		(start 202.562462 117.121204)
		(end 202.755821 117.314563)
		(width 0.15)
		(layer "In4.Cu")
		(net 186)
	)
	(arc
		(start 198.159622 121.910761)
		(mid 198.389431 122.005952)
		(end 198.619241 121.910762)
		(width 0.15)
		(layer "In4.Cu")
		(net 186)
	)
	(arc
		(start 199.345141 119.87894)
		(mid 199.574951 119.78375)
		(end 199.804761 119.87894)
		(width 0.15)
		(layer "In4.Cu")
		(net 186)
	)
	(arc
		(start 203.022065 116.201944)
		(mid 203.251875 116.106754)
		(end 203.481685 116.201944)
		(width 0.15)
		(layer "In4.Cu")
		(net 186)
	)
	(arc
		(start 202.102842 117.121204)
		(mid 202.332652 117.026014)
		(end 202.562462 117.121204)
		(width 0.15)
		(layer "In4.Cu")
		(net 186)
	)
	(arc
		(start 201.1836 118.040442)
		(mid 201.41341 117.945252)
		(end 201.64322 118.040442)
		(width 0.15)
		(layer "In4.Cu")
		(net 186)
	)
	(arc
		(start 200.917341 119.153043)
		(mid 201.147151 119.248233)
		(end 201.37696 119.153042)
		(width 0.15)
		(layer "In4.Cu")
		(net 186)
	)
	(arc
		(start 198.61924 121.91076)
		(mid 198.714431 121.68095)
		(end 198.61924 121.451142)
		(width 0.15)
		(layer "In4.Cu")
		(net 186)
	)
	(arc
		(start 197.506662 121.717421)
		(mid 197.736472 121.622231)
		(end 197.966282 121.717421)
		(width 0.15)
		(layer "In4.Cu")
		(net 186)
	)
	(arc
		(start 200.264418 119.419357)
		(mid 200.169228 119.189547)
		(end 200.264419 118.959738)
		(width 0.15)
		(layer "In4.Cu")
		(net 186)
	)
	(arc
		(start 199.998102 120.072281)
		(mid 200.227912 120.167471)
		(end 200.457722 120.072281)
		(width 0.15)
		(layer "In4.Cu")
		(net 186)
	)
	(arc
		(start 199.53848 120.99152)
		(mid 199.633671 120.76171)
		(end 199.53848 120.531902)
		(width 0.15)
		(layer "In4.Cu")
		(net 186)
	)
	(arc
		(start 202.102843 117.580822)
		(mid 202.007653 117.351012)
		(end 202.102843 117.121202)
		(width 0.15)
		(layer "In4.Cu")
		(net 186)
	)
	(arc
		(start 202.755821 117.314563)
		(mid 202.985631 117.409753)
		(end 203.215441 117.314563)
		(width 0.15)
		(layer "In4.Cu")
		(net 186)
	)
	(arc
		(start 203.022065 116.661564)
		(mid 202.926874 116.431755)
		(end 203.022064 116.201945)
		(width 0.15)
		(layer "In4.Cu")
		(net 186)
	)
	(arc
		(start 203.675062 116.395321)
		(mid 203.904871 116.490512)
		(end 204.134681 116.395322)
		(width 0.15)
		(layer "In4.Cu")
		(net 186)
	)
	(arc
		(start 199.345141 120.33856)
		(mid 199.249951 120.10875)
		(end 199.345141 119.87894)
		(width 0.15)
		(layer "In4.Cu")
		(net 186)
	)
	(arc
		(start 197.506662 122.177041)
		(mid 197.411471 121.947232)
		(end 197.506661 121.717422)
		(width 0.15)
		(layer "In4.Cu")
		(net 186)
	)
	(arc
		(start 197.7 122.83)
		(mid 197.795191 122.60019)
		(end 197.7 122.370382)
		(width 0.15)
		(layer "In4.Cu")
		(net 186)
	)
	(arc
		(start 201.37696 119.15304)
		(mid 201.472151 118.92323)
		(end 201.37696 118.693422)
		(width 0.15)
		(layer "In4.Cu")
		(net 186)
	)
	(arc
		(start 203.21544 117.31456)
		(mid 203.310631 117.08475)
		(end 203.21544 116.854942)
		(width 0.15)
		(layer "In4.Cu")
		(net 186)
	)
	(arc
		(start 200.45772 120.07228)
		(mid 200.552911 119.84247)
		(end 200.45772 119.612662)
		(width 0.15)
		(layer "In4.Cu")
		(net 186)
	)
	(arc
		(start 198.425873 120.798155)
		(mid 198.655683 120.702965)
		(end 198.885493 120.798155)
		(width 0.15)
		(layer "In4.Cu")
		(net 186)
	)
	(arc
		(start 202.2962 118.2338)
		(mid 202.391391 118.00399)
		(end 202.2962 117.774182)
		(width 0.15)
		(layer "In4.Cu")
		(net 186)
	)
	(arc
		(start 200.264417 118.959739)
		(mid 200.494227 118.864549)
		(end 200.724037 118.959739)
		(width 0.15)
		(layer "In4.Cu")
		(net 186)
	)
	(arc
		(start 198.425874 121.257773)
		(mid 198.330684 121.027963)
		(end 198.425874 120.798153)
		(width 0.15)
		(layer "In4.Cu")
		(net 186)
	)
	(arc
		(start 201.183601 118.50006)
		(mid 201.088411 118.27025)
		(end 201.183601 118.04044)
		(width 0.15)
		(layer "In4.Cu")
		(net 186)
	)
	(arc
		(start 199.078861 120.991523)
		(mid 199.308671 121.086713)
		(end 199.538481 120.991523)
		(width 0.15)
		(layer "In4.Cu")
		(net 186)
	)
	(arc
		(start 201.836581 118.233803)
		(mid 202.066391 118.328993)
		(end 202.296201 118.233803)
		(width 0.15)
		(layer "In4.Cu")
		(net 186)
	)
	(segment
		(start 200.65 110.598)
		(end 200.65 111.75)
		(width 0.38)
		(layer "F.Cu")
		(net 187)
	)
	(segment
		(start 194.000501 146.9995)
		(end 194.5 146.5)
		(width 0.256)
		(layer "F.Cu")
		(net 187)
	)
	(via
		(at 194.5 146.5)
		(size 0.45)
		(drill 0.1)
		(layers "F.Cu" "B.Cu")
		(remove_unused_layers yes)
		(keep_end_layers yes)
		(zone_layer_connections)
		(net 187)
	)
	(via
		(at 200.65 111.75)
		(size 0.45)
		(drill 0.1)
		(layers "F.Cu" "B.Cu")
		(remove_unused_layers yes)
		(keep_end_layers yes)
		(zone_layer_connections)
		(net 187)
	)
	(segment
		(start 200.65 111.75)
		(end 200.65 112.53)
		(width 0.148)
		(layer "In4.Cu")
		(net 187)
	)
	(segment
		(start 188.773007 118.000196)
		(end 188.203349 117.430538)
		(width 0.148)
		(layer "In4.Cu")
		(net 187)
	)
	(segment
		(start 188.9 146.7)
		(end 189.25 147.05)
		(width 0.148)
		(layer "In4.Cu")
		(net 187)
	)
	(segment
		(start 200.65 112.53)
		(end 200.1 113.08)
		(width 0.148)
		(layer "In4.Cu")
		(net 187)
	)
	(segment
		(start 187 143.564272)
		(end 187.334728 143.899)
		(width 0.148)
		(layer "In4.Cu")
		(net 187)
	)
	(segment
		(start 194 147)
		(end 194.5 146.5)
		(width 0.15)
		(layer "In4.Cu")
		(net 187)
	)
	(segment
		(start 190.855 114.778884)
		(end 191.424702 115.348586)
		(width 0.148)
		(layer "In4.Cu")
		(net 187)
	)
	(segment
		(start 187 117.75)
		(end 187 143.564272)
		(width 0.148)
		(layer "In4.Cu")
		(net 187)
	)
	(segment
		(start 187.319465 117.430538)
		(end 187.319465 117.430536)
		(width 0.148)
		(layer "In4.Cu")
		(net 187)
	)
	(segment
		(start 191.424701 116.232469)
		(end 191.424701 116.23247)
		(width 0.148)
		(layer "In4.Cu")
		(net 187)
	)
	(segment
		(start 192.025 147.3)
		(end 192.325 147)
		(width 0.148)
		(layer "In4.Cu")
		(net 187)
	)
	(segment
		(start 188 144.25)
		(end 188 144.75)
		(width 0.148)
		(layer "In4.Cu")
		(net 187)
	)
	(segment
		(start 188 144.75)
		(end 188.9 145.65)
		(width 0.148)
		(layer "In4.Cu")
		(net 187)
	)
	(segment
		(start 189.25 147.05)
		(end 190.614272 147.05)
		(width 0.148)
		(layer "In4.Cu")
		(net 187)
	)
	(segment
		(start 187.649 143.899)
		(end 188 144.25)
		(width 0.148)
		(layer "In4.Cu")
		(net 187)
	)
	(segment
		(start 191.67 113.08)
		(end 190.855 113.895)
		(width 0.148)
		(layer "In4.Cu")
		(net 187)
	)
	(segment
		(start 190.95 147.716272)
		(end 191.233728 148)
		(width 0.148)
		(layer "In4.Cu")
		(net 187)
	)
	(segment
		(start 192.025 147.725)
		(end 192.025 147.3)
		(width 0.148)
		(layer "In4.Cu")
		(net 187)
	)
	(segment
		(start 190.95 147.385728)
		(end 190.95 147.716272)
		(width 0.148)
		(layer "In4.Cu")
		(net 187)
	)
	(segment
		(start 200.1 113.08)
		(end 191.67 113.08)
		(width 0.148)
		(layer "In4.Cu")
		(net 187)
	)
	(segment
		(start 190.614272 147.05)
		(end 190.95 147.385728)
		(width 0.148)
		(layer "In4.Cu")
		(net 187)
	)
	(segment
		(start 189.087235 115.662769)
		(end 189.087232 115.662768)
		(width 0.148)
		(layer "In4.Cu")
		(net 187)
	)
	(segment
		(start 191.75 148)
		(end 192.025 147.725)
		(width 0.148)
		(layer "In4.Cu")
		(net 187)
	)
	(segment
		(start 191.233728 148)
		(end 191.75 148)
		(width 0.148)
		(layer "In4.Cu")
		(net 187)
	)
	(segment
		(start 190.540819 116.232469)
		(end 189.971118 115.662768)
		(width 0.148)
		(layer "In4.Cu")
		(net 187)
	)
	(segment
		(start 187.334728 143.899)
		(end 187.649 143.899)
		(width 0.148)
		(layer "In4.Cu")
		(net 187)
	)
	(segment
		(start 190.540819 116.23247)
		(end 190.540819 116.232469)
		(width 0.148)
		(layer "In4.Cu")
		(net 187)
	)
	(segment
		(start 189.087232 116.546652)
		(end 189.656891 117.116311)
		(width 0.148)
		(layer "In4.Cu")
		(net 187)
	)
	(segment
		(start 188.9 145.65)
		(end 188.9 146.7)
		(width 0.148)
		(layer "In4.Cu")
		(net 187)
	)
	(segment
		(start 192.325 147)
		(end 194 147)
		(width 0.148)
		(layer "In4.Cu")
		(net 187)
	)
	(segment
		(start 187.319465 117.430536)
		(end 187 117.75)
		(width 0.148)
		(layer "In4.Cu")
		(net 187)
	)
	(segment
		(start 188.773009 118.000195)
		(end 188.773007 118.000196)
		(width 0.148)
		(layer "In4.Cu")
		(net 187)
	)
	(arc
		(start 189.971118 115.662768)
		(mid 189.529176 115.47971)
		(end 189.087235 115.662769)
		(width 0.148)
		(layer "In4.Cu")
		(net 187)
	)
	(arc
		(start 189.656891 117.116311)
		(mid 189.839949 117.558253)
		(end 189.656891 118.000195)
		(width 0.148)
		(layer "In4.Cu")
		(net 187)
	)
	(arc
		(start 188.203349 117.430538)
		(mid 187.761407 117.24748)
		(end 187.319465 117.430538)
		(width 0.148)
		(layer "In4.Cu")
		(net 187)
	)
	(arc
		(start 190.855 113.895)
		(mid 190.671942 114.336942)
		(end 190.855 114.778884)
		(width 0.148)
		(layer "In4.Cu")
		(net 187)
	)
	(arc
		(start 191.424701 116.23247)
		(mid 190.982761 116.415527)
		(end 190.540819 116.23247)
		(width 0.148)
		(layer "In4.Cu")
		(net 187)
	)
	(arc
		(start 191.424702 115.348586)
		(mid 191.60776 115.790528)
		(end 191.424701 116.232469)
		(width 0.148)
		(layer "In4.Cu")
		(net 187)
	)
	(arc
		(start 189.087232 115.662768)
		(mid 188.904174 116.10471)
		(end 189.087232 116.546652)
		(width 0.148)
		(layer "In4.Cu")
		(net 187)
	)
	(arc
		(start 189.656891 118.000195)
		(mid 189.214949 118.183254)
		(end 188.773009 118.000195)
		(width 0.148)
		(layer "In4.Cu")
		(net 187)
	)
	(segment
		(start 102.575 172.0185)
		(end 108.575 172.0185)
		(width 0.4)
		(layer "F.Cu")
		(net 188)
	)
	(segment
		(start 108.575 172.0185)
		(end 113.026 172.0185)
		(width 0.4)
		(layer "F.Cu")
		(net 188)
	)
	(segment
		(start 102.575 186.5185)
		(end 102.575 172.0185)
		(width 0.4)
		(layer "F.Cu")
		(net 188)
	)
	(segment
		(start 102.575 186.5185)
		(end 108.575 186.5185)
		(width 0.4)
		(layer "F.Cu")
		(net 188)
	)
	(segment
		(start 259.771 132.601499)
		(end 258.523 132.601499)
		(width 0.256)
		(layer "F.Cu")
		(net 189)
	)
	(segment
		(start 258.871 128.503499)
		(end 259.771 128.503499)
		(width 0.256)
		(layer "F.Cu")
		(net 189)
	)
	(segment
		(start 258.523 132.601499)
		(end 257.456499 133.668)
		(width 0.256)
		(layer "F.Cu")
		(net 189)
	)
	(segment
		(start 257.456499 133.668)
		(end 255.324499 133.668)
		(width 0.256)
		(layer "F.Cu")
		(net 189)
	)
	(segment
		(start 258.523 132.601499)
		(end 258.523 128.851499)
		(width 0.256)
		(layer "F.Cu")
		(net 189)
	)
	(segment
		(start 258.523 128.851499)
		(end 258.871 128.503499)
		(width 0.256)
		(layer "F.Cu")
		(net 189)
	)
	(segment
		(start 198.95 110.598)
		(end 198.95 111.75)
		(width 0.38)
		(layer "F.Cu")
		(net 190)
	)
	(segment
		(start 191.0005 146.9995)
		(end 191.5 146.5)
		(width 0.256)
		(layer "F.Cu")
		(net 190)
	)
	(via
		(at 198.95 111.75)
		(size 0.45)
		(drill 0.1)
		(layers "F.Cu" "B.Cu")
		(remove_unused_layers yes)
		(keep_end_layers yes)
		(zone_layer_connections)
		(net 190)
	)
	(via
		(at 191.5 146.5)
		(size 0.45)
		(drill 0.1)
		(layers "F.Cu" "B.Cu")
		(remove_unused_layers yes)
		(keep_end_layers yes)
		(zone_layer_connections)
		(net 190)
	)
	(segment
		(start 201.922793 113.498527)
		(end 201.922792 113.498528)
		(width 0.1)
		(layer "In9.Cu")
		(net 190)
	)
	(segment
		(start 191.975 146.975)
		(end 191.5 146.5)
		(width 0.1)
		(layer "In9.Cu")
		(net 190)
	)
	(segment
		(start 203.195583 115.195583)
		(end 203.195584 115.195584)
		(width 0.1)
		(layer "In9.Cu")
		(net 190)
	)
	(segment
		(start 206 118)
		(end 206 138.23)
		(width 0.1)
		(layer "In9.Cu")
		(net 190)
	)
	(segment
		(start 199.32 144.99)
		(end 199 145.31)
		(width 0.1)
		(layer "In9.Cu")
		(net 190)
	)
	(segment
		(start 206 138.23)
		(end 203.760165 140.469835)
		(width 0.1)
		(layer "In9.Cu")
		(net 190)
	)
	(segment
		(start 203.760165 140.469835)
		(end 203.760165 141.259835)
		(width 0.1)
		(layer "In9.Cu")
		(net 190)
	)
	(segment
		(start 199 145.31)
		(end 199 145.75)
		(width 0.1)
		(layer "In9.Cu")
		(net 190)
	)
	(segment
		(start 198 146.25)
		(end 198 146.685)
		(width 0.1)
		(layer "In9.Cu")
		(net 190)
	)
	(segment
		(start 205.192202 116.168815)
		(end 204.892639 116.468375)
		(width 0.1)
		(layer "In9.Cu")
		(net 190)
	)
	(segment
		(start 198.95 111.75)
		(end 199.75 111.75)
		(width 0.1)
		(layer "In9.Cu")
		(net 190)
	)
	(segment
		(start 205.192201 116.168816)
		(end 205.192202 116.168815)
		(width 0.1)
		(layer "In9.Cu")
		(net 190)
	)
	(segment
		(start 199 145.75)
		(end 198.78 145.97)
		(width 0.1)
		(layer "In9.Cu")
		(net 190)
	)
	(segment
		(start 203.760165 141.259835)
		(end 202.01 143.01)
		(width 0.1)
		(layer "In9.Cu")
		(net 190)
	)
	(segment
		(start 201.03 143.28)
		(end 201.03 143.63)
		(width 0.1)
		(layer "In9.Cu")
		(net 190)
	)
	(segment
		(start 202.646618 113.623231)
		(end 202.347055 113.922791)
		(width 0.1)
		(layer "In9.Cu")
		(net 190)
	)
	(segment
		(start 201.498527 113.498527)
		(end 201.498528 113.498528)
		(width 0.1)
		(layer "In9.Cu")
		(net 190)
	)
	(segment
		(start 203.495146 114.471759)
		(end 203.195583 114.771319)
		(width 0.1)
		(layer "In9.Cu")
		(net 190)
	)
	(segment
		(start 200.189669 144.03)
		(end 200.01 144.209669)
		(width 0.1)
		(layer "In9.Cu")
		(net 190)
	)
	(segment
		(start 199.74 144.99)
		(end 199.32 144.99)
		(width 0.1)
		(layer "In9.Cu")
		(net 190)
	)
	(segment
		(start 203.619848 115.195584)
		(end 203.919399 114.896034)
		(width 0.1)
		(layer "In9.Cu")
		(net 190)
	)
	(segment
		(start 199.75 111.75)
		(end 200.65 112.65)
		(width 0.1)
		(layer "In9.Cu")
		(net 190)
	)
	(segment
		(start 204.343663 115.320298)
		(end 204.044111 115.619847)
		(width 0.1)
		(layer "In9.Cu")
		(net 190)
	)
	(segment
		(start 203.495145 114.47176)
		(end 203.495146 114.471759)
		(width 0.1)
		(layer "In9.Cu")
		(net 190)
	)
	(segment
		(start 204.892639 116.892639)
		(end 204.89264 116.89264)
		(width 0.1)
		(layer "In9.Cu")
		(net 190)
	)
	(segment
		(start 198.28 145.97)
		(end 198 146.25)
		(width 0.1)
		(layer "In9.Cu")
		(net 190)
	)
	(segment
		(start 204.468377 116.044111)
		(end 204.468376 116.044112)
		(width 0.1)
		(layer "In9.Cu")
		(net 190)
	)
	(segment
		(start 206.040718 117.017355)
		(end 206.040719 117.017354)
		(width 0.1)
		(layer "In9.Cu")
		(net 190)
	)
	(segment
		(start 200.63 144.03)
		(end 200.189669 144.03)
		(width 0.1)
		(layer "In9.Cu")
		(net 190)
	)
	(segment
		(start 202.771321 114.347055)
		(end 202.77132 114.347056)
		(width 0.1)
		(layer "In9.Cu")
		(net 190)
	)
	(segment
		(start 202.646617 113.623232)
		(end 202.646618 113.623231)
		(width 0.1)
		(layer "In9.Cu")
		(net 190)
	)
	(segment
		(start 202.77132 114.347056)
		(end 203.070882 114.047495)
		(width 0.1)
		(layer "In9.Cu")
		(net 190)
	)
	(segment
		(start 206.040719 117.017354)
		(end 205.741167 117.316903)
		(width 0.1)
		(layer "In9.Cu")
		(net 190)
	)
	(segment
		(start 205.741167 117.741167)
		(end 205.741168 117.741168)
		(width 0.1)
		(layer "In9.Cu")
		(net 190)
	)
	(segment
		(start 201.922792 113.498528)
		(end 202.222354 113.198967)
		(width 0.1)
		(layer "In9.Cu")
		(net 190)
	)
	(segment
		(start 204.343662 115.320299)
		(end 204.343663 115.320298)
		(width 0.1)
		(layer "In9.Cu")
		(net 190)
	)
	(segment
		(start 202.347055 114.347055)
		(end 202.347056 114.347056)
		(width 0.1)
		(layer "In9.Cu")
		(net 190)
	)
	(segment
		(start 205.316905 116.892639)
		(end 205.316904 116.89264)
		(width 0.1)
		(layer "In9.Cu")
		(net 190)
	)
	(segment
		(start 201.074264 112.65)
		(end 201.37382 112.350445)
		(width 0.1)
		(layer "In9.Cu")
		(net 190)
	)
	(segment
		(start 201.798084 112.774709)
		(end 201.498527 113.074263)
		(width 0.1)
		(layer "In9.Cu")
		(net 190)
	)
	(segment
		(start 205.741168 117.741168)
		(end 206 118)
		(width 0.1)
		(layer "In9.Cu")
		(net 190)
	)
	(segment
		(start 202.01 143.01)
		(end 201.3 143.01)
		(width 0.1)
		(layer "In9.Cu")
		(net 190)
	)
	(segment
		(start 204.044111 116.044111)
		(end 204.044112 116.044112)
		(width 0.1)
		(layer "In9.Cu")
		(net 190)
	)
	(segment
		(start 200.01 144.72)
		(end 199.74 144.99)
		(width 0.1)
		(layer "In9.Cu")
		(net 190)
	)
	(segment
		(start 198 146.685)
		(end 197.71 146.975)
		(width 0.1)
		(layer "In9.Cu")
		(net 190)
	)
	(segment
		(start 205.316904 116.89264)
		(end 205.616455 116.59309)
		(width 0.1)
		(layer "In9.Cu")
		(net 190)
	)
	(segment
		(start 201.798083 112.77471)
		(end 201.798084 112.774709)
		(width 0.1)
		(layer "In9.Cu")
		(net 190)
	)
	(segment
		(start 197.71 146.975)
		(end 191.975 146.975)
		(width 0.1)
		(layer "In9.Cu")
		(net 190)
	)
	(segment
		(start 201.074265 112.649999)
		(end 201.074264 112.65)
		(width 0.1)
		(layer "In9.Cu")
		(net 190)
	)
	(segment
		(start 198.78 145.97)
		(end 198.28 145.97)
		(width 0.1)
		(layer "In9.Cu")
		(net 190)
	)
	(segment
		(start 201.3 143.01)
		(end 201.03 143.28)
		(width 0.1)
		(layer "In9.Cu")
		(net 190)
	)
	(segment
		(start 201.03 143.63)
		(end 200.63 144.03)
		(width 0.1)
		(layer "In9.Cu")
		(net 190)
	)
	(segment
		(start 203.619849 115.195583)
		(end 203.619848 115.195584)
		(width 0.1)
		(layer "In9.Cu")
		(net 190)
	)
	(segment
		(start 200.01 144.209669)
		(end 200.01 144.72)
		(width 0.1)
		(layer "In9.Cu")
		(net 190)
	)
	(segment
		(start 204.468376 116.044112)
		(end 204.767938 115.744551)
		(width 0.1)
		(layer "In9.Cu")
		(net 190)
	)
	(arc
		(start 205.616455 116.59309)
		(mid 205.828587 116.505222)
		(end 206.040719 116.59309)
		(width 0.1)
		(layer "In9.Cu")
		(net 190)
	)
	(arc
		(start 200.65 112.65)
		(mid 200.862134 112.737869)
		(end 201.074265 112.649999)
		(width 0.1)
		(layer "In9.Cu")
		(net 190)
	)
	(arc
		(start 205.192202 115.744551)
		(mid 205.280069 115.956683)
		(end 205.192201 116.168816)
		(width 0.1)
		(layer "In9.Cu")
		(net 190)
	)
	(arc
		(start 204.343663 114.896034)
		(mid 204.43153 115.108166)
		(end 204.343662 115.320299)
		(width 0.1)
		(layer "In9.Cu")
		(net 190)
	)
	(arc
		(start 203.195584 115.195584)
		(mid 203.407718 115.283453)
		(end 203.619849 115.195583)
		(width 0.1)
		(layer "In9.Cu")
		(net 190)
	)
	(arc
		(start 204.044112 116.044112)
		(mid 204.256246 116.131981)
		(end 204.468377 116.044111)
		(width 0.1)
		(layer "In9.Cu")
		(net 190)
	)
	(arc
		(start 203.495146 114.047495)
		(mid 203.583013 114.259627)
		(end 203.495145 114.47176)
		(width 0.1)
		(layer "In9.Cu")
		(net 190)
	)
	(arc
		(start 201.498527 113.074263)
		(mid 201.410659 113.286395)
		(end 201.498527 113.498527)
		(width 0.1)
		(layer "In9.Cu")
		(net 190)
	)
	(arc
		(start 201.498528 113.498528)
		(mid 201.710662 113.586397)
		(end 201.922793 113.498527)
		(width 0.1)
		(layer "In9.Cu")
		(net 190)
	)
	(arc
		(start 203.919399 114.896034)
		(mid 204.131531 114.808166)
		(end 204.343663 114.896034)
		(width 0.1)
		(layer "In9.Cu")
		(net 190)
	)
	(arc
		(start 202.646618 113.198967)
		(mid 202.734485 113.411099)
		(end 202.646617 113.623232)
		(width 0.1)
		(layer "In9.Cu")
		(net 190)
	)
	(arc
		(start 202.347055 113.922791)
		(mid 202.259187 114.134923)
		(end 202.347055 114.347055)
		(width 0.1)
		(layer "In9.Cu")
		(net 190)
	)
	(arc
		(start 202.347056 114.347056)
		(mid 202.55919 114.434925)
		(end 202.771321 114.347055)
		(width 0.1)
		(layer "In9.Cu")
		(net 190)
	)
	(arc
		(start 201.37382 112.350445)
		(mid 201.585952 112.262577)
		(end 201.798084 112.350445)
		(width 0.1)
		(layer "In9.Cu")
		(net 190)
	)
	(arc
		(start 201.798084 112.350445)
		(mid 201.885951 112.562577)
		(end 201.798083 112.77471)
		(width 0.1)
		(layer "In9.Cu")
		(net 190)
	)
	(arc
		(start 203.070882 114.047495)
		(mid 203.283014 113.959627)
		(end 203.495146 114.047495)
		(width 0.1)
		(layer "In9.Cu")
		(net 190)
	)
	(arc
		(start 202.222354 113.198967)
		(mid 202.434486 113.111099)
		(end 202.646618 113.198967)
		(width 0.1)
		(layer "In9.Cu")
		(net 190)
	)
	(arc
		(start 206.040719 116.59309)
		(mid 206.128586 116.805222)
		(end 206.040718 117.017355)
		(width 0.1)
		(layer "In9.Cu")
		(net 190)
	)
	(arc
		(start 204.892639 116.468375)
		(mid 204.804771 116.680507)
		(end 204.892639 116.892639)
		(width 0.1)
		(layer "In9.Cu")
		(net 190)
	)
	(arc
		(start 204.044111 115.619847)
		(mid 203.956243 115.831979)
		(end 204.044111 116.044111)
		(width 0.1)
		(layer "In9.Cu")
		(net 190)
	)
	(arc
		(start 205.741167 117.316903)
		(mid 205.653299 117.529035)
		(end 205.741167 117.741167)
		(width 0.1)
		(layer "In9.Cu")
		(net 190)
	)
	(arc
		(start 203.195583 114.771319)
		(mid 203.107715 114.983451)
		(end 203.195583 115.195583)
		(width 0.1)
		(layer "In9.Cu")
		(net 190)
	)
	(arc
		(start 204.89264 116.89264)
		(mid 205.104774 116.980509)
		(end 205.316905 116.892639)
		(width 0.1)
		(layer "In9.Cu")
		(net 190)
	)
	(arc
		(start 204.767938 115.744551)
		(mid 204.98007 115.656683)
		(end 205.192202 115.744551)
		(width 0.1)
		(layer "In9.Cu")
		(net 190)
	)
	(segment
		(start 195.0005 142.9995)
		(end 195.5 142.5)
		(width 0.256)
		(layer "F.Cu")
		(net 191)
	)
	(segment
		(start 197.25 110.598)
		(end 197.25 111.75)
		(width 0.38)
		(layer "F.Cu")
		(net 191)
	)
	(via
		(at 197.25 111.75)
		(size 0.45)
		(drill 0.1)
		(layers "F.Cu" "B.Cu")
		(remove_unused_layers yes)
		(keep_end_layers yes)
		(zone_layer_connections)
		(net 191)
	)
	(via
		(at 195.5 142.5)
		(size 0.45)
		(drill 0.1)
		(layers "F.Cu" "B.Cu")
		(remove_unused_layers yes)
		(keep_end_layers yes)
		(zone_layer_connections)
		(net 191)
	)
	(segment
		(start 200.06 141.73)
		(end 199.79 142)
		(width 0.1)
		(layer "In9.Cu")
		(net 191)
	)
	(segment
		(start 199.8 119.35)
		(end 197.75 119.35)
		(width 0.1)
		(layer "In9.Cu")
		(net 191)
	)
	(segment
		(start 198.01 143.74)
		(end 197.74 144.01)
		(width 0.1)
		(layer "In9.Cu")
		(net 191)
	)
	(segment
		(start 196 143.76)
		(end 196 143.275)
		(width 0.1)
		(layer "In9.Cu")
		(net 191)
	)
	(segment
		(start 198.875 115.175)
		(end 198.997056 115.297056)
		(width 0.1)
		(layer "In9.Cu")
		(net 191)
	)
	(segment
		(start 197.25 111.75)
		(end 197.25 113.55)
		(width 0.1)
		(layer "In9.Cu")
		(net 191)
	)
	(segment
		(start 199 142.33)
		(end 199 142.81)
		(width 0.1)
		(layer "In9.Cu")
		(net 191)
	)
	(segment
		(start 200.2 116.5)
		(end 200.2 117.35)
		(width 0.1)
		(layer "In9.Cu")
		(net 191)
	)
	(segment
		(start 196 143.275)
		(end 195.5 142.775)
		(width 0.1)
		(layer "In9.Cu")
		(net 191)
	)
	(segment
		(start 200.2 120.55)
		(end 200.2 120.7)
		(width 0.1)
		(layer "In9.Cu")
		(net 191)
	)
	(segment
		(start 197.400017 114.422591)
		(end 197.400015 114.42259)
		(width 0.1)
		(layer "In9.Cu")
		(net 191)
	)
	(segment
		(start 198.29 143.02)
		(end 198.01 143.3)
		(width 0.1)
		(layer "In9.Cu")
		(net 191)
	)
	(segment
		(start 201.09712 122.837501)
		(end 201.211142 122.723476)
		(width 0.1)
		(layer "In9.Cu")
		(net 191)
	)
	(segment
		(start 196.25 144.01)
		(end 196 143.76)
		(width 0.1)
		(layer "In9.Cu")
		(net 191)
	)
	(segment
		(start 200.06 141.28)
		(end 200.06 141.73)
		(width 0.1)
		(layer "In9.Cu")
		(net 191)
	)
	(segment
		(start 201.556739 123.756738)
		(end 201.556737 123.756737)
		(width 0.1)
		(layer "In9.Cu")
		(net 191)
	)
	(segment
		(start 199 142.81)
		(end 198.79 143.02)
		(width 0.1)
		(layer "In9.Cu")
		(net 191)
	)
	(segment
		(start 197.400016 114.740789)
		(end 197.400017 114.740791)
		(width 0.1)
		(layer "In9.Cu")
		(net 191)
	)
	(segment
		(start 200.2 122.4)
		(end 200.6375 122.8375)
		(width 0.1)
		(layer "In9.Cu")
		(net 191)
	)
	(segment
		(start 202.75 137.35)
		(end 201.02 139.08)
		(width 0.1)
		(layer "In9.Cu")
		(net 191)
	)
	(segment
		(start 199.79 142)
		(end 199.33 142)
		(width 0.1)
		(layer "In9.Cu")
		(net 191)
	)
	(segment
		(start 199.25 121.75)
		(end 199.85 121.75)
		(width 0.1)
		(layer "In9.Cu")
		(net 191)
	)
	(segment
		(start 197.859629 115.872171)
		(end 198.5568 115.174999)
		(width 0.1)
		(layer "In9.Cu")
		(net 191)
	)
	(segment
		(start 202.75 124.95)
		(end 202.75 137.35)
		(width 0.1)
		(layer "In9.Cu")
		(net 191)
	)
	(segment
		(start 201.02 139.08)
		(end 201.02 140.73)
		(width 0.1)
		(layer "In9.Cu")
		(net 191)
	)
	(segment
		(start 201.02 140.73)
		(end 200.73 141.02)
		(width 0.1)
		(layer "In9.Cu")
		(net 191)
	)
	(segment
		(start 197.75 120.15)
		(end 199.8 120.15)
		(width 0.1)
		(layer "In9.Cu")
		(net 191)
	)
	(segment
		(start 201.670761 123.183096)
		(end 201.670761 123.183095)
		(width 0.1)
		(layer "In9.Cu")
		(net 191)
	)
	(segment
		(start 197.74 144.01)
		(end 196.25 144.01)
		(width 0.1)
		(layer "In9.Cu")
		(net 191)
	)
	(segment
		(start 198.79 143.02)
		(end 198.29 143.02)
		(width 0.1)
		(layer "In9.Cu")
		(net 191)
	)
	(segment
		(start 199.8 117.75)
		(end 197.75 117.75)
		(width 0.1)
		(layer "In9.Cu")
		(net 191)
	)
	(segment
		(start 201.670761 122.723477)
		(end 201.670762 122.723477)
		(width 0.1)
		(layer "In9.Cu")
		(net 191)
	)
	(segment
		(start 195.5 142.775)
		(end 195.5 142.5)
		(width 0.1)
		(layer "In9.Cu")
		(net 191)
	)
	(segment
		(start 197.718216 114.74079)
		(end 197.920403 114.538602)
		(width 0.1)
		(layer "In9.Cu")
		(net 191)
	)
	(segment
		(start 201.670761 123.183095)
		(end 201.556738 123.297119)
		(width 0.1)
		(layer "In9.Cu")
		(net 191)
	)
	(segment
		(start 198.238603 114.538603)
		(end 198.238602 114.538602)
		(width 0.1)
		(layer "In9.Cu")
		(net 191)
	)
	(segment
		(start 198.464023 117.10288)
		(end 198.672055 116.894847)
		(width 0.1)
		(layer "In9.Cu")
		(net 191)
	)
	(segment
		(start 198.5568 115.174999)
		(end 198.556801 115.174999)
		(width 0.1)
		(layer "In9.Cu")
		(net 191)
	)
	(segment
		(start 197.920403 114.538602)
		(end 197.920404 114.538602)
		(width 0.1)
		(layer "In9.Cu")
		(net 191)
	)
	(segment
		(start 198.672055 116.894847)
		(end 199.421319 116.145583)
		(width 0.1)
		(layer "In9.Cu")
		(net 191)
	)
	(segment
		(start 197.602203 114.220402)
		(end 197.400017 114.422591)
		(width 0.1)
		(layer "In9.Cu")
		(net 191)
	)
	(segment
		(start 199.845583 116.145583)
		(end 200.2 116.5)
		(width 0.1)
		(layer "In9.Cu")
		(net 191)
	)
	(segment
		(start 199.85 121.05)
		(end 199.25 121.05)
		(width 0.1)
		(layer "In9.Cu")
		(net 191)
	)
	(segment
		(start 200.73 141.02)
		(end 200.32 141.02)
		(width 0.1)
		(layer "In9.Cu")
		(net 191)
	)
	(segment
		(start 199.33 142)
		(end 199 142.33)
		(width 0.1)
		(layer "In9.Cu")
		(net 191)
	)
	(segment
		(start 201.097119 122.837499)
		(end 201.09712 122.837501)
		(width 0.1)
		(layer "In9.Cu")
		(net 191)
	)
	(segment
		(start 198.01 143.3)
		(end 198.01 143.74)
		(width 0.1)
		(layer "In9.Cu")
		(net 191)
	)
	(segment
		(start 198.997055 115.721321)
		(end 198.039758 116.678617)
		(width 0.1)
		(layer "In9.Cu")
		(net 191)
	)
	(segment
		(start 197.25 113.55)
		(end 197.602204 113.902203)
		(width 0.1)
		(layer "In9.Cu")
		(net 191)
	)
	(segment
		(start 197.54143 115.553971)
		(end 197.54143 115.553972)
		(width 0.1)
		(layer "In9.Cu")
		(net 191)
	)
	(segment
		(start 200.32 141.02)
		(end 200.06 141.28)
		(width 0.1)
		(layer "In9.Cu")
		(net 191)
	)
	(segment
		(start 201.556737 123.756737)
		(end 202.75 124.95)
		(width 0.1)
		(layer "In9.Cu")
		(net 191)
	)
	(segment
		(start 197.75 118.55)
		(end 199.8 118.55)
		(width 0.1)
		(layer "In9.Cu")
		(net 191)
	)
	(segment
		(start 200.2 122.1)
		(end 200.2 122.4)
		(width 0.1)
		(layer "In9.Cu")
		(net 191)
	)
	(segment
		(start 198.238602 114.8568)
		(end 197.54143 115.553971)
		(width 0.1)
		(layer "In9.Cu")
		(net 191)
	)
	(arc
		(start 199.8 118.55)
		(mid 200.082843 118.667157)
		(end 200.2 118.95)
		(width 0.1)
		(layer "In9.Cu")
		(net 191)
	)
	(arc
		(start 197.75 117.75)
		(mid 197.467157 117.867157)
		(end 197.35 118.15)
		(width 0.1)
		(layer "In9.Cu")
		(net 191)
	)
	(arc
		(start 197.54143 115.553972)
		(mid 197.475528 115.713071)
		(end 197.541431 115.872171)
		(width 0.1)
		(layer "In9.Cu")
		(net 191)
	)
	(arc
		(start 198.039758 117.102881)
		(mid 198.251891 117.190749)
		(end 198.464023 117.10288)
		(width 0.1)
		(layer "In9.Cu")
		(net 191)
	)
	(arc
		(start 197.541431 115.872171)
		(mid 197.70053 115.938072)
		(end 197.859629 115.872171)
		(width 0.1)
		(layer "In9.Cu")
		(net 191)
	)
	(arc
		(start 197.920404 114.538602)
		(mid 198.079503 114.4727)
		(end 198.238603 114.538603)
		(width 0.1)
		(layer "In9.Cu")
		(net 191)
	)
	(arc
		(start 199.8 120.15)
		(mid 200.082843 120.267157)
		(end 200.2 120.55)
		(width 0.1)
		(layer "In9.Cu")
		(net 191)
	)
	(arc
		(start 198.238602 114.538602)
		(mid 198.304503 114.697701)
		(end 198.238602 114.8568)
		(width 0.1)
		(layer "In9.Cu")
		(net 191)
	)
	(arc
		(start 199.85 121.75)
		(mid 200.097487 121.852513)
		(end 200.2 122.1)
		(width 0.1)
		(layer "In9.Cu")
		(net 191)
	)
	(arc
		(start 200.2 120.7)
		(mid 200.097487 120.947487)
		(end 199.85 121.05)
		(width 0.1)
		(layer "In9.Cu")
		(net 191)
	)
	(arc
		(start 200.2 117.35)
		(mid 200.082843 117.632843)
		(end 199.8 117.75)
		(width 0.1)
		(layer "In9.Cu")
		(net 191)
	)
	(arc
		(start 200.6375 122.8375)
		(mid 200.86731 122.93269)
		(end 201.097119 122.837499)
		(width 0.1)
		(layer "In9.Cu")
		(net 191)
	)
	(arc
		(start 198.9 121.4)
		(mid 199.002513 121.647487)
		(end 199.25 121.75)
		(width 0.1)
		(layer "In9.Cu")
		(net 191)
	)
	(arc
		(start 197.35 118.15)
		(mid 197.467157 118.432843)
		(end 197.75 118.55)
		(width 0.1)
		(layer "In9.Cu")
		(net 191)
	)
	(arc
		(start 197.400017 114.740791)
		(mid 197.559116 114.806691)
		(end 197.718216 114.74079)
		(width 0.1)
		(layer "In9.Cu")
		(net 191)
	)
	(arc
		(start 198.039758 116.678617)
		(mid 197.95189 116.890749)
		(end 198.039758 117.102881)
		(width 0.1)
		(layer "In9.Cu")
		(net 191)
	)
	(arc
		(start 199.25 121.05)
		(mid 199.002513 121.152513)
		(end 198.9 121.4)
		(width 0.1)
		(layer "In9.Cu")
		(net 191)
	)
	(arc
		(start 197.602204 113.902203)
		(mid 197.668106 114.061304)
		(end 197.602203 114.220402)
		(width 0.1)
		(layer "In9.Cu")
		(net 191)
	)
	(arc
		(start 201.556738 123.297119)
		(mid 201.461548 123.526929)
		(end 201.556739 123.756738)
		(width 0.1)
		(layer "In9.Cu")
		(net 191)
	)
	(arc
		(start 197.35 119.75)
		(mid 197.467157 120.032843)
		(end 197.75 120.15)
		(width 0.1)
		(layer "In9.Cu")
		(net 191)
	)
	(arc
		(start 197.75 119.35)
		(mid 197.467157 119.467157)
		(end 197.35 119.75)
		(width 0.1)
		(layer "In9.Cu")
		(net 191)
	)
	(arc
		(start 201.211142 122.723476)
		(mid 201.440952 122.628286)
		(end 201.670761 122.723477)
		(width 0.1)
		(layer "In9.Cu")
		(net 191)
	)
	(arc
		(start 197.400015 114.42259)
		(mid 197.334115 114.581691)
		(end 197.400016 114.740789)
		(width 0.1)
		(layer "In9.Cu")
		(net 191)
	)
	(arc
		(start 198.997056 115.297056)
		(mid 199.084924 115.509189)
		(end 198.997055 115.721321)
		(width 0.1)
		(layer "In9.Cu")
		(net 191)
	)
	(arc
		(start 199.421319 116.145583)
		(mid 199.633451 116.057715)
		(end 199.845583 116.145583)
		(width 0.1)
		(layer "In9.Cu")
		(net 191)
	)
	(arc
		(start 200.2 118.95)
		(mid 200.082843 119.232843)
		(end 199.8 119.35)
		(width 0.1)
		(layer "In9.Cu")
		(net 191)
	)
	(arc
		(start 201.670762 122.723477)
		(mid 201.765952 122.953287)
		(end 201.670761 123.183096)
		(width 0.1)
		(layer "In9.Cu")
		(net 191)
	)
	(arc
		(start 198.556801 115.174999)
		(mid 198.7159 115.109097)
		(end 198.875 115.175)
		(width 0.1)
		(layer "In9.Cu")
		(net 191)
	)
	(segment
		(start 193.0005 142.9995)
		(end 193.500001 142.5)
		(width 0.256)
		(layer "F.Cu")
		(net 192)
	)
	(segment
		(start 195.55 110.598)
		(end 195.55 111.75)
		(width 0.38)
		(layer "F.Cu")
		(net 192)
	)
	(via
		(at 195.55 111.75)
		(size 0.45)
		(drill 0.1)
		(layers "F.Cu" "B.Cu")
		(remove_unused_layers yes)
		(keep_end_layers yes)
		(zone_layer_connections)
		(net 192)
	)
	(via
		(at 193.500001 142.5)
		(size 0.45)
		(drill 0.1)
		(layers "F.Cu" "B.Cu")
		(remove_unused_layers yes)
		(keep_end_layers yes)
		(zone_layer_connections)
		(net 192)
	)
	(segment
		(start 201.96 141.98)
		(end 202.93 141.01)
		(width 0.1)
		(layer "In9.Cu")
		(net 192)
	)
	(segment
		(start 193.500001 142.5)
		(end 194.000001 143)
		(width 0.1)
		(layer "In9.Cu")
		(net 192)
	)
	(segment
		(start 196.12 106.64)
		(end 195.82 106.94)
		(width 0.1)
		(layer "In9.Cu")
		(net 192)
	)
	(segment
		(start 196.35 146.02)
		(end 197.67 146.02)
		(width 0.1)
		(layer "In9.Cu")
		(net 192)
	)
	(segment
		(start 198.68 145.04)
		(end 199 144.72)
		(width 0.1)
		(layer "In9.Cu")
		(net 192)
	)
	(segment
		(start 200.24 143.02)
		(end 200.71 143.02)
		(width 0.1)
		(layer "In9.Cu")
		(net 192)
	)
	(segment
		(start 195.82 111.48)
		(end 195.55 111.75)
		(width 0.1)
		(layer "In9.Cu")
		(net 192)
	)
	(segment
		(start 201.34 141.98)
		(end 201.96 141.98)
		(width 0.1)
		(layer "In9.Cu")
		(net 192)
	)
	(segment
		(start 198.22 145.04)
		(end 198.68 145.04)
		(width 0.1)
		(layer "In9.Cu")
		(net 192)
	)
	(segment
		(start 201.01 142.72)
		(end 201.01 142.31)
		(width 0.1)
		(layer "In9.Cu")
		(net 192)
	)
	(segment
		(start 205.08 118.73)
		(end 198.32 111.97)
		(width 0.1)
		(layer "In9.Cu")
		(net 192)
	)
	(segment
		(start 200.01 143.7)
		(end 200.01 143.25)
		(width 0.1)
		(layer "In9.Cu")
		(net 192)
	)
	(segment
		(start 198.32 111.97)
		(end 198.32 111.27)
		(width 0.1)
		(layer "In9.Cu")
		(net 192)
	)
	(segment
		(start 199 107.26)
		(end 198.38 106.64)
		(width 0.1)
		(layer "In9.Cu")
		(net 192)
	)
	(segment
		(start 200.71 143.02)
		(end 201.01 142.72)
		(width 0.1)
		(layer "In9.Cu")
		(net 192)
	)
	(segment
		(start 194.69 143)
		(end 195 143.31)
		(width 0.1)
		(layer "In9.Cu")
		(net 192)
	)
	(segment
		(start 195 144.69)
		(end 195.29 144.98)
		(width 0.1)
		(layer "In9.Cu")
		(net 192)
	)
	(segment
		(start 199 110.59)
		(end 199 107.26)
		(width 0.1)
		(layer "In9.Cu")
		(net 192)
	)
	(segment
		(start 199.71 144)
		(end 200.01 143.7)
		(width 0.1)
		(layer "In9.Cu")
		(net 192)
	)
	(segment
		(start 202.93 141.01)
		(end 202.93 139.89)
		(width 0.1)
		(layer "In9.Cu")
		(net 192)
	)
	(segment
		(start 197.67 146.02)
		(end 198.01 145.68)
		(width 0.1)
		(layer "In9.Cu")
		(net 192)
	)
	(segment
		(start 198.38 106.64)
		(end 196.12 106.64)
		(width 0.1)
		(layer "In9.Cu")
		(net 192)
	)
	(segment
		(start 199 144.72)
		(end 199 144.36)
		(width 0.1)
		(layer "In9.Cu")
		(net 192)
	)
	(segment
		(start 198.01 145.68)
		(end 198.01 145.25)
		(width 0.1)
		(layer "In9.Cu")
		(net 192)
	)
	(segment
		(start 199 144.36)
		(end 199.36 144)
		(width 0.1)
		(layer "In9.Cu")
		(net 192)
	)
	(segment
		(start 205.08 137.74)
		(end 205.08 118.73)
		(width 0.1)
		(layer "In9.Cu")
		(net 192)
	)
	(segment
		(start 196.01 145.29)
		(end 196.01 145.68)
		(width 0.1)
		(layer "In9.Cu")
		(net 192)
	)
	(segment
		(start 195.7 144.98)
		(end 196.01 145.29)
		(width 0.1)
		(layer "In9.Cu")
		(net 192)
	)
	(segment
		(start 199.36 144)
		(end 199.71 144)
		(width 0.1)
		(layer "In9.Cu")
		(net 192)
	)
	(segment
		(start 200.01 143.25)
		(end 200.24 143.02)
		(width 0.1)
		(layer "In9.Cu")
		(net 192)
	)
	(segment
		(start 194.000001 143)
		(end 194.69 143)
		(width 0.1)
		(layer "In9.Cu")
		(net 192)
	)
	(segment
		(start 195 143.31)
		(end 195 144.69)
		(width 0.1)
		(layer "In9.Cu")
		(net 192)
	)
	(segment
		(start 198.32 111.27)
		(end 199 110.59)
		(width 0.1)
		(layer "In9.Cu")
		(net 192)
	)
	(segment
		(start 198.01 145.25)
		(end 198.22 145.04)
		(width 0.1)
		(layer "In9.Cu")
		(net 192)
	)
	(segment
		(start 202.93 139.89)
		(end 205.08 137.74)
		(width 0.1)
		(layer "In9.Cu")
		(net 192)
	)
	(segment
		(start 195.82 106.94)
		(end 195.82 111.48)
		(width 0.1)
		(layer "In9.Cu")
		(net 192)
	)
	(segment
		(start 196.01 145.68)
		(end 196.35 146.02)
		(width 0.1)
		(layer "In9.Cu")
		(net 192)
	)
	(segment
		(start 201.01 142.31)
		(end 201.34 141.98)
		(width 0.1)
		(layer "In9.Cu")
		(net 192)
	)
	(segment
		(start 195.29 144.98)
		(end 195.7 144.98)
		(width 0.1)
		(layer "In9.Cu")
		(net 192)
	)
	(segment
		(start 196.0005 140.9995)
		(end 196.499999 140.5)
		(width 0.256)
		(layer "F.Cu")
		(net 193)
	)
	(segment
		(start 193.85 110.598)
		(end 193.85 111.75)
		(width 0.38)
		(layer "F.Cu")
		(net 193)
	)
	(via
		(at 193.85 111.75)
		(size 0.45)
		(drill 0.1)
		(layers "F.Cu" "B.Cu")
		(remove_unused_layers yes)
		(keep_end_layers yes)
		(zone_layer_connections)
		(net 193)
	)
	(via
		(at 196.499999 140.5)
		(size 0.45)
		(drill 0.1)
		(layers "F.Cu" "B.Cu")
		(remove_unused_layers yes)
		(keep_end_layers yes)
		(zone_layer_connections)
		(net 193)
	)
	(segment
		(start 192.169362 114.830638)
		(end 192.169365 114.830638)
		(width 0.1)
		(layer "In9.Cu")
		(net 193)
	)
	(segment
		(start 192.2 117.65)
		(end 192.2 117.525)
		(width 0.1)
		(layer "In9.Cu")
		(net 193)
	)
	(segment
		(start 192.94718 114.441729)
		(end 192.947181 114.441729)
		(width 0.1)
		(layer "In9.Cu")
		(net 193)
	)
	(segment
		(start 190.2 116.05)
		(end 190.45 115.8)
		(width 0.1)
		(layer "In9.Cu")
		(net 193)
	)
	(segment
		(start 194.85 121.6)
		(end 193.05 121.6)
		(width 0.1)
		(layer "In9.Cu")
		(net 193)
	)
	(segment
		(start 192.95 116.088579)
		(end 192.95 116.375)
		(width 0.1)
		(layer "In9.Cu")
		(net 193)
	)
	(segment
		(start 192.75 116.575)
		(end 190.525 116.575)
		(width 0.1)
		(layer "In9.Cu")
		(net 193)
	)
	(segment
		(start 193.265379 114.759928)
		(end 192.94718 114.441729)
		(width 0.1)
		(layer "In9.Cu")
		(net 193)
	)
	(segment
		(start 192.48756 115.537747)
		(end 192.169361 115.219548)
		(width 0.1)
		(layer "In9.Cu")
		(net 193)
	)
	(segment
		(start 190.949999 118.146447)
		(end 190.985355 118.11109)
		(width 0.1)
		(layer "In9.Cu")
		(net 193)
	)
	(segment
		(start 192.375 118.175)
		(end 192.731835 118.175)
		(width 0.1)
		(layer "In9.Cu")
		(net 193)
	)
	(segment
		(start 192.05 121.6)
		(end 191.8375 121.6)
		(width 0.1)
		(layer "In9.Cu")
		(net 193)
	)
	(segment
		(start 193.265379 115.148836)
		(end 193.265378 115.148837)
		(width 0.1)
		(layer "In9.Cu")
		(net 193)
	)
	(segment
		(start 190.2 116.25)
		(end 190.2 116.05)
		(width 0.1)
		(layer "In9.Cu")
		(net 193)
	)
	(segment
		(start 192.947181 114.052819)
		(end 192.947184 114.052819)
		(width 0.1)
		(layer "In9.Cu")
		(net 193)
	)
	(segment
		(start 194.043198 113.982109)
		(end 193.724999 113.66391)
		(width 0.1)
		(layer "In9.Cu")
		(net 193)
	)
	(segment
		(start 190.45 115.8)
		(end 191.2 115.8)
		(width 0.1)
		(layer "In9.Cu")
		(net 193)
	)
	(segment
		(start 192.558273 114.830638)
		(end 192.876471 115.148836)
		(width 0.1)
		(layer "In9.Cu")
		(net 193)
	)
	(segment
		(start 191.05 118.6)
		(end 190.95 118.5)
		(width 0.1)
		(layer "In9.Cu")
		(net 193)
	)
	(segment
		(start 193.725 113.275)
		(end 193.85 113.15)
		(width 0.1)
		(layer "In9.Cu")
		(net 193)
	)
	(segment
		(start 192.169361 115.219548)
		(end 192.169362 115.219548)
		(width 0.1)
		(layer "In9.Cu")
		(net 193)
	)
	(segment
		(start 191.780454 115.608457)
		(end 192.098652 115.926655)
		(width 0.1)
		(layer "In9.Cu")
		(net 193)
	)
	(segment
		(start 191.8375 121.6)
		(end 191.6 121.3625)
		(width 0.1)
		(layer "In9.Cu")
		(net 193)
	)
	(segment
		(start 192.731835 118.525)
		(end 192.375 118.525)
		(width 0.1)
		(layer "In9.Cu")
		(net 193)
	)
	(segment
		(start 196.55 140.5)
		(end 197 140.05)
		(width 0.1)
		(layer "In9.Cu")
		(net 193)
	)
	(segment
		(start 190.631802 117.757536)
		(end 190.596445 117.792892)
		(width 0.1)
		(layer "In9.Cu")
		(net 193)
	)
	(segment
		(start 192.8 121.35)
		(end 192.8 120)
		(width 0.1)
		(layer "In9.Cu")
		(net 193)
	)
	(segment
		(start 191.6 117.525)
		(end 191.6 119.175)
		(width 0.1)
		(layer "In9.Cu")
		(net 193)
	)
	(segment
		(start 192.375 118.875)
		(end 192.731835 118.875)
		(width 0.1)
		(layer "In9.Cu")
		(net 193)
	)
	(segment
		(start 198.15 124.9)
		(end 194.85 121.6)
		(width 0.1)
		(layer "In9.Cu")
		(net 193)
	)
	(segment
		(start 193.336092 114.052819)
		(end 193.65429 114.371017)
		(width 0.1)
		(layer "In9.Cu")
		(net 193)
	)
	(segment
		(start 197 140.05)
		(end 197 138.1)
		(width 0.1)
		(layer "In9.Cu")
		(net 193)
	)
	(segment
		(start 192.947184 114.052819)
		(end 192.947183 114.05282)
		(width 0.1)
		(layer "In9.Cu")
		(net 193)
	)
	(segment
		(start 192.731835 117.825)
		(end 192.375 117.825)
		(width 0.1)
		(layer "In9.Cu")
		(net 193)
	)
	(segment
		(start 192.48756 115.926655)
		(end 192.487559 115.926656)
		(width 0.1)
		(layer "In9.Cu")
		(net 193)
	)
	(segment
		(start 191.05 119.65)
		(end 191.05 118.6)
		(width 0.1)
		(layer "In9.Cu")
		(net 193)
	)
	(segment
		(start 192.5 117.225)
		(end 193.675 117.225)
		(width 0.1)
		(layer "In9.Cu")
		(net 193)
	)
	(segment
		(start 193.724999 113.66391)
		(end 193.725 113.66391)
		(width 0.1)
		(layer "In9.Cu")
		(net 193)
	)
	(segment
		(start 193.675 116.575)
		(end 193.55 116.575)
		(width 0.1)
		(layer "In9.Cu")
		(net 193)
	)
	(segment
		(start 193.35 116.375)
		(end 193.35 116.088579)
		(width 0.1)
		(layer "In9.Cu")
		(net 193)
	)
	(segment
		(start 190.985355 117.757536)
		(end 190.985355 117.757537)
		(width 0.1)
		(layer "In9.Cu")
		(net 193)
	)
	(segment
		(start 192.169365 114.830638)
		(end 192.169364 114.830639)
		(width 0.1)
		(layer "In9.Cu")
		(net 193)
	)
	(segment
		(start 196.499999 140.5)
		(end 196.55 140.5)
		(width 0.1)
		(layer "In9.Cu")
		(net 193)
	)
	(segment
		(start 191.6 121.3625)
		(end 191.6 120.2)
		(width 0.1)
		(layer "In9.Cu")
		(net 193)
	)
	(segment
		(start 190.242891 117.792892)
		(end 190.2 117.75)
		(width 0.1)
		(layer "In9.Cu")
		(net 193)
	)
	(segment
		(start 190.525 117.225)
		(end 191.3 117.225)
		(width 0.1)
		(layer "In9.Cu")
		(net 193)
	)
	(segment
		(start 191.6 120.2)
		(end 191.05 119.65)
		(width 0.1)
		(layer "In9.Cu")
		(net 193)
	)
	(segment
		(start 190.2 117.75)
		(end 190.2 117.55)
		(width 0.1)
		(layer "In9.Cu")
		(net 193)
	)
	(segment
		(start 197 138.1)
		(end 198.15 136.95)
		(width 0.1)
		(layer "In9.Cu")
		(net 193)
	)
	(segment
		(start 198.15 136.95)
		(end 198.15 124.9)
		(width 0.1)
		(layer "In9.Cu")
		(net 193)
	)
	(segment
		(start 192.2 119.175)
		(end 192.2 119.05)
		(width 0.1)
		(layer "In9.Cu")
		(net 193)
	)
	(segment
		(start 193.85 113.15)
		(end 193.85 111.75)
		(width 0.1)
		(layer "In9.Cu")
		(net 193)
	)
	(segment
		(start 192.3 120)
		(end 192.3 121.35)
		(width 0.1)
		(layer "In9.Cu")
		(net 193)
	)
	(segment
		(start 194.043198 114.371017)
		(end 194.043197 114.371018)
		(width 0.1)
		(layer "In9.Cu")
		(net 193)
	)
	(segment
		(start 191.2 115.8)
		(end 191.391545 115.608458)
		(width 0.1)
		(layer "In9.Cu")
		(net 193)
	)
	(arc
		(start 193.65429 114.371017)
		(mid 193.848745 114.451561)
		(end 194.043198 114.371017)
		(width 0.1)
		(layer "In9.Cu")
		(net 193)
	)
	(arc
		(start 193.265378 115.148837)
		(mid 193.345924 114.954383)
		(end 193.265379 114.759928)
		(width 0.1)
		(layer "In9.Cu")
		(net 193)
	)
	(arc
		(start 192.2 117.525)
		(mid 192.287868 117.312868)
		(end 192.5 117.225)
		(width 0.1)
		(layer "In9.Cu")
		(net 193)
	)
	(arc
		(start 192.731835 118.875)
		(mid 192.855579 118.823744)
		(end 192.906835 118.7)
		(width 0.1)
		(layer "In9.Cu")
		(net 193)
	)
	(arc
		(start 192.098652 115.926655)
		(mid 192.293107 116.007199)
		(end 192.48756 115.926655)
		(width 0.1)
		(layer "In9.Cu")
		(net 193)
	)
	(arc
		(start 190.2 117.55)
		(mid 190.29519 117.32019)
		(end 190.525 117.225)
		(width 0.1)
		(layer "In9.Cu")
		(net 193)
	)
	(arc
		(start 192.375 117.825)
		(mid 192.251256 117.773744)
		(end 192.2 117.65)
		(width 0.1)
		(layer "In9.Cu")
		(net 193)
	)
	(arc
		(start 192.169362 115.219548)
		(mid 192.088815 115.025094)
		(end 192.169362 114.830638)
		(width 0.1)
		(layer "In9.Cu")
		(net 193)
	)
	(arc
		(start 192.3 121.35)
		(mid 192.226777 121.526777)
		(end 192.05 121.6)
		(width 0.1)
		(layer "In9.Cu")
		(net 193)
	)
	(arc
		(start 192.906835 118.7)
		(mid 192.855579 118.576256)
		(end 192.731835 118.525)
		(width 0.1)
		(layer "In9.Cu")
		(net 193)
	)
	(arc
		(start 190.525 116.575)
		(mid 190.29519 116.47981)
		(end 190.2 116.25)
		(width 0.1)
		(layer "In9.Cu")
		(net 193)
	)
	(arc
		(start 193.05 121.6)
		(mid 192.873223 121.526777)
		(end 192.8 121.35)
		(width 0.1)
		(layer "In9.Cu")
		(net 193)
	)
	(arc
		(start 193.725 113.66391)
		(mid 193.644453 113.469456)
		(end 193.725 113.275)
		(width 0.1)
		(layer "In9.Cu")
		(net 193)
	)
	(arc
		(start 191.3 117.225)
		(mid 191.512132 117.312868)
		(end 191.6 117.525)
		(width 0.1)
		(layer "In9.Cu")
		(net 193)
	)
	(arc
		(start 192.55 119.75)
		(mid 192.373223 119.823223)
		(end 192.3 120)
		(width 0.1)
		(layer "In9.Cu")
		(net 193)
	)
	(arc
		(start 192.947181 114.441729)
		(mid 192.866634 114.247275)
		(end 192.947181 114.052819)
		(width 0.1)
		(layer "In9.Cu")
		(net 193)
	)
	(arc
		(start 191.6 119.175)
		(mid 191.687868 119.387132)
		(end 191.9 119.475)
		(width 0.1)
		(layer "In9.Cu")
		(net 193)
	)
	(arc
		(start 193.35 116.088579)
		(mid 193.291421 115.947158)
		(end 193.15 115.888579)
		(width 0.1)
		(layer "In9.Cu")
		(net 193)
	)
	(arc
		(start 190.985355 117.757537)
		(mid 190.808579 117.684313)
		(end 190.631802 117.757536)
		(width 0.1)
		(layer "In9.Cu")
		(net 193)
	)
	(arc
		(start 194 116.9)
		(mid 193.90481 116.67019)
		(end 193.675 116.575)
		(width 0.1)
		(layer "In9.Cu")
		(net 193)
	)
	(arc
		(start 192.95 116.375)
		(mid 192.891421 116.516421)
		(end 192.75 116.575)
		(width 0.1)
		(layer "In9.Cu")
		(net 193)
	)
	(arc
		(start 192.731835 118.175)
		(mid 192.855579 118.123744)
		(end 192.906835 118)
		(width 0.1)
		(layer "In9.Cu")
		(net 193)
	)
	(arc
		(start 190.596445 117.792892)
		(mid 190.419668 117.866115)
		(end 190.242891 117.792892)
		(width 0.1)
		(layer "In9.Cu")
		(net 193)
	)
	(arc
		(start 193.15 115.888579)
		(mid 193.008579 115.947158)
		(end 192.95 116.088579)
		(width 0.1)
		(layer "In9.Cu")
		(net 193)
	)
	(arc
		(start 193.55 116.575)
		(mid 193.408579 116.516421)
		(end 193.35 116.375)
		(width 0.1)
		(layer "In9.Cu")
		(net 193)
	)
	(arc
		(start 192.487559 115.926656)
		(mid 192.568105 115.732202)
		(end 192.48756 115.537747)
		(width 0.1)
		(layer "In9.Cu")
		(net 193)
	)
	(arc
		(start 192.375 118.525)
		(mid 192.251256 118.473744)
		(end 192.2 118.35)
		(width 0.1)
		(layer "In9.Cu")
		(net 193)
	)
	(arc
		(start 192.169364 114.830639)
		(mid 192.363818 114.750093)
		(end 192.558273 114.830638)
		(width 0.1)
		(layer "In9.Cu")
		(net 193)
	)
	(arc
		(start 192.906835 118)
		(mid 192.855579 117.876256)
		(end 192.731835 117.825)
		(width 0.1)
		(layer "In9.Cu")
		(net 193)
	)
	(arc
		(start 193.675 117.225)
		(mid 193.90481 117.12981)
		(end 194 116.9)
		(width 0.1)
		(layer "In9.Cu")
		(net 193)
	)
	(arc
		(start 190.95 118.5)
		(mid 190.876776 118.323224)
		(end 190.949999 118.146447)
		(width 0.1)
		(layer "In9.Cu")
		(net 193)
	)
	(arc
		(start 192.876471 115.148836)
		(mid 193.070926 115.22938)
		(end 193.265379 115.148836)
		(width 0.1)
		(layer "In9.Cu")
		(net 193)
	)
	(arc
		(start 190.985355 118.11109)
		(mid 191.058578 117.934313)
		(end 190.985355 117.757536)
		(width 0.1)
		(layer "In9.Cu")
		(net 193)
	)
	(arc
		(start 192.2 118.35)
		(mid 192.251256 118.226256)
		(end 192.375 118.175)
		(width 0.1)
		(layer "In9.Cu")
		(net 193)
	)
	(arc
		(start 192.8 120)
		(mid 192.726777 119.823223)
		(end 192.55 119.75)
		(width 0.1)
		(layer "In9.Cu")
		(net 193)
	)
	(arc
		(start 191.9 119.475)
		(mid 192.112132 119.387132)
		(end 192.2 119.175)
		(width 0.1)
		(layer "In9.Cu")
		(net 193)
	)
	(arc
		(start 192.2 119.05)
		(mid 192.251256 118.926256)
		(end 192.375 118.875)
		(width 0.1)
		(layer "In9.Cu")
		(net 193)
	)
	(arc
		(start 191.391545 115.608458)
		(mid 191.585999 115.527912)
		(end 191.780454 115.608457)
		(width 0.1)
		(layer "In9.Cu")
		(net 193)
	)
	(arc
		(start 194.043197 114.371018)
		(mid 194.123743 114.176564)
		(end 194.043198 113.982109)
		(width 0.1)
		(layer "In9.Cu")
		(net 193)
	)
	(arc
		(start 192.947183 114.05282)
		(mid 193.141637 113.972274)
		(end 193.336092 114.052819)
		(width 0.1)
		(layer "In9.Cu")
		(net 193)
	)
	(segment
		(start 192.15 110.598)
		(end 192.15 111.75)
		(width 0.38)
		(layer "F.Cu")
		(net 194)
	)
	(segment
		(start 195.0005 139.9995)
		(end 195.5 139.5)
		(width 0.256)
		(layer "F.Cu")
		(net 194)
	)
	(via
		(at 192.15 111.75)
		(size 0.45)
		(drill 0.1)
		(layers "F.Cu" "B.Cu")
		(remove_unused_layers yes)
		(keep_end_layers yes)
		(zone_layer_connections)
		(net 194)
	)
	(via
		(at 195.5 139.5)
		(size 0.45)
		(drill 0.1)
		(layers "F.Cu" "B.Cu")
		(remove_unused_layers yes)
		(keep_end_layers yes)
		(zone_layer_connections)
		(net 194)
	)
	(segment
		(start 187.9 115.25)
		(end 187.9 115.4)
		(width 0.1)
		(layer "In9.Cu")
		(net 194)
	)
	(segment
		(start 195.734187 125.934187)
		(end 196 126.2)
		(width 0.1)
		(layer "In9.Cu")
		(net 194)
	)
	(segment
		(start 189.6 123.5)
		(end 189.95 123.85)
		(width 0.1)
		(layer "In9.Cu")
		(net 194)
	)
	(segment
		(start 187.9 118.7)
		(end 188.075 118.875)
		(width 0.1)
		(layer "In9.Cu")
		(net 194)
	)
	(segment
		(start 191.05 114.1)
		(end 190.9 114.1)
		(width 0.1)
		(layer "In9.Cu")
		(net 194)
	)
	(segment
		(start 193.25 123.1)
		(end 193.25 123.6)
		(width 0.1)
		(layer "In9.Cu")
		(net 194)
	)
	(segment
		(start 189.95 123.85)
		(end 190.5 123.85)
		(width 0.1)
		(layer "In9.Cu")
		(net 194)
	)
	(segment
		(start 189.85 120.85)
		(end 190.35 120.85)
		(width 0.1)
		(layer "In9.Cu")
		(net 194)
	)
	(segment
		(start 195.415991 125.297791)
		(end 195.804899 124.908884)
		(width 0.1)
		(layer "In9.Cu")
		(net 194)
	)
	(segment
		(start 196 137)
		(end 195.5 137.5)
		(width 0.1)
		(layer "In9.Cu")
		(net 194)
	)
	(segment
		(start 190.75 123.6)
		(end 190.75 123.1)
		(width 0.1)
		(layer "In9.Cu")
		(net 194)
	)
	(segment
		(start 189.6 123.4)
		(end 189.6 123.5)
		(width 0.1)
		(layer "In9.Cu")
		(net 194)
	)
	(segment
		(start 195.486701 124.590686)
		(end 195.097791 124.979593)
		(width 0.1)
		(layer "In9.Cu")
		(net 194)
	)
	(segment
		(start 187.9 118.1)
		(end 187.9 118.7)
		(width 0.1)
		(layer "In9.Cu")
		(net 194)
	)
	(segment
		(start 196.123097 125.227082)
		(end 195.734187 125.615989)
		(width 0.1)
		(layer "In9.Cu")
		(net 194)
	)
	(segment
		(start 189.489212 120.289213)
		(end 189.6 120.4)
		(width 0.1)
		(layer "In9.Cu")
		(net 194)
	)
	(segment
		(start 191.25 123.1)
		(end 191.25 123.6)
		(width 0.1)
		(layer "In9.Cu")
		(net 194)
	)
	(segment
		(start 189.842765 119.582106)
		(end 189.842765 119.582105)
		(width 0.1)
		(layer "In9.Cu")
		(net 194)
	)
	(segment
		(start 195.4867 124.590687)
		(end 195.486701 124.590686)
		(width 0.1)
		(layer "In9.Cu")
		(net 194)
	)
	(segment
		(start 189.135659 119.582105)
		(end 189.13566 119.582107)
		(width 0.1)
		(layer "In9.Cu")
		(net 194)
	)
	(segment
		(start 196 126.2)
		(end 196 137)
		(width 0.1)
		(layer "In9.Cu")
		(net 194)
	)
	(segment
		(start 190.3 114.55)
		(end 190.3 114.3)
		(width 0.1)
		(layer "In9.Cu")
		(net 194)
	)
	(segment
		(start 189.5 114.55)
		(end 189.5 114.3)
		(width 0.1)
		(layer "In9.Cu")
		(net 194)
	)
	(segment
		(start 189.85 121.85)
		(end 190.35 121.85)
		(width 0.1)
		(layer "In9.Cu")
		(net 194)
	)
	(segment
		(start 195.5 137.5)
		(end 195.5 139.5)
		(width 0.1)
		(layer "In9.Cu")
		(net 194)
	)
	(segment
		(start 189.3 114.1)
		(end 189.05 114.1)
		(width 0.1)
		(layer "In9.Cu")
		(net 194)
	)
	(segment
		(start 194.850305 123.95429)
		(end 194.461395 124.343197)
		(width 0.1)
		(layer "In9.Cu")
		(net 194)
	)
	(segment
		(start 192.75 123.6)
		(end 192.75 123.1)
		(width 0.1)
		(layer "In9.Cu")
		(net 194)
	)
	(segment
		(start 189.05 114.1)
		(end 188.948527 114.20147)
		(width 0.1)
		(layer "In9.Cu")
		(net 194)
	)
	(segment
		(start 188.675 117.875)
		(end 188.125 117.875)
		(width 0.1)
		(layer "In9.Cu")
		(net 194)
	)
	(segment
		(start 188.948528 115.05)
		(end 188.948529 115.049999)
		(width 0.1)
		(layer "In9.Cu")
		(net 194)
	)
	(segment
		(start 192.15 113)
		(end 191.05 114.1)
		(width 0.1)
		(layer "In9.Cu")
		(net 194)
	)
	(segment
		(start 194.779595 124.661395)
		(end 195.168503 124.272488)
		(width 0.1)
		(layer "In9.Cu")
		(net 194)
	)
	(segment
		(start 188.125 116.525)
		(end 188.675 116.525)
		(width 0.1)
		(layer "In9.Cu")
		(net 194)
	)
	(segment
		(start 189.6 122.6)
		(end 189.6 122.7)
		(width 0.1)
		(layer "In9.Cu")
		(net 194)
	)
	(segment
		(start 194.461395 124.661395)
		(end 194.461396 124.661396)
		(width 0.1)
		(layer "In9.Cu")
		(net 194)
	)
	(segment
		(start 194.850304 123.954291)
		(end 194.850305 123.95429)
		(width 0.1)
		(layer "In9.Cu")
		(net 194)
	)
	(segment
		(start 192.25 123.1)
		(end 192.25 123.6)
		(width 0.1)
		(layer "In9.Cu")
		(net 194)
	)
	(segment
		(start 189.966704 123.225)
		(end 189.775 123.225)
		(width 0.1)
		(layer "In9.Cu")
		(net 194)
	)
	(segment
		(start 195.097791 125.297791)
		(end 195.097792 125.297792)
		(width 0.1)
		(layer "In9.Cu")
		(net 194)
	)
	(segment
		(start 189.135659 118.874999)
		(end 188.782106 119.228553)
		(width 0.1)
		(layer "In9.Cu")
		(net 194)
	)
	(segment
		(start 189.9 114.3)
		(end 189.9 114.55)
		(width 0.1)
		(layer "In9.Cu")
		(net 194)
	)
	(segment
		(start 194.143199 124.024999)
		(end 194.532107 123.636092)
		(width 0.1)
		(layer "In9.Cu")
		(net 194)
	)
	(segment
		(start 189.842766 119.228552)
		(end 189.842766 119.228553)
		(width 0.1)
		(layer "In9.Cu")
		(net 194)
	)
	(segment
		(start 189.13566 118.521446)
		(end 189.13566 118.521447)
		(width 0.1)
		(layer "In9.Cu")
		(net 194)
	)
	(segment
		(start 188.675 116.975)
		(end 188.125 116.975)
		(width 0.1)
		(layer "In9.Cu")
		(net 194)
	)
	(segment
		(start 193.5 123.85)
		(end 193.65 123.85)
		(width 0.1)
		(layer "In9.Cu")
		(net 194)
	)
	(segment
		(start 189.842765 119.582105)
		(end 189.489212 119.935659)
		(width 0.1)
		(layer "In9.Cu")
		(net 194)
	)
	(segment
		(start 189.135659 118.875)
		(end 189.135659 118.874999)
		(width 0.1)
		(layer "In9.Cu")
		(net 194)
	)
	(segment
		(start 192.15 111.75)
		(end 192.15 113)
		(width 0.1)
		(layer "In9.Cu")
		(net 194)
	)
	(segment
		(start 188.125 115.625)
		(end 188.675 115.625)
		(width 0.1)
		(layer "In9.Cu")
		(net 194)
	)
	(segment
		(start 190.35 121.35)
		(end 189.85 121.35)
		(width 0.1)
		(layer "In9.Cu")
		(net 194)
	)
	(segment
		(start 190.7 114.3)
		(end 190.7 114.55)
		(width 0.1)
		(layer "In9.Cu")
		(net 194)
	)
	(segment
		(start 188.782106 119.582107)
		(end 188.782106 119.582106)
		(width 0.1)
		(layer "In9.Cu")
		(net 194)
	)
	(segment
		(start 189.6 120.4)
		(end 189.6 120.6)
		(width 0.1)
		(layer "In9.Cu")
		(net 194)
	)
	(segment
		(start 188.125 117.425)
		(end 188.675 117.425)
		(width 0.1)
		(layer "In9.Cu")
		(net 194)
	)
	(segment
		(start 193.65 123.85)
		(end 193.825 124.025)
		(width 0.1)
		(layer "In9.Cu")
		(net 194)
	)
	(segment
		(start 190.35 122.35)
		(end 189.85 122.35)
		(width 0.1)
		(layer "In9.Cu")
		(net 194)
	)
	(segment
		(start 188.428554 118.875001)
		(end 188.782106 118.521446)
		(width 0.1)
		(layer "In9.Cu")
		(net 194)
	)
	(segment
		(start 188.948528 114.625735)
		(end 188.948528 114.625734)
		(width 0.1)
		(layer "In9.Cu")
		(net 194)
	)
	(segment
		(start 189.775 122.875)
		(end 189.966704 122.875)
		(width 0.1)
		(layer "In9.Cu")
		(net 194)
	)
	(segment
		(start 189.13566 119.582107)
		(end 189.489212 119.228552)
		(width 0.1)
		(layer "In9.Cu")
		(net 194)
	)
	(segment
		(start 188.675 116.075)
		(end 188.125 116.075)
		(width 0.1)
		(layer "In9.Cu")
		(net 194)
	)
	(segment
		(start 188.428553 118.874999)
		(end 188.428554 118.875001)
		(width 0.1)
		(layer "In9.Cu")
		(net 194)
	)
	(segment
		(start 196.123096 125.227083)
		(end 196.123097 125.227082)
		(width 0.1)
		(layer "In9.Cu")
		(net 194)
	)
	(segment
		(start 188.1 115.05)
		(end 187.9 115.25)
		(width 0.1)
		(layer "In9.Cu")
		(net 194)
	)
	(segment
		(start 191.75 123.6)
		(end 191.75 123.1)
		(width 0.1)
		(layer "In9.Cu")
		(net 194)
	)
	(arc
		(start 188.675 115.625)
		(mid 188.834099 115.690901)
		(end 188.9 115.85)
		(width 0.1)
		(layer "In9.Cu")
		(net 194)
	)
	(arc
		(start 195.168503 124.272488)
		(mid 195.327602 124.206587)
		(end 195.486701 124.272488)
		(width 0.1)
		(layer "In9.Cu")
		(net 194)
	)
	(arc
		(start 189.966704 122.875)
		(mid 190.090448 122.926256)
		(end 190.141704 123.05)
		(width 0.1)
		(layer "In9.Cu")
		(net 194)
	)
	(arc
		(start 188.948528 114.625734)
		(mid 189.036396 114.837867)
		(end 188.948528 115.05)
		(width 0.1)
		(layer "In9.Cu")
		(net 194)
	)
	(arc
		(start 187.9 117.2)
		(mid 187.965901 117.359099)
		(end 188.125 117.425)
		(width 0.1)
		(layer "In9.Cu")
		(net 194)
	)
	(arc
		(start 194.532107 123.636092)
		(mid 194.691206 123.570191)
		(end 194.850305 123.636092)
		(width 0.1)
		(layer "In9.Cu")
		(net 194)
	)
	(arc
		(start 195.734187 125.615989)
		(mid 195.668286 125.775088)
		(end 195.734187 125.934187)
		(width 0.1)
		(layer "In9.Cu")
		(net 194)
	)
	(arc
		(start 189.775 123.225)
		(mid 189.651256 123.276256)
		(end 189.6 123.4)
		(width 0.1)
		(layer "In9.Cu")
		(net 194)
	)
	(arc
		(start 189.85 121.35)
		(mid 189.673223 121.423223)
		(end 189.6 121.6)
		(width 0.1)
		(layer "In9.Cu")
		(net 194)
	)
	(arc
		(start 190.35 120.85)
		(mid 190.526777 120.923223)
		(end 190.6 121.1)
		(width 0.1)
		(layer "In9.Cu")
		(net 194)
	)
	(arc
		(start 192 122.85)
		(mid 192.176777 122.923223)
		(end 192.25 123.1)
		(width 0.1)
		(layer "In9.Cu")
		(net 194)
	)
	(arc
		(start 189.13566 118.521447)
		(mid 189.208883 118.698224)
		(end 189.135659 118.875)
		(width 0.1)
		(layer "In9.Cu")
		(net 194)
	)
	(arc
		(start 188.782106 118.521446)
		(mid 188.958883 118.448223)
		(end 189.13566 118.521446)
		(width 0.1)
		(layer "In9.Cu")
		(net 194)
	)
	(arc
		(start 192.5 123.85)
		(mid 192.676777 123.776777)
		(end 192.75 123.6)
		(width 0.1)
		(layer "In9.Cu")
		(net 194)
	)
	(arc
		(start 191.75 123.1)
		(mid 191.823223 122.923223)
		(end 192 122.85)
		(width 0.1)
		(layer "In9.Cu")
		(net 194)
	)
	(arc
		(start 190.75 123.1)
		(mid 190.823223 122.923223)
		(end 191 122.85)
		(width 0.1)
		(layer "In9.Cu")
		(net 194)
	)
	(arc
		(start 188.524264 115.05)
		(mid 188.312132 114.962132)
		(end 188.1 115.05)
		(width 0.1)
		(layer "In9.Cu")
		(net 194)
	)
	(arc
		(start 191.5 123.85)
		(mid 191.676777 123.776777)
		(end 191.75 123.6)
		(width 0.1)
		(layer "In9.Cu")
		(net 194)
	)
	(arc
		(start 188.782106 119.582106)
		(mid 188.958883 119.655329)
		(end 189.135659 119.582105)
		(width 0.1)
		(layer "In9.Cu")
		(net 194)
	)
	(arc
		(start 196.123097 124.908884)
		(mid 196.188997 125.067983)
		(end 196.123096 125.227083)
		(width 0.1)
		(layer "In9.Cu")
		(net 194)
	)
	(arc
		(start 190.1 114.1)
		(mid 189.958579 114.158579)
		(end 189.9 114.3)
		(width 0.1)
		(layer "In9.Cu")
		(net 194)
	)
	(arc
		(start 194.850305 123.636092)
		(mid 194.916205 123.795191)
		(end 194.850304 123.954291)
		(width 0.1)
		(layer "In9.Cu")
		(net 194)
	)
	(arc
		(start 190.3 114.3)
		(mid 190.241421 114.158579)
		(end 190.1 114.1)
		(width 0.1)
		(layer "In9.Cu")
		(net 194)
	)
	(arc
		(start 192.25 123.6)
		(mid 192.323223 123.776777)
		(end 192.5 123.85)
		(width 0.1)
		(layer "In9.Cu")
		(net 194)
	)
	(arc
		(start 192.75 123.1)
		(mid 192.823223 122.923223)
		(end 193 122.85)
		(width 0.1)
		(layer "In9.Cu")
		(net 194)
	)
	(arc
		(start 190.6 121.1)
		(mid 190.526777 121.276777)
		(end 190.35 121.35)
		(width 0.1)
		(layer "In9.Cu")
		(net 194)
	)
	(arc
		(start 189.6 122.7)
		(mid 189.651256 122.823744)
		(end 189.775 122.875)
		(width 0.1)
		(layer "In9.Cu")
		(net 194)
	)
	(arc
		(start 189.489212 119.228552)
		(mid 189.665989 119.155329)
		(end 189.842766 119.228552)
		(width 0.1)
		(layer "In9.Cu")
		(net 194)
	)
	(arc
		(start 191.25 123.6)
		(mid 191.323223 123.776777)
		(end 191.5 123.85)
		(width 0.1)
		(layer "In9.Cu")
		(net 194)
	)
	(arc
		(start 188.9 115.85)
		(mid 188.834099 116.009099)
		(end 188.675 116.075)
		(width 0.1)
		(layer "In9.Cu")
		(net 194)
	)
	(arc
		(start 190.141704 123.05)
		(mid 190.090448 123.173744)
		(end 189.966704 123.225)
		(width 0.1)
		(layer "In9.Cu")
		(net 194)
	)
	(arc
		(start 188.075 118.875)
		(mid 188.251777 118.948223)
		(end 188.428553 118.874999)
		(width 0.1)
		(layer "In9.Cu")
		(net 194)
	)
	(arc
		(start 194.461396 124.661396)
		(mid 194.620497 124.727298)
		(end 194.779595 124.661395)
		(width 0.1)
		(layer "In9.Cu")
		(net 194)
	)
	(arc
		(start 189.6 120.6)
		(mid 189.673223 120.776777)
		(end 189.85 120.85)
		(width 0.1)
		(layer "In9.Cu")
		(net 194)
	)
	(arc
		(start 195.804899 124.908884)
		(mid 195.963998 124.842983)
		(end 196.123097 124.908884)
		(width 0.1)
		(layer "In9.Cu")
		(net 194)
	)
	(arc
		(start 189.9 114.55)
		(mid 189.841421 114.691421)
		(end 189.7 114.75)
		(width 0.1)
		(layer "In9.Cu")
		(net 194)
	)
	(arc
		(start 189.7 114.75)
		(mid 189.558579 114.691421)
		(end 189.5 114.55)
		(width 0.1)
		(layer "In9.Cu")
		(net 194)
	)
	(arc
		(start 188.675 116.525)
		(mid 188.834099 116.590901)
		(end 188.9 116.75)
		(width 0.1)
		(layer "In9.Cu")
		(net 194)
	)
	(arc
		(start 190.9 114.1)
		(mid 190.758579 114.158579)
		(end 190.7 114.3)
		(width 0.1)
		(layer "In9.Cu")
		(net 194)
	)
	(arc
		(start 195.097791 124.979593)
		(mid 195.03189 125.138692)
		(end 195.097791 125.297791)
		(width 0.1)
		(layer "In9.Cu")
		(net 194)
	)
	(arc
		(start 188.675 117.425)
		(mid 188.834099 117.490901)
		(end 188.9 117.65)
		(width 0.1)
		(layer "In9.Cu")
		(net 194)
	)
	(arc
		(start 188.9 117.65)
		(mid 188.834099 117.809099)
		(end 188.675 117.875)
		(width 0.1)
		(layer "In9.Cu")
		(net 194)
	)
	(arc
		(start 195.486701 124.272488)
		(mid 195.552601 124.431587)
		(end 195.4867 124.590687)
		(width 0.1)
		(layer "In9.Cu")
		(net 194)
	)
	(arc
		(start 195.097792 125.297792)
		(mid 195.256893 125.363694)
		(end 195.415991 125.297791)
		(width 0.1)
		(layer "In9.Cu")
		(net 194)
	)
	(arc
		(start 193 122.85)
		(mid 193.176777 122.923223)
		(end 193.25 123.1)
		(width 0.1)
		(layer "In9.Cu")
		(net 194)
	)
	(arc
		(start 188.125 116.075)
		(mid 187.965901 116.140901)
		(end 187.9 116.3)
		(width 0.1)
		(layer "In9.Cu")
		(net 194)
	)
	(arc
		(start 189.489212 119.935659)
		(mid 189.415989 120.112436)
		(end 189.489212 120.289213)
		(width 0.1)
		(layer "In9.Cu")
		(net 194)
	)
	(arc
		(start 190.35 121.85)
		(mid 190.526777 121.923223)
		(end 190.6 122.1)
		(width 0.1)
		(layer "In9.Cu")
		(net 194)
	)
	(arc
		(start 193.825 124.025)
		(mid 193.984101 124.090902)
		(end 194.143199 124.024999)
		(width 0.1)
		(layer "In9.Cu")
		(net 194)
	)
	(arc
		(start 193.25 123.6)
		(mid 193.323223 123.776777)
		(end 193.5 123.85)
		(width 0.1)
		(layer "In9.Cu")
		(net 194)
	)
	(arc
		(start 187.9 116.3)
		(mid 187.965901 116.459099)
		(end 188.125 116.525)
		(width 0.1)
		(layer "In9.Cu")
		(net 194)
	)
	(arc
		(start 188.125 116.975)
		(mid 187.965901 117.040901)
		(end 187.9 117.2)
		(width 0.1)
		(layer "In9.Cu")
		(net 194)
	)
	(arc
		(start 190.5 123.85)
		(mid 190.676777 123.776777)
		(end 190.75 123.6)
		(width 0.1)
		(layer "In9.Cu")
		(net 194)
	)
	(arc
		(start 190.5 114.75)
		(mid 190.358579 114.691421)
		(end 190.3 114.55)
		(width 0.1)
		(layer "In9.Cu")
		(net 194)
	)
	(arc
		(start 189.85 122.35)
		(mid 189.673223 122.423223)
		(end 189.6 122.6)
		(width 0.1)
		(layer "In9.Cu")
		(net 194)
	)
	(arc
		(start 189.5 114.3)
		(mid 189.441421 114.158579)
		(end 189.3 114.1)
		(width 0.1)
		(layer "In9.Cu")
		(net 194)
	)
	(arc
		(start 190.6 122.1)
		(mid 190.526777 122.276777)
		(end 190.35 122.35)
		(width 0.1)
		(layer "In9.Cu")
		(net 194)
	)
	(arc
		(start 189.842766 119.228553)
		(mid 189.915989 119.40533)
		(end 189.842765 119.582106)
		(width 0.1)
		(layer "In9.Cu")
		(net 194)
	)
	(arc
		(start 188.948527 114.20147)
		(mid 188.860659 114.413603)
		(end 188.948528 114.625735)
		(width 0.1)
		(layer "In9.Cu")
		(net 194)
	)
	(arc
		(start 188.782106 119.228553)
		(mid 188.708883 119.40533)
		(end 188.782106 119.582107)
		(width 0.1)
		(layer "In9.Cu")
		(net 194)
	)
	(arc
		(start 188.9 116.75)
		(mid 188.834099 116.909099)
		(end 188.675 116.975)
		(width 0.1)
		(layer "In9.Cu")
		(net 194)
	)
	(arc
		(start 190.7 114.55)
		(mid 190.641421 114.691421)
		(end 190.5 114.75)
		(width 0.1)
		(layer "In9.Cu")
		(net 194)
	)
	(arc
		(start 188.125 117.875)
		(mid 187.965901 117.940901)
		(end 187.9 118.1)
		(width 0.1)
		(layer "In9.Cu")
		(net 194)
	)
	(arc
		(start 191 122.85)
		(mid 191.176777 122.923223)
		(end 191.25 123.1)
		(width 0.1)
		(layer "In9.Cu")
		(net 194)
	)
	(arc
		(start 194.461395 124.343197)
		(mid 194.395494 124.502296)
		(end 194.461395 124.661395)
		(width 0.1)
		(layer "In9.Cu")
		(net 194)
	)
	(arc
		(start 187.9 115.4)
		(mid 187.965901 115.559099)
		(end 188.125 115.625)
		(width 0.1)
		(layer "In9.Cu")
		(net 194)
	)
	(arc
		(start 189.6 121.6)
		(mid 189.673223 121.776777)
		(end 189.85 121.85)
		(width 0.1)
		(layer "In9.Cu")
		(net 194)
	)
	(arc
		(start 188.948529 115.049999)
		(mid 188.736397 115.137868)
		(end 188.524264 115.05)
		(width 0.1)
		(layer "In9.Cu")
		(net 194)
	)
	(segment
		(start 173.45 110.598)
		(end 173.45 111.75)
		(width 0.38)
		(layer "F.Cu")
		(net 195)
	)
	(via
		(at 173.45 111.75)
		(size 0.45)
		(drill 0.1)
		(layers "F.Cu" "B.Cu")
		(remove_unused_layers yes)
		(keep_end_layers yes)
		(zone_layer_connections)
		(net 195)
	)
	(segment
		(start 172.6 110.598)
		(end 172.6 111.75)
		(width 0.38)
		(layer "F.Cu")
		(net 196)
	)
	(via
		(at 172.6 111.75)
		(size 0.45)
		(drill 0.1)
		(layers "F.Cu" "B.Cu")
		(remove_unused_layers yes)
		(keep_end_layers yes)
		(zone_layer_connections)
		(net 196)
	)
	(segment
		(start 134.094834 170.678665)
		(end 134.124499 170.649)
		(width 0.1)
		(layer "F.Cu")
		(net 197)
	)
	(segment
		(start 134.094834 171.274834)
		(end 134.094834 170.678665)
		(width 0.177)
		(layer "F.Cu")
		(net 197)
	)
	(segment
		(start 134.380499 170.393)
		(end 134.124499 170.649)
		(width 0.182)
		(layer "F.Cu")
		(net 197)
	)
	(segment
		(start 241.001 145.1)
		(end 240 145.1)
		(width 0.256)
		(layer "F.Cu")
		(net 197)
	)
	(segment
		(start 135.525499 170.393)
		(end 134.380499 170.393)
		(width 0.182)
		(layer "F.Cu")
		(net 197)
	)
	(via
		(at 134.094834 171.274834)
		(size 0.45)
		(drill 0.1)
		(layers "F.Cu" "B.Cu")
		(remove_unused_layers yes)
		(keep_end_layers yes)
		(zone_layer_connections)
		(net 197)
	)
	(via
		(at 240 145.1)
		(size 0.45)
		(drill 0.1)
		(layers "F.Cu" "B.Cu")
		(remove_unused_layers yes)
		(keep_end_layers yes)
		(zone_layer_connections)
		(net 197)
	)
	(segment
		(start 151.57 183.5)
		(end 151.57 179.700331)
		(width 0.1)
		(layer "In4.Cu")
		(net 197)
	)
	(segment
		(start 232.740331 178.505)
		(end 209.945 178.505)
		(width 0.1)
		(layer "In4.Cu")
		(net 197)
	)
	(segment
		(start 237.655499 188.38)
		(end 235.399499 186.124)
		(width 0.1)
		(layer "In4.Cu")
		(net 197)
	)
	(segment
		(start 258.275 146.125)
		(end 260.874499 148.724499)
		(width 0.1)
		(layer "In4.Cu")
		(net 197)
	)
	(segment
		(start 143.909669 172.04)
		(end 134.86 172.04)
		(width 0.1)
		(layer "In4.Cu")
		(net 197)
	)
	(segment
		(start 234.4 183.224501)
		(end 234.4 180.164669)
		(width 0.1)
		(layer "In4.Cu")
		(net 197)
	)
	(segment
		(start 235.399499 184.224)
		(end 234.4 183.224501)
		(width 0.1)
		(layer "In4.Cu")
		(net 197)
	)
	(segment
		(start 134.86 172.04)
		(end 134.094834 171.274834)
		(width 0.1)
		(layer "In4.Cu")
		(net 197)
	)
	(segment
		(start 151.57 179.700331)
		(end 143.909669 172.04)
		(width 0.1)
		(layer "In4.Cu")
		(net 197)
	)
	(segment
		(start 203.74 184.71)
		(end 152.78 184.71)
		(width 0.1)
		(layer "In4.Cu")
		(net 197)
	)
	(segment
		(start 247.991165 146.125)
		(end 258.275 146.125)
		(width 0.1)
		(layer "In4.Cu")
		(net 197)
	)
	(segment
		(start 209.945 178.505)
		(end 203.74 184.71)
		(width 0.1)
		(layer "In4.Cu")
		(net 197)
	)
	(segment
		(start 253.093499 188.38)
		(end 237.655499 188.38)
		(width 0.1)
		(layer "In4.Cu")
		(net 197)
	)
	(segment
		(start 152.78 184.71)
		(end 151.57 183.5)
		(width 0.1)
		(layer "In4.Cu")
		(net 197)
	)
	(segment
		(start 260.874499 148.724499)
		(end 260.874499 180.599)
		(width 0.1)
		(layer "In4.Cu")
		(net 197)
	)
	(segment
		(start 234.4 180.164669)
		(end 232.740331 178.505)
		(width 0.1)
		(layer "In4.Cu")
		(net 197)
	)
	(segment
		(start 260.874499 180.599)
		(end 253.093499 188.38)
		(width 0.1)
		(layer "In4.Cu")
		(net 197)
	)
	(segment
		(start 235.399499 186.124)
		(end 235.399499 184.224)
		(width 0.1)
		(layer "In4.Cu")
		(net 197)
	)
	(segment
		(start 240 145.1)
		(end 246.966165 145.1)
		(width 0.1)
		(layer "In4.Cu")
		(net 197)
	)
	(segment
		(start 246.966165 145.1)
		(end 247.991165 146.125)
		(width 0.1)
		(layer "In4.Cu")
		(net 197)
	)
	(segment
		(start 181.95 110.598)
		(end 181.95 111.75)
		(width 0.38)
		(layer "F.Cu")
		(net 198)
	)
	(segment
		(start 191.0005 140.9995)
		(end 191.500001 140.5)
		(width 0.256)
		(layer "F.Cu")
		(net 198)
	)
	(via
		(at 191.500001 140.5)
		(size 0.45)
		(drill 0.1)
		(layers "F.Cu" "B.Cu")
		(remove_unused_layers yes)
		(keep_end_layers yes)
		(zone_layer_connections)
		(net 198)
	)
	(via
		(at 181.95 111.75)
		(size 0.45)
		(drill 0.1)
		(layers "F.Cu" "B.Cu")
		(remove_unused_layers yes)
		(keep_end_layers yes)
		(zone_layer_connections)
		(net 198)
	)
	(segment
		(start 173 120)
		(end 173.175 120.175)
		(width 0.1)
		(layer "In9.Cu")
		(net 198)
	)
	(segment
		(start 177.5 119.25)
		(end 177.15 118.9)
		(width 0.1)
		(layer "In9.Cu")
		(net 198)
	)
	(segment
		(start 174.624569 119.998224)
		(end 174.023527 120.599263)
		(width 0.1)
		(layer "In9.Cu")
		(net 198)
	)
	(segment
		(start 173.67751 120.096751)
		(end 173.677509 120.096752)
		(width 0.1)
		(layer "In9.Cu")
		(net 198)
	)
	(segment
		(start 175.457626 121.439428)
		(end 175.457625 121.439429)
		(width 0.1)
		(layer "In9.Cu")
		(net 198)
	)
	(segment
		(start 175.139428 121.439428)
		(end 175.019238 121.559619)
		(width 0.1)
		(layer "In9.Cu")
		(net 198)
	)
	(segment
		(start 174.559619 121.099999)
		(end 174.55962 121.100001)
		(width 0.1)
		(layer "In9.Cu")
		(net 198)
	)
	(segment
		(start 174.023528 121.023528)
		(end 174.1 121.1)
		(width 0.1)
		(layer "In9.Cu")
		(net 198)
	)
	(segment
		(start 173.924999 119.637132)
		(end 173.924998 119.637132)
		(width 0.1)
		(layer "In9.Cu")
		(net 198)
	)
	(segment
		(start 189.85 130.3)
		(end 191 131.45)
		(width 0.1)
		(layer "In9.Cu")
		(net 198)
	)
	(segment
		(start 177.15 118.9)
		(end 173.45 118.9)
		(width 0.1)
		(layer "In9.Cu")
		(net 198)
	)
	(segment
		(start 181.95 111.75)
		(end 181.95 117.2)
		(width 0.1)
		(layer "In9.Cu")
		(net 198)
	)
	(segment
		(start 173 119.35)
		(end 173 120)
		(width 0.1)
		(layer "In9.Cu")
		(net 198)
	)
	(segment
		(start 175.746966 119.629809)
		(end 175.746965 119.629809)
		(width 0.1)
		(layer "In9.Cu")
		(net 198)
	)
	(segment
		(start 176.261394 123.261395)
		(end 176.261395 123.261396)
		(width 0.1)
		(layer "In9.Cu")
		(net 198)
	)
	(segment
		(start 175.943198 122.624998)
		(end 175.943199 122.625)
		(width 0.1)
		(layer "In9.Cu")
		(net 198)
	)
	(segment
		(start 180.65 130.3)
		(end 189.85 130.3)
		(width 0.1)
		(layer "In9.Cu")
		(net 198)
	)
	(segment
		(start 176.41222 120.166636)
		(end 176.412219 120.166634)
		(width 0.1)
		(layer "In9.Cu")
		(net 198)
	)
	(segment
		(start 175.358057 119.735875)
		(end 175.464123 119.629809)
		(width 0.1)
		(layer "In9.Cu")
		(net 198)
	)
	(segment
		(start 175.775824 120.803032)
		(end 175.775823 120.80303)
		(width 0.1)
		(layer "In9.Cu")
		(net 198)
	)
	(segment
		(start 175.019238 122.019239)
		(end 175.625 122.625)
		(width 0.1)
		(layer "In9.Cu")
		(net 198)
	)
	(segment
		(start 174.023527 121.023527)
		(end 174.023528 121.023528)
		(width 0.1)
		(layer "In9.Cu")
		(net 198)
	)
	(segment
		(start 178.1 125.1)
		(end 178.1 127.75)
		(width 0.1)
		(layer "In9.Cu")
		(net 198)
	)
	(segment
		(start 176.539518 119.57972)
		(end 176.539518 119.579721)
		(width 0.1)
		(layer "In9.Cu")
		(net 198)
	)
	(segment
		(start 175.943199 122.625)
		(end 176.09536 122.472836)
		(width 0.1)
		(layer "In9.Cu")
		(net 198)
	)
	(segment
		(start 179.9 119.25)
		(end 177.5 119.25)
		(width 0.1)
		(layer "In9.Cu")
		(net 198)
	)
	(segment
		(start 176.029809 119.629809)
		(end 176.079898 119.57972)
		(width 0.1)
		(layer "In9.Cu")
		(net 198)
	)
	(segment
		(start 176.539517 120.03934)
		(end 176.41222 120.166636)
		(width 0.1)
		(layer "In9.Cu")
		(net 198)
	)
	(segment
		(start 175.775823 121.121228)
		(end 176.164732 121.510137)
		(width 0.1)
		(layer "In9.Cu")
		(net 198)
	)
	(segment
		(start 173.599265 120.174999)
		(end 173.67751 120.096751)
		(width 0.1)
		(layer "In9.Cu")
		(net 198)
	)
	(segment
		(start 173.67751 119.672487)
		(end 173.712866 119.637132)
		(width 0.1)
		(layer "In9.Cu")
		(net 198)
	)
	(segment
		(start 173.45 118.9)
		(end 173 119.35)
		(width 0.1)
		(layer "In9.Cu")
		(net 198)
	)
	(segment
		(start 175.846534 121.828336)
		(end 175.457626 121.439428)
		(width 0.1)
		(layer "In9.Cu")
		(net 198)
	)
	(segment
		(start 176.413558 122.791034)
		(end 176.261394 122.943197)
		(width 0.1)
		(layer "In9.Cu")
		(net 198)
	)
	(segment
		(start 181.95 117.2)
		(end 179.9 119.25)
		(width 0.1)
		(layer "In9.Cu")
		(net 198)
	)
	(segment
		(start 191.500001 140.200001)
		(end 191.500001 140.5)
		(width 0.1)
		(layer "In9.Cu")
		(net 198)
	)
	(segment
		(start 175.464123 119.629809)
		(end 175.464123 119.629808)
		(width 0.1)
		(layer "In9.Cu")
		(net 198)
	)
	(segment
		(start 174.55962 121.100001)
		(end 175.358056 120.30156)
		(width 0.1)
		(layer "In9.Cu")
		(net 198)
	)
	(segment
		(start 178.1 127.75)
		(end 180.65 130.3)
		(width 0.1)
		(layer "In9.Cu")
		(net 198)
	)
	(segment
		(start 176.164732 121.510137)
		(end 176.164733 121.510137)
		(width 0.1)
		(layer "In9.Cu")
		(net 198)
	)
	(segment
		(start 176.48293 121.19194)
		(end 176.094022 120.803032)
		(width 0.1)
		(layer "In9.Cu")
		(net 198)
	)
	(segment
		(start 176.412219 120.484832)
		(end 176.801128 120.873741)
		(width 0.1)
		(layer "In9.Cu")
		(net 198)
	)
	(segment
		(start 191 139.7)
		(end 191.500001 140.200001)
		(width 0.1)
		(layer "In9.Cu")
		(net 198)
	)
	(segment
		(start 176.261395 123.261396)
		(end 178.1 125.1)
		(width 0.1)
		(layer "In9.Cu")
		(net 198)
	)
	(segment
		(start 176.094022 120.803032)
		(end 176.094021 120.803033)
		(width 0.1)
		(layer "In9.Cu")
		(net 198)
	)
	(segment
		(start 174.137132 119.637132)
		(end 174.200305 119.57396)
		(width 0.1)
		(layer "In9.Cu")
		(net 198)
	)
	(segment
		(start 191 131.45)
		(end 191 139.7)
		(width 0.1)
		(layer "In9.Cu")
		(net 198)
	)
	(segment
		(start 176.801128 120.873741)
		(end 176.801129 120.873741)
		(width 0.1)
		(layer "In9.Cu")
		(net 198)
	)
	(segment
		(start 174.624568 119.998225)
		(end 174.624569 119.998224)
		(width 0.1)
		(layer "In9.Cu")
		(net 198)
	)
	(segment
		(start 173.712866 119.637132)
		(end 173.712866 119.637131)
		(width 0.1)
		(layer "In9.Cu")
		(net 198)
	)
	(arc
		(start 174.200305 119.57396)
		(mid 174.412437 119.486092)
		(end 174.624569 119.57396)
		(width 0.1)
		(layer "In9.Cu")
		(net 198)
	)
	(arc
		(start 175.775823 120.80303)
		(mid 175.709922 120.962129)
		(end 175.775823 121.121228)
		(width 0.1)
		(layer "In9.Cu")
		(net 198)
	)
	(arc
		(start 175.358057 120.018717)
		(mid 175.299479 119.877296)
		(end 175.358057 119.735875)
		(width 0.1)
		(layer "In9.Cu")
		(net 198)
	)
	(arc
		(start 176.539518 119.579721)
		(mid 176.634708 119.809531)
		(end 176.539517 120.03934)
		(width 0.1)
		(layer "In9.Cu")
		(net 198)
	)
	(arc
		(start 176.261394 122.943197)
		(mid 176.195493 123.102296)
		(end 176.261394 123.261395)
		(width 0.1)
		(layer "In9.Cu")
		(net 198)
	)
	(arc
		(start 175.457625 121.439429)
		(mid 175.298527 121.373528)
		(end 175.139428 121.439428)
		(width 0.1)
		(layer "In9.Cu")
		(net 198)
	)
	(arc
		(start 176.801129 120.873741)
		(mid 176.86703 121.032841)
		(end 176.801128 121.19194)
		(width 0.1)
		(layer "In9.Cu")
		(net 198)
	)
	(arc
		(start 173.924998 119.637132)
		(mid 174.031065 119.681066)
		(end 174.137132 119.637132)
		(width 0.1)
		(layer "In9.Cu")
		(net 198)
	)
	(arc
		(start 175.019238 121.559619)
		(mid 174.924048 121.789429)
		(end 175.019238 122.019239)
		(width 0.1)
		(layer "In9.Cu")
		(net 198)
	)
	(arc
		(start 173.677509 120.096752)
		(mid 173.721444 119.990686)
		(end 173.67751 119.884619)
		(width 0.1)
		(layer "In9.Cu")
		(net 198)
	)
	(arc
		(start 175.625 122.625)
		(mid 175.784098 122.690901)
		(end 175.943198 122.624998)
		(width 0.1)
		(layer "In9.Cu")
		(net 198)
	)
	(arc
		(start 176.801128 121.19194)
		(mid 176.642029 121.257841)
		(end 176.48293 121.19194)
		(width 0.1)
		(layer "In9.Cu")
		(net 198)
	)
	(arc
		(start 176.079898 119.57972)
		(mid 176.309708 119.48453)
		(end 176.539518 119.57972)
		(width 0.1)
		(layer "In9.Cu")
		(net 198)
	)
	(arc
		(start 176.09536 122.472836)
		(mid 176.254459 122.406935)
		(end 176.413558 122.472836)
		(width 0.1)
		(layer "In9.Cu")
		(net 198)
	)
	(arc
		(start 173.67751 119.884619)
		(mid 173.633576 119.778553)
		(end 173.67751 119.672487)
		(width 0.1)
		(layer "In9.Cu")
		(net 198)
	)
	(arc
		(start 176.094021 120.803033)
		(mid 175.934923 120.737132)
		(end 175.775824 120.803032)
		(width 0.1)
		(layer "In9.Cu")
		(net 198)
	)
	(arc
		(start 175.358056 120.30156)
		(mid 175.416635 120.160139)
		(end 175.358057 120.018717)
		(width 0.1)
		(layer "In9.Cu")
		(net 198)
	)
	(arc
		(start 174.023527 120.599263)
		(mid 173.935659 120.811395)
		(end 174.023527 121.023527)
		(width 0.1)
		(layer "In9.Cu")
		(net 198)
	)
	(arc
		(start 176.412219 120.166634)
		(mid 176.346318 120.325733)
		(end 176.412219 120.484832)
		(width 0.1)
		(layer "In9.Cu")
		(net 198)
	)
	(arc
		(start 176.164733 121.510137)
		(mid 176.230634 121.669237)
		(end 176.164732 121.828336)
		(width 0.1)
		(layer "In9.Cu")
		(net 198)
	)
	(arc
		(start 174.1 121.1)
		(mid 174.32981 121.19519)
		(end 174.559619 121.099999)
		(width 0.1)
		(layer "In9.Cu")
		(net 198)
	)
	(arc
		(start 176.413558 122.472836)
		(mid 176.479459 122.631935)
		(end 176.413558 122.791034)
		(width 0.1)
		(layer "In9.Cu")
		(net 198)
	)
	(arc
		(start 174.624569 119.57396)
		(mid 174.712436 119.786092)
		(end 174.624568 119.998225)
		(width 0.1)
		(layer "In9.Cu")
		(net 198)
	)
	(arc
		(start 173.712866 119.637131)
		(mid 173.818933 119.593197)
		(end 173.924999 119.637132)
		(width 0.1)
		(layer "In9.Cu")
		(net 198)
	)
	(arc
		(start 175.746965 119.629809)
		(mid 175.888387 119.688388)
		(end 176.029809 119.629809)
		(width 0.1)
		(layer "In9.Cu")
		(net 198)
	)
	(arc
		(start 173.175 120.175)
		(mid 173.387134 120.262869)
		(end 173.599265 120.174999)
		(width 0.1)
		(layer "In9.Cu")
		(net 198)
	)
	(arc
		(start 176.164732 121.828336)
		(mid 176.005633 121.894237)
		(end 175.846534 121.828336)
		(width 0.1)
		(layer "In9.Cu")
		(net 198)
	)
	(arc
		(start 175.464123 119.629808)
		(mid 175.605545 119.57123)
		(end 175.746966 119.629809)
		(width 0.1)
		(layer "In9.Cu")
		(net 198)
	)
	(segment
		(start 189.0005 139.9995)
		(end 189.5 139.5)
		(width 0.256)
		(layer "F.Cu")
		(net 199)
	)
	(segment
		(start 180.25 110.598)
		(end 180.25 111.75)
		(width 0.38)
		(layer "F.Cu")
		(net 199)
	)
	(via
		(at 189.5 139.5)
		(size 0.45)
		(drill 0.1)
		(layers "F.Cu" "B.Cu")
		(remove_unused_layers yes)
		(keep_end_layers yes)
		(zone_layer_connections)
		(net 199)
	)
	(via
		(at 180.25 111.75)
		(size 0.45)
		(drill 0.1)
		(layers "F.Cu" "B.Cu")
		(remove_unused_layers yes)
		(keep_end_layers yes)
		(zone_layer_connections)
		(net 199)
	)
	(segment
		(start 188.45 132.35)
		(end 189.7 133.6)
		(width 0.1)
		(layer "In9.Cu")
		(net 199)
	)
	(segment
		(start 179.014212 116.289338)
		(end 179.579898 116.855024)
		(width 0.1)
		(layer "In9.Cu")
		(net 199)
	)
	(segment
		(start 189.7 138.6)
		(end 189.5 138.8)
		(width 0.1)
		(layer "In9.Cu")
		(net 199)
	)
	(segment
		(start 177.6 117.35)
		(end 177.5 117.45)
		(width 0.1)
		(layer "In9.Cu")
		(net 199)
	)
	(segment
		(start 178.307107 116.642893)
		(end 178.307105 116.642892)
		(width 0.1)
		(layer "In9.Cu")
		(net 199)
	)
	(segment
		(start 179.45 132.35)
		(end 188.45 132.35)
		(width 0.1)
		(layer "In9.Cu")
		(net 199)
	)
	(segment
		(start 177.953553 117.35)
		(end 177.953552 117.35)
		(width 0.1)
		(layer "In9.Cu")
		(net 199)
	)
	(segment
		(start 179.014214 115.935786)
		(end 179.014212 115.935785)
		(width 0.1)
		(layer "In9.Cu")
		(net 199)
	)
	(segment
		(start 179.226345 117.208578)
		(end 178.66066 116.642893)
		(width 0.1)
		(layer "In9.Cu")
		(net 199)
	)
	(segment
		(start 176.732843 131.549999)
		(end 176.732842 131.55)
		(width 0.1)
		(layer "In9.Cu")
		(net 199)
	)
	(segment
		(start 176.35 131.45)
		(end 176.45 131.55)
		(width 0.1)
		(layer "In9.Cu")
		(net 199)
	)
	(segment
		(start 179.367767 115.935786)
		(end 179.367766 115.935786)
		(width 0.1)
		(layer "In9.Cu")
		(net 199)
	)
	(segment
		(start 179.579898 117.208578)
		(end 179.579899 117.208578)
		(width 0.1)
		(layer "In9.Cu")
		(net 199)
	)
	(segment
		(start 177.05104 132.151041)
		(end 177.086396 132.186396)
		(width 0.1)
		(layer "In9.Cu")
		(net 199)
	)
	(segment
		(start 177.525 132.075)
		(end 177.525 131.725)
		(width 0.1)
		(layer "In9.Cu")
		(net 199)
	)
	(segment
		(start 176.35 131.35)
		(end 176.35 131.45)
		(width 0.1)
		(layer "In9.Cu")
		(net 199)
	)
	(segment
		(start 176.975 131.075)
		(end 176.625 131.075)
		(width 0.1)
		(layer "In9.Cu")
		(net 199)
	)
	(segment
		(start 180.478578 115.663882)
		(end 180.264518 115.877943)
		(width 0.1)
		(layer "In9.Cu")
		(net 199)
	)
	(segment
		(start 177.5 117.45)
		(end 172.65 117.45)
		(width 0.1)
		(layer "In9.Cu")
		(net 199)
	)
	(segment
		(start 178.66066 116.642893)
		(end 178.660659 116.642893)
		(width 0.1)
		(layer "In9.Cu")
		(net 199)
	)
	(segment
		(start 180.478579 115.416395)
		(end 180.478579 115.416396)
		(width 0.1)
		(layer "In9.Cu")
		(net 199)
	)
	(segment
		(start 179.175 131.725)
		(end 179.175 132.075)
		(width 0.1)
		(layer "In9.Cu")
		(net 199)
	)
	(segment
		(start 179.933452 116.501471)
		(end 179.367767 115.935786)
		(width 0.1)
		(layer "In9.Cu")
		(net 199)
	)
	(segment
		(start 180.478578 115.663883)
		(end 180.478578 115.663882)
		(width 0.1)
		(layer "In9.Cu")
		(net 199)
	)
	(segment
		(start 180.264517 116.125429)
		(end 180.287005 116.147917)
		(width 0.1)
		(layer "In9.Cu")
		(net 199)
	)
	(segment
		(start 176.625 130.525)
		(end 176.975 130.525)
		(width 0.1)
		(layer "In9.Cu")
		(net 199)
	)
	(segment
		(start 180.287005 116.501471)
		(end 180.287006 116.501471)
		(width 0.1)
		(layer "In9.Cu")
		(net 199)
	)
	(segment
		(start 189.5 138.8)
		(end 189.5 139.5)
		(width 0.1)
		(layer "In9.Cu")
		(net 199)
	)
	(segment
		(start 171.45 118.65)
		(end 171.45 120.7)
		(width 0.1)
		(layer "In9.Cu")
		(net 199)
	)
	(segment
		(start 179.721319 115.582231)
		(end 179.769544 115.630456)
		(width 0.1)
		(layer "In9.Cu")
		(net 199)
	)
	(segment
		(start 178.625 132.075)
		(end 178.625 131.725)
		(width 0.1)
		(layer "In9.Cu")
		(net 199)
	)
	(segment
		(start 180.25 111.75)
		(end 180.25 114.7)
		(width 0.1)
		(layer "In9.Cu")
		(net 199)
	)
	(segment
		(start 178.307105 116.642892)
		(end 178.307105 116.642891)
		(width 0.1)
		(layer "In9.Cu")
		(net 199)
	)
	(segment
		(start 176.625 129.425)
		(end 176.975 129.425)
		(width 0.1)
		(layer "In9.Cu")
		(net 199)
	)
	(segment
		(start 177.086396 132.186396)
		(end 177.25 132.35)
		(width 0.1)
		(layer "In9.Cu")
		(net 199)
	)
	(segment
		(start 180.017032 115.630457)
		(end 180.231091 115.416395)
		(width 0.1)
		(layer "In9.Cu")
		(net 199)
	)
	(segment
		(start 189.7 133.6)
		(end 189.7 138.6)
		(width 0.1)
		(layer "In9.Cu")
		(net 199)
	)
	(segment
		(start 177.015684 131.55)
		(end 177.051039 131.585355)
		(width 0.1)
		(layer "In9.Cu")
		(net 199)
	)
	(segment
		(start 176.35 125.6)
		(end 176.35 129.15)
		(width 0.1)
		(layer "In9.Cu")
		(net 199)
	)
	(segment
		(start 178.075 131.725)
		(end 178.075 132.075)
		(width 0.1)
		(layer "In9.Cu")
		(net 199)
	)
	(segment
		(start 178.519238 117.915685)
		(end 177.953553 117.35)
		(width 0.1)
		(layer "In9.Cu")
		(net 199)
	)
	(segment
		(start 171.45 120.7)
		(end 176.35 125.6)
		(width 0.1)
		(layer "In9.Cu")
		(net 199)
	)
	(segment
		(start 180.264518 116.125431)
		(end 180.264517 116.125429)
		(width 0.1)
		(layer "In9.Cu")
		(net 199)
	)
	(segment
		(start 178.307105 116.996445)
		(end 178.872791 117.562131)
		(width 0.1)
		(layer "In9.Cu")
		(net 199)
	)
	(segment
		(start 172.65 117.45)
		(end 171.45 118.65)
		(width 0.1)
		(layer "In9.Cu")
		(net 199)
	)
	(segment
		(start 176.975 129.975)
		(end 176.625 129.975)
		(width 0.1)
		(layer "In9.Cu")
		(net 199)
	)
	(segment
		(start 179.014212 115.935785)
		(end 179.014212 115.935784)
		(width 0.1)
		(layer "In9.Cu")
		(net 199)
	)
	(segment
		(start 180.25 114.7)
		(end 179.721319 115.228677)
		(width 0.1)
		(layer "In9.Cu")
		(net 199)
	)
	(segment
		(start 178.872791 117.915685)
		(end 178.872792 117.915685)
		(width 0.1)
		(layer "In9.Cu")
		(net 199)
	)
	(segment
		(start 177.051038 131.868198)
		(end 177.05104 131.868199)
		(width 0.1)
		(layer "In9.Cu")
		(net 199)
	)
	(segment
		(start 180.017031 115.630455)
		(end 180.017032 115.630457)
		(width 0.1)
		(layer "In9.Cu")
		(net 199)
	)
	(arc
		(start 179.014212 115.935784)
		(mid 178.940989 116.112561)
		(end 179.014212 116.289338)
		(width 0.1)
		(layer "In9.Cu")
		(net 199)
	)
	(arc
		(start 176.625 129.975)
		(mid 176.430546 130.055546)
		(end 176.35 130.25)
		(width 0.1)
		(layer "In9.Cu")
		(net 199)
	)
	(arc
		(start 178.9 131.45)
		(mid 179.094454 131.530546)
		(end 179.175 131.725)
		(width 0.1)
		(layer "In9.Cu")
		(net 199)
	)
	(arc
		(start 177.051039 131.585355)
		(mid 177.109617 131.726777)
		(end 177.051038 131.868198)
		(width 0.1)
		(layer "In9.Cu")
		(net 199)
	)
	(arc
		(start 176.35 130.25)
		(mid 176.430546 130.444454)
		(end 176.625 130.525)
		(width 0.1)
		(layer "In9.Cu")
		(net 199)
	)
	(arc
		(start 176.35 129.15)
		(mid 176.430546 129.344454)
		(end 176.625 129.425)
		(width 0.1)
		(layer "In9.Cu")
		(net 199)
	)
	(arc
		(start 178.872791 117.562131)
		(mid 178.946014 117.738908)
		(end 178.872791 117.915685)
		(width 0.1)
		(layer "In9.Cu")
		(net 199)
	)
	(arc
		(start 179.175 132.075)
		(mid 179.255546 132.269454)
		(end 179.45 132.35)
		(width 0.1)
		(layer "In9.Cu")
		(net 199)
	)
	(arc
		(start 179.721319 115.228677)
		(mid 179.648096 115.405454)
		(end 179.721319 115.582231)
		(width 0.1)
		(layer "In9.Cu")
		(net 199)
	)
	(arc
		(start 179.579898 116.855024)
		(mid 179.653121 117.031801)
		(end 179.579898 117.208578)
		(width 0.1)
		(layer "In9.Cu")
		(net 199)
	)
	(arc
		(start 177.25 130.8)
		(mid 177.169454 130.994454)
		(end 176.975 131.075)
		(width 0.1)
		(layer "In9.Cu")
		(net 199)
	)
	(arc
		(start 180.264518 115.877943)
		(mid 180.213262 116.001687)
		(end 180.264518 116.125431)
		(width 0.1)
		(layer "In9.Cu")
		(net 199)
	)
	(arc
		(start 176.45 131.55)
		(mid 176.591422 131.608578)
		(end 176.732843 131.549999)
		(width 0.1)
		(layer "In9.Cu")
		(net 199)
	)
	(arc
		(start 179.367766 115.935786)
		(mid 179.19099 115.862563)
		(end 179.014214 115.935786)
		(width 0.1)
		(layer "In9.Cu")
		(net 199)
	)
	(arc
		(start 179.579899 117.208578)
		(mid 179.403122 117.281801)
		(end 179.226345 117.208578)
		(width 0.1)
		(layer "In9.Cu")
		(net 199)
	)
	(arc
		(start 177.8 131.45)
		(mid 177.994454 131.530546)
		(end 178.075 131.725)
		(width 0.1)
		(layer "In9.Cu")
		(net 199)
	)
	(arc
		(start 177.25 132.35)
		(mid 177.444454 132.269454)
		(end 177.525 132.075)
		(width 0.1)
		(layer "In9.Cu")
		(net 199)
	)
	(arc
		(start 178.35 132.35)
		(mid 178.544454 132.269454)
		(end 178.625 132.075)
		(width 0.1)
		(layer "In9.Cu")
		(net 199)
	)
	(arc
		(start 177.25 129.7)
		(mid 177.169454 129.894454)
		(end 176.975 129.975)
		(width 0.1)
		(layer "In9.Cu")
		(net 199)
	)
	(arc
		(start 180.287005 116.147917)
		(mid 180.360228 116.324694)
		(end 180.287005 116.501471)
		(width 0.1)
		(layer "In9.Cu")
		(net 199)
	)
	(arc
		(start 179.769544 115.630456)
		(mid 179.893288 115.681712)
		(end 180.017031 115.630455)
		(width 0.1)
		(layer "In9.Cu")
		(net 199)
	)
	(arc
		(start 177.525 131.725)
		(mid 177.605546 131.530546)
		(end 177.8 131.45)
		(width 0.1)
		(layer "In9.Cu")
		(net 199)
	)
	(arc
		(start 176.625 131.075)
		(mid 176.430546 131.155546)
		(end 176.35 131.35)
		(width 0.1)
		(layer "In9.Cu")
		(net 199)
	)
	(arc
		(start 177.953552 117.35)
		(mid 177.776776 117.276777)
		(end 177.6 117.35)
		(width 0.1)
		(layer "In9.Cu")
		(net 199)
	)
	(arc
		(start 177.05104 131.868199)
		(mid 176.992461 132.009619)
		(end 177.05104 132.151041)
		(width 0.1)
		(layer "In9.Cu")
		(net 199)
	)
	(arc
		(start 180.287006 116.501471)
		(mid 180.110229 116.574694)
		(end 179.933452 116.501471)
		(width 0.1)
		(layer "In9.Cu")
		(net 199)
	)
	(arc
		(start 176.975 130.525)
		(mid 177.169454 130.605546)
		(end 177.25 130.8)
		(width 0.1)
		(layer "In9.Cu")
		(net 199)
	)
	(arc
		(start 178.625 131.725)
		(mid 178.705546 131.530546)
		(end 178.9 131.45)
		(width 0.1)
		(layer "In9.Cu")
		(net 199)
	)
	(arc
		(start 180.231091 115.416395)
		(mid 180.354835 115.365139)
		(end 180.478579 115.416395)
		(width 0.1)
		(layer "In9.Cu")
		(net 199)
	)
	(arc
		(start 176.732842 131.55)
		(mid 176.874264 131.491423)
		(end 177.015684 131.55)
		(width 0.1)
		(layer "In9.Cu")
		(net 199)
	)
	(arc
		(start 178.872792 117.915685)
		(mid 178.696015 117.988908)
		(end 178.519238 117.915685)
		(width 0.1)
		(layer "In9.Cu")
		(net 199)
	)
	(arc
		(start 176.975 129.425)
		(mid 177.169454 129.505546)
		(end 177.25 129.7)
		(width 0.1)
		(layer "In9.Cu")
		(net 199)
	)
	(arc
		(start 178.660659 116.642893)
		(mid 178.483883 116.56967)
		(end 178.307107 116.642893)
		(width 0.1)
		(layer "In9.Cu")
		(net 199)
	)
	(arc
		(start 178.075 132.075)
		(mid 178.155546 132.269454)
		(end 178.35 132.35)
		(width 0.1)
		(layer "In9.Cu")
		(net 199)
	)
	(arc
		(start 180.478579 115.416396)
		(mid 180.529835 115.54014)
		(end 180.478578 115.663883)
		(width 0.1)
		(layer "In9.Cu")
		(net 199)
	)
	(arc
		(start 178.307105 116.642891)
		(mid 178.233882 116.819668)
		(end 178.307105 116.996445)
		(width 0.1)
		(layer "In9.Cu")
		(net 199)
	)
	(segment
		(start 178.55 110.598)
		(end 178.55 111.75)
		(width 0.38)
		(layer "F.Cu")
		(net 200)
	)
	(segment
		(start 189.000501 141.9995)
		(end 189.5 141.5)
		(width 0.256)
		(layer "F.Cu")
		(net 200)
	)
	(via
		(at 178.55 111.75)
		(size 0.45)
		(drill 0.1)
		(layers "F.Cu" "B.Cu")
		(remove_unused_layers yes)
		(keep_end_layers yes)
		(zone_layer_connections)
		(net 200)
	)
	(via
		(at 189.5 141.5)
		(size 0.45)
		(drill 0.1)
		(layers "F.Cu" "B.Cu")
		(remove_unused_layers yes)
		(keep_end_layers yes)
		(zone_layer_connections)
		(net 200)
	)
	(segment
		(start 178.55 114.05)
		(end 176.55 116.05)
		(width 0.1)
		(layer "In9.Cu")
		(net 200)
	)
	(segment
		(start 188.125 135.8)
		(end 188.025 135.8)
		(width 0.1)
		(layer "In9.Cu")
		(net 200)
	)
	(segment
		(start 171.05 116.05)
		(end 169.05 118.05)
		(width 0.1)
		(layer "In9.Cu")
		(net 200)
	)
	(segment
		(start 178.55 111.75)
		(end 178.55 114.05)
		(width 0.1)
		(layer "In9.Cu")
		(net 200)
	)
	(segment
		(start 187.520877 135.433716)
		(end 187.520876 135.433717)
		(width 0.1)
		(layer "In9.Cu")
		(net 200)
	)
	(segment
		(start 184.2 134.225)
		(end 184.2 134.075)
		(width 0.1)
		(layer "In9.Cu")
		(net 200)
	)
	(segment
		(start 176.775 134.475)
		(end 176.95 134.475)
		(width 0.1)
		(layer "In9.Cu")
		(net 200)
	)
	(segment
		(start 181.2 134.225)
		(end 181.2 134.075)
		(width 0.1)
		(layer "In9.Cu")
		(net 200)
	)
	(segment
		(start 186.2 134.225)
		(end 186.2 134.075)
		(width 0.1)
		(layer "In9.Cu")
		(net 200)
	)
	(segment
		(start 177.2 134.225)
		(end 177.2 134.075)
		(width 0.1)
		(layer "In9.Cu")
		(net 200)
	)
	(segment
		(start 188.5 140.5)
		(end 189.5 141.5)
		(width 0.1)
		(layer "In9.Cu")
		(net 200)
	)
	(segment
		(start 180.7 134.075)
		(end 180.7 134.225)
		(width 0.1)
		(layer "In9.Cu")
		(net 200)
	)
	(segment
		(start 169.05 121.05)
		(end 174.4 126.4)
		(width 0.1)
		(layer "In9.Cu")
		(net 200)
	)
	(segment
		(start 186.90075 134.472598)
		(end 187.422598 134.472598)
		(width 0.1)
		(layer "In9.Cu")
		(net 200)
	)
	(segment
		(start 188.5 138.65)
		(end 188.5 140.5)
		(width 0.1)
		(layer "In9.Cu")
		(net 200)
	)
	(segment
		(start 179.2 134.225)
		(end 179.2 134.075)
		(width 0.1)
		(layer "In9.Cu")
		(net 200)
	)
	(segment
		(start 169.05 118.05)
		(end 169.05 121.05)
		(width 0.1)
		(layer "In9.Cu")
		(net 200)
	)
	(segment
		(start 181.7 134.075)
		(end 181.7 134.225)
		(width 0.1)
		(layer "In9.Cu")
		(net 200)
	)
	(segment
		(start 183.2 134.225)
		(end 183.2 134.075)
		(width 0.1)
		(layer "In9.Cu")
		(net 200)
	)
	(segment
		(start 183.7 134.075)
		(end 183.7 134.225)
		(width 0.1)
		(layer "In9.Cu")
		(net 200)
	)
	(segment
		(start 182.2 134.225)
		(end 182.2 134.075)
		(width 0.1)
		(layer "In9.Cu")
		(net 200)
	)
	(segment
		(start 178.7 134.075)
		(end 178.7 134.225)
		(width 0.1)
		(layer "In9.Cu")
		(net 200)
	)
	(segment
		(start 187.474999 134.843199)
		(end 187.475 134.843198)
		(width 0.1)
		(layer "In9.Cu")
		(net 200)
	)
	(segment
		(start 185.7 134.075)
		(end 185.7 134.225)
		(width 0.1)
		(layer "In9.Cu")
		(net 200)
	)
	(segment
		(start 188.025 136.3)
		(end 188.125 136.3)
		(width 0.1)
		(layer "In9.Cu")
		(net 200)
	)
	(segment
		(start 179.7 134.075)
		(end 179.7 134.225)
		(width 0.1)
		(layer "In9.Cu")
		(net 200)
	)
	(segment
		(start 184.7 134.075)
		(end 184.7 134.225)
		(width 0.1)
		(layer "In9.Cu")
		(net 200)
	)
	(segment
		(start 177.7 134.075)
		(end 177.7 134.225)
		(width 0.1)
		(layer "In9.Cu")
		(net 200)
	)
	(segment
		(start 187.422598 134.472598)
		(end 187.475 134.525)
		(width 0.1)
		(layer "In9.Cu")
		(net 200)
	)
	(segment
		(start 188.375 135.425)
		(end 188.375 135.55)
		(width 0.1)
		(layer "In9.Cu")
		(net 200)
	)
	(segment
		(start 180.2 134.225)
		(end 180.2 134.075)
		(width 0.1)
		(layer "In9.Cu")
		(net 200)
	)
	(segment
		(start 178.2 134.225)
		(end 178.2 134.075)
		(width 0.1)
		(layer "In9.Cu")
		(net 200)
	)
	(segment
		(start 186.7 134.075)
		(end 186.7 134.225)
		(width 0.1)
		(layer "In9.Cu")
		(net 200)
	)
	(segment
		(start 174.4 132.1)
		(end 176.775 134.475)
		(width 0.1)
		(layer "In9.Cu")
		(net 200)
	)
	(segment
		(start 188.375 136.55)
		(end 188.375 138.525)
		(width 0.1)
		(layer "In9.Cu")
		(net 200)
	)
	(segment
		(start 187.520876 135.433717)
		(end 187.793197 135.161395)
		(width 0.1)
		(layer "In9.Cu")
		(net 200)
	)
	(segment
		(start 176.55 116.05)
		(end 171.05 116.05)
		(width 0.1)
		(layer "In9.Cu")
		(net 200)
	)
	(segment
		(start 188.111396 135.161396)
		(end 188.375 135.425)
		(width 0.1)
		(layer "In9.Cu")
		(net 200)
	)
	(segment
		(start 188.375 138.525)
		(end 188.5 138.65)
		(width 0.1)
		(layer "In9.Cu")
		(net 200)
	)
	(segment
		(start 187.475 134.843198)
		(end 187.202678 135.115519)
		(width 0.1)
		(layer "In9.Cu")
		(net 200)
	)
	(segment
		(start 182.7 134.075)
		(end 182.7 134.225)
		(width 0.1)
		(layer "In9.Cu")
		(net 200)
	)
	(segment
		(start 174.4 126.4)
		(end 174.4 132.1)
		(width 0.1)
		(layer "In9.Cu")
		(net 200)
	)
	(segment
		(start 185.2 134.225)
		(end 185.2 134.075)
		(width 0.1)
		(layer "In9.Cu")
		(net 200)
	)
	(segment
		(start 188.111395 135.161395)
		(end 188.111396 135.161396)
		(width 0.1)
		(layer "In9.Cu")
		(net 200)
	)
	(arc
		(start 180.7 134.225)
		(mid 180.773223 134.401777)
		(end 180.95 134.475)
		(width 0.1)
		(layer "In9.Cu")
		(net 200)
	)
	(arc
		(start 177.45 133.825)
		(mid 177.626777 133.898223)
		(end 177.7 134.075)
		(width 0.1)
		(layer "In9.Cu")
		(net 200)
	)
	(arc
		(start 185.45 133.825)
		(mid 185.626777 133.898223)
		(end 185.7 134.075)
		(width 0.1)
		(layer "In9.Cu")
		(net 200)
	)
	(arc
		(start 182.7 134.225)
		(mid 182.773223 134.401777)
		(end 182.95 134.475)
		(width 0.1)
		(layer "In9.Cu")
		(net 200)
	)
	(arc
		(start 178.2 134.075)
		(mid 178.273223 133.898223)
		(end 178.45 133.825)
		(width 0.1)
		(layer "In9.Cu")
		(net 200)
	)
	(arc
		(start 178.95 134.475)
		(mid 179.126777 134.401777)
		(end 179.2 134.225)
		(width 0.1)
		(layer "In9.Cu")
		(net 200)
	)
	(arc
		(start 186.2 134.075)
		(mid 186.273223 133.898223)
		(end 186.45 133.825)
		(width 0.1)
		(layer "In9.Cu")
		(net 200)
	)
	(arc
		(start 188.125 136.3)
		(mid 188.301777 136.373223)
		(end 188.375 136.55)
		(width 0.1)
		(layer "In9.Cu")
		(net 200)
	)
	(arc
		(start 179.7 134.225)
		(mid 179.773223 134.401777)
		(end 179.95 134.475)
		(width 0.1)
		(layer "In9.Cu")
		(net 200)
	)
	(arc
		(start 183.95 134.475)
		(mid 184.126777 134.401777)
		(end 184.2 134.225)
		(width 0.1)
		(layer "In9.Cu")
		(net 200)
	)
	(arc
		(start 176.95 134.475)
		(mid 177.126777 134.401777)
		(end 177.2 134.225)
		(width 0.1)
		(layer "In9.Cu")
		(net 200)
	)
	(arc
		(start 183.7 134.225)
		(mid 183.773223 134.401777)
		(end 183.95 134.475)
		(width 0.1)
		(layer "In9.Cu")
		(net 200)
	)
	(arc
		(start 181.2 134.075)
		(mid 181.273223 133.898223)
		(end 181.45 133.825)
		(width 0.1)
		(layer "In9.Cu")
		(net 200)
	)
	(arc
		(start 178.45 133.825)
		(mid 178.626777 133.898223)
		(end 178.7 134.075)
		(width 0.1)
		(layer "In9.Cu")
		(net 200)
	)
	(arc
		(start 187.202678 135.433717)
		(mid 187.361778 135.499618)
		(end 187.520877 135.433716)
		(width 0.1)
		(layer "In9.Cu")
		(net 200)
	)
	(arc
		(start 179.2 134.075)
		(mid 179.273223 133.898223)
		(end 179.45 133.825)
		(width 0.1)
		(layer "In9.Cu")
		(net 200)
	)
	(arc
		(start 187.793197 135.161395)
		(mid 187.952296 135.095494)
		(end 188.111395 135.161395)
		(width 0.1)
		(layer "In9.Cu")
		(net 200)
	)
	(arc
		(start 181.95 134.475)
		(mid 182.126777 134.401777)
		(end 182.2 134.225)
		(width 0.1)
		(layer "In9.Cu")
		(net 200)
	)
	(arc
		(start 181.45 133.825)
		(mid 181.626777 133.898223)
		(end 181.7 134.075)
		(width 0.1)
		(layer "In9.Cu")
		(net 200)
	)
	(arc
		(start 185.95 134.475)
		(mid 186.126777 134.401777)
		(end 186.2 134.225)
		(width 0.1)
		(layer "In9.Cu")
		(net 200)
	)
	(arc
		(start 187.775 136.05)
		(mid 187.848223 136.226777)
		(end 188.025 136.3)
		(width 0.1)
		(layer "In9.Cu")
		(net 200)
	)
	(arc
		(start 178.7 134.225)
		(mid 178.773223 134.401777)
		(end 178.95 134.475)
		(width 0.1)
		(layer "In9.Cu")
		(net 200)
	)
	(arc
		(start 177.2 134.075)
		(mid 177.273223 133.898223)
		(end 177.45 133.825)
		(width 0.1)
		(layer "In9.Cu")
		(net 200)
	)
	(arc
		(start 177.7 134.225)
		(mid 177.773223 134.401777)
		(end 177.95 134.475)
		(width 0.1)
		(layer "In9.Cu")
		(net 200)
	)
	(arc
		(start 186.45 133.825)
		(mid 186.626777 133.898223)
		(end 186.7 134.075)
		(width 0.1)
		(layer "In9.Cu")
		(net 200)
	)
	(arc
		(start 184.2 134.075)
		(mid 184.273223 133.898223)
		(end 184.45 133.825)
		(width 0.1)
		(layer "In9.Cu")
		(net 200)
	)
	(arc
		(start 187.202678 135.115519)
		(mid 187.136777 135.274618)
		(end 187.202678 135.433717)
		(width 0.1)
		(layer "In9.Cu")
		(net 200)
	)
	(arc
		(start 180.2 134.075)
		(mid 180.273223 133.898223)
		(end 180.45 133.825)
		(width 0.1)
		(layer "In9.Cu")
		(net 200)
	)
	(arc
		(start 183.45 133.825)
		(mid 183.626777 133.898223)
		(end 183.7 134.075)
		(width 0.1)
		(layer "In9.Cu")
		(net 200)
	)
	(arc
		(start 188.025 135.8)
		(mid 187.848223 135.873223)
		(end 187.775 136.05)
		(width 0.1)
		(layer "In9.Cu")
		(net 200)
	)
	(arc
		(start 188.375 135.55)
		(mid 188.301777 135.726777)
		(end 188.125 135.8)
		(width 0.1)
		(layer "In9.Cu")
		(net 200)
	)
	(arc
		(start 181.7 134.225)
		(mid 181.773223 134.401777)
		(end 181.95 134.475)
		(width 0.1)
		(layer "In9.Cu")
		(net 200)
	)
	(arc
		(start 179.95 134.475)
		(mid 180.126777 134.401777)
		(end 180.2 134.225)
		(width 0.1)
		(layer "In9.Cu")
		(net 200)
	)
	(arc
		(start 185.2 134.075)
		(mid 185.273223 133.898223)
		(end 185.45 133.825)
		(width 0.1)
		(layer "In9.Cu")
		(net 200)
	)
	(arc
		(start 182.95 134.475)
		(mid 183.126777 134.401777)
		(end 183.2 134.225)
		(width 0.1)
		(layer "In9.Cu")
		(net 200)
	)
	(arc
		(start 184.45 133.825)
		(mid 184.626777 133.898223)
		(end 184.7 134.075)
		(width 0.1)
		(layer "In9.Cu")
		(net 200)
	)
	(arc
		(start 184.95 134.475)
		(mid 185.126777 134.401777)
		(end 185.2 134.225)
		(width 0.1)
		(layer "In9.Cu")
		(net 200)
	)
	(arc
		(start 182.2 134.075)
		(mid 182.273223 133.898223)
		(end 182.45 133.825)
		(width 0.1)
		(layer "In9.Cu")
		(net 200)
	)
	(arc
		(start 187.475 134.525)
		(mid 187.540901 134.6841)
		(end 187.474999 134.843199)
		(width 0.1)
		(layer "In9.Cu")
		(net 200)
	)
	(arc
		(start 180.45 133.825)
		(mid 180.626777 133.898223)
		(end 180.7 134.075)
		(width 0.1)
		(layer "In9.Cu")
		(net 200)
	)
	(arc
		(start 179.45 133.825)
		(mid 179.626777 133.898223)
		(end 179.7 134.075)
		(width 0.1)
		(layer "In9.Cu")
		(net 200)
	)
	(arc
		(start 184.7 134.225)
		(mid 184.773223 134.401777)
		(end 184.95 134.475)
		(width 0.1)
		(layer "In9.Cu")
		(net 200)
	)
	(arc
		(start 186.7 134.225)
		(mid 186.756747 134.383598)
		(end 186.90075 134.472598)
		(width 0.1)
		(layer "In9.Cu")
		(net 200)
	)
	(arc
		(start 177.95 134.475)
		(mid 178.126777 134.401777)
		(end 178.2 134.225)
		(width 0.1)
		(layer "In9.Cu")
		(net 200)
	)
	(arc
		(start 182.45 133.825)
		(mid 182.626777 133.898223)
		(end 182.7 134.075)
		(width 0.1)
		(layer "In9.Cu")
		(net 200)
	)
	(arc
		(start 183.2 134.075)
		(mid 183.273223 133.898223)
		(end 183.45 133.825)
		(width 0.1)
		(layer "In9.Cu")
		(net 200)
	)
	(arc
		(start 185.7 134.225)
		(mid 185.773223 134.401777)
		(end 185.95 134.475)
		(width 0.1)
		(layer "In9.Cu")
		(net 200)
	)
	(arc
		(start 180.95 134.475)
		(mid 181.126777 134.401777)
		(end 181.2 134.225)
		(width 0.1)
		(layer "In9.Cu")
		(net 200)
	)
	(segment
		(start 235.57 132.8)
		(end 237.118499 132.8)
		(width 0.256)
		(layer "F.Cu")
		(net 201)
	)
	(segment
		(start 235.57 132.8)
		(end 234.721347 132.8)
		(width 0.256)
		(layer "F.Cu")
		(net 201)
	)
	(segment
		(start 237.118499 132.8)
		(end 237.126499 132.808)
		(width 0.256)
		(layer "F.Cu")
		(net 201)
	)
	(segment
		(start 234.721347 132.8)
		(end 234.7 132.778653)
		(width 0.256)
		(layer "F.Cu")
		(net 201)
	)
	(via
		(at 234.7 132.778653)
		(size 0.45)
		(drill 0.1)
		(layers "F.Cu" "B.Cu")
		(remove_unused_layers yes)
		(keep_end_layers yes)
		(zone_layer_connections)
		(net 201)
	)
	(segment
		(start 235.121347 132.778653)
		(end 235.579999 132.320001)
		(width 0.198)
		(layer "B.Cu")
		(net 201)
	)
	(segment
		(start 234.05 133.295)
		(end 234.695 133.295)
		(width 0.198)
		(layer "B.Cu")
		(net 201)
	)
	(segment
		(start 234.135 134.35)
		(end 234.06 134.275)
		(width 0.198)
		(layer "B.Cu")
		(net 201)
	)
	(segment
		(start 234.7 133.3)
		(end 234.7 134.35)
		(width 0.198)
		(layer "B.Cu")
		(net 201)
	)
	(segment
		(start 234.7 132.778653)
		(end 234.7 133.3)
		(width 0.198)
		(layer "B.Cu")
		(net 201)
	)
	(segment
		(start 234.7 132.778653)
		(end 235.121347 132.778653)
		(width 0.198)
		(layer "B.Cu")
		(net 201)
	)
	(segment
		(start 234.7 134.35)
		(end 234.135 134.35)
		(width 0.198)
		(layer "B.Cu")
		(net 201)
	)
	(segment
		(start 234.7 134.35)
		(end 235.59 135.24)
		(width 0.198)
		(layer "B.Cu")
		(net 201)
	)
	(segment
		(start 234.695 133.295)
		(end 234.7 133.3)
		(width 0.198)
		(layer "B.Cu")
		(net 201)
	)
	(segment
		(start 190.0005 139.9995)
		(end 190.5 139.5)
		(width 0.256)
		(layer "F.Cu")
		(net 202)
	)
	(segment
		(start 176.85 110.598)
		(end 176.85 111.75)
		(width 0.38)
		(layer "F.Cu")
		(net 202)
	)
	(via
		(at 190.5 139.5)
		(size 0.45)
		(drill 0.1)
		(layers "F.Cu" "B.Cu")
		(remove_unused_layers yes)
		(keep_end_layers yes)
		(zone_layer_connections)
		(net 202)
	)
	(via
		(at 176.85 111.75)
		(size 0.45)
		(drill 0.1)
		(layers "F.Cu" "B.Cu")
		(remove_unused_layers yes)
		(keep_end_layers yes)
		(zone_layer_connections)
		(net 202)
	)
	(segment
		(start 167.35 122.25)
		(end 172.55 127.45)
		(width 0.1)
		(layer "In9.Cu")
		(net 202)
	)
	(segment
		(start 169.85 114.85)
		(end 169.6 114.85)
		(width 0.1)
		(layer "In9.Cu")
		(net 202)
	)
	(segment
		(start 171.875 114.467819)
		(end 171.875 114.625)
		(width 0.1)
		(layer "In9.Cu")
		(net 202)
	)
	(segment
		(start 191 140.76)
		(end 191 140.3)
		(width 0.1)
		(layer "In9.Cu")
		(net 202)
	)
	(segment
		(start 172.55 133.3)
		(end 175.4 136.15)
		(width 0.1)
		(layer "In9.Cu")
		(net 202)
	)
	(segment
		(start 190.24 141.03)
		(end 190.73 141.03)
		(width 0.1)
		(layer "In9.Cu")
		(net 202)
	)
	(segment
		(start 172.775 114.467819)
		(end 172.775 114.625)
		(width 0.1)
		(layer "In9.Cu")
		(net 202)
	)
	(segment
		(start 176.85 111.75)
		(end 176.85 112.45)
		(width 0.1)
		(layer "In9.Cu")
		(net 202)
	)
	(segment
		(start 190.5 139.8)
		(end 190.5 139.5)
		(width 0.1)
		(layer "In9.Cu")
		(net 202)
	)
	(segment
		(start 190 141.76)
		(end 190 141.27)
		(width 0.1)
		(layer "In9.Cu")
		(net 202)
	)
	(segment
		(start 170.975 114.467819)
		(end 170.975 114.625)
		(width 0.1)
		(layer "In9.Cu")
		(net 202)
	)
	(segment
		(start 171.425 114.625)
		(end 171.425 114.467819)
		(width 0.1)
		(layer "In9.Cu")
		(net 202)
	)
	(segment
		(start 175.2 114.6)
		(end 174.95 114.85)
		(width 0.1)
		(layer "In9.Cu")
		(net 202)
	)
	(segment
		(start 189.36 142.4)
		(end 190 141.76)
		(width 0.1)
		(layer "In9.Cu")
		(net 202)
	)
	(segment
		(start 174.95 114.85)
		(end 174.35 114.85)
		(width 0.1)
		(layer "In9.Cu")
		(net 202)
	)
	(segment
		(start 187.5 142.4)
		(end 189.36 142.4)
		(width 0.1)
		(layer "In9.Cu")
		(net 202)
	)
	(segment
		(start 170.525 114.625)
		(end 170.525 114.467802)
		(width 0.1)
		(layer "In9.Cu")
		(net 202)
	)
	(segment
		(start 185.5 136.15)
		(end 187 137.65)
		(width 0.1)
		(layer "In9.Cu")
		(net 202)
	)
	(segment
		(start 169.6 114.85)
		(end 167.35 117.1)
		(width 0.1)
		(layer "In9.Cu")
		(net 202)
	)
	(segment
		(start 167.35 117.1)
		(end 167.35 122.25)
		(width 0.1)
		(layer "In9.Cu")
		(net 202)
	)
	(segment
		(start 174.125 114.625)
		(end 174.125 114.467802)
		(width 0.1)
		(layer "In9.Cu")
		(net 202)
	)
	(segment
		(start 170.075 114.467802)
		(end 170.075 114.625)
		(width 0.1)
		(layer "In9.Cu")
		(net 202)
	)
	(segment
		(start 191 140.3)
		(end 190.5 139.8)
		(width 0.1)
		(layer "In9.Cu")
		(net 202)
	)
	(segment
		(start 175.2 114.1)
		(end 175.2 114.6)
		(width 0.1)
		(layer "In9.Cu")
		(net 202)
	)
	(segment
		(start 187 137.65)
		(end 187 141.9)
		(width 0.1)
		(layer "In9.Cu")
		(net 202)
	)
	(segment
		(start 173.675 114.467802)
		(end 173.675 114.625)
		(width 0.1)
		(layer "In9.Cu")
		(net 202)
	)
	(segment
		(start 172.55 127.45)
		(end 172.55 133.3)
		(width 0.1)
		(layer "In9.Cu")
		(net 202)
	)
	(segment
		(start 172.325 114.625)
		(end 172.325 114.467819)
		(width 0.1)
		(layer "In9.Cu")
		(net 202)
	)
	(segment
		(start 190 141.27)
		(end 190.24 141.03)
		(width 0.1)
		(layer "In9.Cu")
		(net 202)
	)
	(segment
		(start 175.4 136.15)
		(end 185.5 136.15)
		(width 0.1)
		(layer "In9.Cu")
		(net 202)
	)
	(segment
		(start 190.73 141.03)
		(end 191 140.76)
		(width 0.1)
		(layer "In9.Cu")
		(net 202)
	)
	(segment
		(start 187 141.9)
		(end 187.5 142.4)
		(width 0.1)
		(layer "In9.Cu")
		(net 202)
	)
	(segment
		(start 173.225 114.625)
		(end 173.225 114.467819)
		(width 0.1)
		(layer "In9.Cu")
		(net 202)
	)
	(segment
		(start 176.85 112.45)
		(end 175.2 114.1)
		(width 0.1)
		(layer "In9.Cu")
		(net 202)
	)
	(arc
		(start 174.35 114.85)
		(mid 174.190901 114.784099)
		(end 174.125 114.625)
		(width 0.1)
		(layer "In9.Cu")
		(net 202)
	)
	(arc
		(start 173 114.242819)
		(mid 172.840901 114.30872)
		(end 172.775 114.467819)
		(width 0.1)
		(layer "In9.Cu")
		(net 202)
	)
	(arc
		(start 174.125 114.467802)
		(mid 174.059099 114.308703)
		(end 173.9 114.242802)
		(width 0.1)
		(layer "In9.Cu")
		(net 202)
	)
	(arc
		(start 170.3 114.242802)
		(mid 170.140901 114.308703)
		(end 170.075 114.467802)
		(width 0.1)
		(layer "In9.Cu")
		(net 202)
	)
	(arc
		(start 170.75 114.85)
		(mid 170.590901 114.784099)
		(end 170.525 114.625)
		(width 0.1)
		(layer "In9.Cu")
		(net 202)
	)
	(arc
		(start 170.975 114.625)
		(mid 170.909099 114.784099)
		(end 170.75 114.85)
		(width 0.1)
		(layer "In9.Cu")
		(net 202)
	)
	(arc
		(start 173.45 114.85)
		(mid 173.290901 114.784099)
		(end 173.225 114.625)
		(width 0.1)
		(layer "In9.Cu")
		(net 202)
	)
	(arc
		(start 173.675 114.625)
		(mid 173.609099 114.784099)
		(end 173.45 114.85)
		(width 0.1)
		(layer "In9.Cu")
		(net 202)
	)
	(arc
		(start 171.875 114.625)
		(mid 171.809099 114.784099)
		(end 171.65 114.85)
		(width 0.1)
		(layer "In9.Cu")
		(net 202)
	)
	(arc
		(start 172.325 114.467819)
		(mid 172.259099 114.30872)
		(end 172.1 114.242819)
		(width 0.1)
		(layer "In9.Cu")
		(net 202)
	)
	(arc
		(start 173.9 114.242802)
		(mid 173.740901 114.308703)
		(end 173.675 114.467802)
		(width 0.1)
		(layer "In9.Cu")
		(net 202)
	)
	(arc
		(start 171.65 114.85)
		(mid 171.490901 114.784099)
		(end 171.425 114.625)
		(width 0.1)
		(layer "In9.Cu")
		(net 202)
	)
	(arc
		(start 172.775 114.625)
		(mid 172.709099 114.784099)
		(end 172.55 114.85)
		(width 0.1)
		(layer "In9.Cu")
		(net 202)
	)
	(arc
		(start 171.2 114.242819)
		(mid 171.040901 114.30872)
		(end 170.975 114.467819)
		(width 0.1)
		(layer "In9.Cu")
		(net 202)
	)
	(arc
		(start 170.525 114.467802)
		(mid 170.459099 114.308703)
		(end 170.3 114.242802)
		(width 0.1)
		(layer "In9.Cu")
		(net 202)
	)
	(arc
		(start 172.55 114.85)
		(mid 172.390901 114.784099)
		(end 172.325 114.625)
		(width 0.1)
		(layer "In9.Cu")
		(net 202)
	)
	(arc
		(start 170.075 114.625)
		(mid 170.009099 114.784099)
		(end 169.85 114.85)
		(width 0.1)
		(layer "In9.Cu")
		(net 202)
	)
	(arc
		(start 173.225 114.467819)
		(mid 173.159099 114.30872)
		(end 173 114.242819)
		(width 0.1)
		(layer "In9.Cu")
		(net 202)
	)
	(arc
		(start 171.425 114.467819)
		(mid 171.359099 114.30872)
		(end 171.2 114.242819)
		(width 0.1)
		(layer "In9.Cu")
		(net 202)
	)
	(arc
		(start 172.1 114.242819)
		(mid 171.940901 114.30872)
		(end 171.875 114.467819)
		(width 0.1)
		(layer "In9.Cu")
		(net 202)
	)
	(segment
		(start 175.15 110.598)
		(end 175.15 111.75)
		(width 0.38)
		(layer "F.Cu")
		(net 203)
	)
	(segment
		(start 192.0005 141.9995)
		(end 192.5 141.5)
		(width 0.256)
		(layer "F.Cu")
		(net 203)
	)
	(via
		(at 192.5 141.5)
		(size 0.45)
		(drill 0.1)
		(layers "F.Cu" "B.Cu")
		(remove_unused_layers yes)
		(keep_end_layers yes)
		(zone_layer_connections)
		(net 203)
	)
	(via
		(at 175.15 111.75)
		(size 0.45)
		(drill 0.1)
		(layers "F.Cu" "B.Cu")
		(remove_unused_layers yes)
		(keep_end_layers yes)
		(zone_layer_connections)
		(net 203)
	)
	(segment
		(start 168.635 112.915)
		(end 173.985 112.915)
		(width 0.1)
		(layer "In9.Cu")
		(net 203)
	)
	(segment
		(start 185.375 144)
		(end 185 143.625)
		(width 0.1)
		(layer "In9.Cu")
		(net 203)
	)
	(segment
		(start 185 143.625)
		(end 185 138.97)
		(width 0.1)
		(layer "In9.Cu")
		(net 203)
	)
	(segment
		(start 184.07 138.04)
		(end 173.39 138.04)
		(width 0.1)
		(layer "In9.Cu")
		(net 203)
	)
	(segment
		(start 192 142.78)
		(end 191.78 143)
		(width 0.1)
		(layer "In9.Cu")
		(net 203)
	)
	(segment
		(start 173.985 112.915)
		(end 175.15 111.75)
		(width 0.1)
		(layer "In9.Cu")
		(net 203)
	)
	(segment
		(start 192.5 141.5)
		(end 192 142)
		(width 0.1)
		(layer "In9.Cu")
		(net 203)
	)
	(segment
		(start 191.78 143)
		(end 190.25 143)
		(width 0.1)
		(layer "In9.Cu")
		(net 203)
	)
	(segment
		(start 170.79 128.58)
		(end 165.25 123.04)
		(width 0.1)
		(layer "In9.Cu")
		(net 203)
	)
	(segment
		(start 185 138.97)
		(end 184.07 138.04)
		(width 0.1)
		(layer "In9.Cu")
		(net 203)
	)
	(segment
		(start 189.71 144)
		(end 185.375 144)
		(width 0.1)
		(layer "In9.Cu")
		(net 203)
	)
	(segment
		(start 190.01 143.7)
		(end 189.71 144)
		(width 0.1)
		(layer "In9.Cu")
		(net 203)
	)
	(segment
		(start 165.25 116.3)
		(end 168.635 112.915)
		(width 0.1)
		(layer "In9.Cu")
		(net 203)
	)
	(segment
		(start 165.25 123.04)
		(end 165.25 116.3)
		(width 0.1)
		(layer "In9.Cu")
		(net 203)
	)
	(segment
		(start 190.25 143)
		(end 190.01 143.24)
		(width 0.1)
		(layer "In9.Cu")
		(net 203)
	)
	(segment
		(start 190.01 143.24)
		(end 190.01 143.7)
		(width 0.1)
		(layer "In9.Cu")
		(net 203)
	)
	(segment
		(start 173.39 138.04)
		(end 170.79 135.44)
		(width 0.1)
		(layer "In9.Cu")
		(net 203)
	)
	(segment
		(start 170.79 135.44)
		(end 170.79 128.58)
		(width 0.1)
		(layer "In9.Cu")
		(net 203)
	)
	(segment
		(start 192 142)
		(end 192 142.78)
		(width 0.1)
		(layer "In9.Cu")
		(net 203)
	)
	(segment
		(start 170.9 110.598)
		(end 170.9 111.75)
		(width 0.38)
		(layer "F.Cu")
		(net 204)
	)
	(segment
		(start 190.0005 145.9995)
		(end 190.5 145.5)
		(width 0.256)
		(layer "F.Cu")
		(net 204)
	)
	(via
		(at 190.5 145.5)
		(size 0.45)
		(drill 0.1)
		(layers "F.Cu" "B.Cu")
		(remove_unused_layers yes)
		(keep_end_layers yes)
		(zone_layer_connections)
		(net 204)
	)
	(via
		(at 170.9 111.75)
		(size 0.45)
		(drill 0.1)
		(layers "F.Cu" "B.Cu")
		(remove_unused_layers yes)
		(keep_end_layers yes)
		(zone_layer_connections)
		(net 204)
	)
	(segment
		(start 178.1081 114.725)
		(end 177.8 114.725)
		(width 0.148)
		(layer "In6.Cu")
		(net 204)
	)
	(segment
		(start 173.054962 112.915013)
		(end 172.807475 113.162499)
		(width 0.148)
		(layer "In6.Cu")
		(net 204)
	)
	(segment
		(start 194 128.5)
		(end 180.225 114.725)
		(width 0.148)
		(layer "In6.Cu")
		(net 204)
	)
	(segment
		(start 177.479025 114.404025)
		(end 177.479025 114.404024)
		(width 0.148)
		(layer "In6.Cu")
		(net 204)
	)
	(segment
		(start 173.875 114.725)
		(end 173.30245 114.152449)
		(width 0.148)
		(layer "In6.Cu")
		(net 204)
	)
	(segment
		(start 176.20805 114.725)
		(end 175.9 114.725)
		(width 0.148)
		(layer "In6.Cu")
		(net 204)
	)
	(segment
		(start 173.302449 113.657474)
		(end 173.549935 113.409987)
		(width 0.148)
		(layer "In6.Cu")
		(net 204)
	)
	(segment
		(start 174.628975 114.403974)
		(end 174.628975 114.403975)
		(width 0.148)
		(layer "In6.Cu")
		(net 204)
	)
	(segment
		(start 190.5 145.5)
		(end 191 146)
		(width 0.148)
		(layer "In6.Cu")
		(net 204)
	)
	(segment
		(start 193.7 146)
		(end 194 145.7)
		(width 0.148)
		(layer "In6.Cu")
		(net 204)
	)
	(segment
		(start 176.529025 114.404024)
		(end 176.529025 114.404025)
		(width 0.148)
		(layer "In6.Cu")
		(net 204)
	)
	(segment
		(start 172.3125 113.1625)
		(end 170.9 111.75)
		(width 0.148)
		(layer "In6.Cu")
		(net 204)
	)
	(segment
		(start 180.225 114.725)
		(end 179.7 114.725)
		(width 0.148)
		(layer "In6.Cu")
		(net 204)
	)
	(segment
		(start 174.30795 114.725)
		(end 174 114.725)
		(width 0.148)
		(layer "In6.Cu")
		(net 204)
	)
	(segment
		(start 175.578975 114.403975)
		(end 175.578975 114.403974)
		(width 0.148)
		(layer "In6.Cu")
		(net 204)
	)
	(segment
		(start 191 146)
		(end 193.7 146)
		(width 0.148)
		(layer "In6.Cu")
		(net 204)
	)
	(segment
		(start 170.9 111.75)
		(end 170.9 111.748)
		(width 0.148)
		(layer "In6.Cu")
		(net 204)
	)
	(segment
		(start 194 145.7)
		(end 194 128.5)
		(width 0.148)
		(layer "In6.Cu")
		(net 204)
	)
	(segment
		(start 179.37905 114.40405)
		(end 179.37905 114.404049)
		(width 0.148)
		(layer "In6.Cu")
		(net 204)
	)
	(segment
		(start 178.42905 114.404049)
		(end 178.42905 114.40405)
		(width 0.148)
		(layer "In6.Cu")
		(net 204)
	)
	(segment
		(start 174 114.725)
		(end 173.875 114.725)
		(width 0.148)
		(layer "In6.Cu")
		(net 204)
	)
	(segment
		(start 175.25795 114.082949)
		(end 174.95 114.082949)
		(width 0.148)
		(layer "In6.Cu")
		(net 204)
	)
	(segment
		(start 173.549936 112.915012)
		(end 173.549937 112.915014)
		(width 0.148)
		(layer "In6.Cu")
		(net 204)
	)
	(segment
		(start 177.15805 114.083049)
		(end 176.85 114.083049)
		(width 0.148)
		(layer "In6.Cu")
		(net 204)
	)
	(segment
		(start 179.0581 114.083099)
		(end 178.75 114.083099)
		(width 0.148)
		(layer "In6.Cu")
		(net 204)
	)
	(arc
		(start 176.85 114.083049)
		(mid 176.623036 114.17706)
		(end 176.529025 114.404024)
		(width 0.148)
		(layer "In6.Cu")
		(net 204)
	)
	(arc
		(start 174.628975 114.403975)
		(mid 174.534949 114.630974)
		(end 174.30795 114.725)
		(width 0.148)
		(layer "In6.Cu")
		(net 204)
	)
	(arc
		(start 178.42905 114.40405)
		(mid 178.335046 114.630996)
		(end 178.1081 114.725)
		(width 0.148)
		(layer "In6.Cu")
		(net 204)
	)
	(arc
		(start 175.9 114.725)
		(mid 175.673001 114.630974)
		(end 175.578975 114.403975)
		(width 0.148)
		(layer "In6.Cu")
		(net 204)
	)
	(arc
		(start 177.479025 114.404024)
		(mid 177.385014 114.17706)
		(end 177.15805 114.083049)
		(width 0.148)
		(layer "In6.Cu")
		(net 204)
	)
	(arc
		(start 178.75 114.083099)
		(mid 178.523054 114.177103)
		(end 178.42905 114.404049)
		(width 0.148)
		(layer "In6.Cu")
		(net 204)
	)
	(arc
		(start 173.549937 112.915014)
		(mid 173.30245 112.812501)
		(end 173.054962 112.915013)
		(width 0.148)
		(layer "In6.Cu")
		(net 204)
	)
	(arc
		(start 177.8 114.725)
		(mid 177.573036 114.630989)
		(end 177.479025 114.404025)
		(width 0.148)
		(layer "In6.Cu")
		(net 204)
	)
	(arc
		(start 179.37905 114.404049)
		(mid 179.285046 114.177103)
		(end 179.0581 114.083099)
		(width 0.148)
		(layer "In6.Cu")
		(net 204)
	)
	(arc
		(start 172.807475 113.162499)
		(mid 172.559988 113.265012)
		(end 172.3125 113.1625)
		(width 0.148)
		(layer "In6.Cu")
		(net 204)
	)
	(arc
		(start 176.529025 114.404025)
		(mid 176.435014 114.630989)
		(end 176.20805 114.725)
		(width 0.148)
		(layer "In6.Cu")
		(net 204)
	)
	(arc
		(start 174.95 114.082949)
		(mid 174.723001 114.176975)
		(end 174.628975 114.403974)
		(width 0.148)
		(layer "In6.Cu")
		(net 204)
	)
	(arc
		(start 175.578975 114.403974)
		(mid 175.484949 114.176975)
		(end 175.25795 114.082949)
		(width 0.148)
		(layer "In6.Cu")
		(net 204)
	)
	(arc
		(start 173.549935 113.409987)
		(mid 173.652448 113.1625)
		(end 173.549936 112.915012)
		(width 0.148)
		(layer "In6.Cu")
		(net 204)
	)
	(arc
		(start 173.30245 114.152449)
		(mid 173.199937 113.904962)
		(end 173.302449 113.657474)
		(width 0.148)
		(layer "In6.Cu")
		(net 204)
	)
	(arc
		(start 179.7 114.725)
		(mid 179.473054 114.630996)
		(end 179.37905 114.40405)
		(width 0.148)
		(layer "In6.Cu")
		(net 204)
	)
	(segment
		(start 169.2 110.598)
		(end 169.2 111.75)
		(width 0.38)
		(layer "F.Cu")
		(net 205)
	)
	(segment
		(start 189 145)
		(end 189.5 144.5)
		(width 0.256)
		(layer "F.Cu")
		(net 205)
	)
	(via
		(at 189.5 144.5)
		(size 0.45)
		(drill 0.1)
		(layers "F.Cu" "B.Cu")
		(remove_unused_layers yes)
		(keep_end_layers yes)
		(zone_layer_connections)
		(net 205)
	)
	(via
		(at 169.2 111.75)
		(size 0.45)
		(drill 0.1)
		(layers "F.Cu" "B.Cu")
		(remove_unused_layers yes)
		(keep_end_layers yes)
		(zone_layer_connections)
		(net 205)
	)
	(segment
		(start 183.156091 121.369264)
		(end 183.194479 121.330875)
		(width 0.148)
		(layer "In6.Cu")
		(net 205)
	)
	(segment
		(start 179.775 117.275)
		(end 180.0125 117.5125)
		(width 0.148)
		(layer "In6.Cu")
		(net 205)
	)
	(segment
		(start 184.428847 122.642092)
		(end 184.428846 122.642093)
		(width 0.148)
		(layer "In6.Cu")
		(net 205)
	)
	(segment
		(start 192 129.5)
		(end 192 143.8)
		(width 0.148)
		(layer "In6.Cu")
		(net 205)
	)
	(segment
		(start 182.558083 120.694481)
		(end 182.558084 120.69448)
		(width 0.148)
		(layer "In6.Cu")
		(net 205)
	)
	(segment
		(start 181.883299 120.096472)
		(end 181.921687 120.058083)
		(width 0.148)
		(layer "In6.Cu")
		(net 205)
	)
	(segment
		(start 189.520079 127.733196)
		(end 189.520078 127.733197)
		(width 0.148)
		(layer "In6.Cu")
		(net 205)
	)
	(segment
		(start 191.467628 128.967628)
		(end 192 129.5)
		(width 0.148)
		(layer "In6.Cu")
		(net 205)
	)
	(segment
		(start 183.830876 121.967272)
		(end 183.79245 122.005697)
		(width 0.148)
		(layer "In6.Cu")
		(net 205)
	)
	(segment
		(start 181.285292 119.421688)
		(end 181.246903 119.460076)
		(width 0.148)
		(layer "In6.Cu")
		(net 205)
	)
	(segment
		(start 188.922044 127.05844)
		(end 188.883682 127.096801)
		(width 0.148)
		(layer "In6.Cu")
		(net 205)
	)
	(segment
		(start 188.922043 127.058441)
		(end 188.922044 127.05844)
		(width 0.148)
		(layer "In6.Cu")
		(net 205)
	)
	(segment
		(start 181.285291 119.421689)
		(end 181.285292 119.421688)
		(width 0.148)
		(layer "In6.Cu")
		(net 205)
	)
	(segment
		(start 187.649252 125.785648)
		(end 187.610848 125.824051)
		(width 0.148)
		(layer "In6.Cu")
		(net 205)
	)
	(segment
		(start 192 143.8)
		(end 191.8 144)
		(width 0.148)
		(layer "In6.Cu")
		(net 205)
	)
	(segment
		(start 191.8 144)
		(end 190 144)
		(width 0.148)
		(layer "In6.Cu")
		(net 205)
	)
	(segment
		(start 185.103667 122.603667)
		(end 185.103668 122.603668)
		(width 0.148)
		(layer "In6.Cu")
		(net 205)
	)
	(segment
		(start 189.520078 127.733197)
		(end 189.558439 127.694835)
		(width 0.148)
		(layer "In6.Cu")
		(net 205)
	)
	(segment
		(start 180.610508 118.823679)
		(end 180.610507 118.82368)
		(width 0.148)
		(layer "In6.Cu")
		(net 205)
	)
	(segment
		(start 188.922043 126.422043)
		(end 188.922044 126.422044)
		(width 0.148)
		(layer "In6.Cu")
		(net 205)
	)
	(segment
		(start 172.6 117.275)
		(end 179.775 117.275)
		(width 0.148)
		(layer "In6.Cu")
		(net 205)
	)
	(segment
		(start 190.79283 129.006029)
		(end 190.792829 129.00603)
		(width 0.148)
		(layer "In6.Cu")
		(net 205)
	)
	(segment
		(start 182.558083 120.058083)
		(end 182.558084 120.058084)
		(width 0.148)
		(layer "In6.Cu")
		(net 205)
	)
	(segment
		(start 169.2 111.748)
		(end 169.2 113.875)
		(width 0.148)
		(layer "In6.Cu")
		(net 205)
	)
	(segment
		(start 180.012499 118.148897)
		(end 180.0125 118.148896)
		(width 0.148)
		(layer "In6.Cu")
		(net 205)
	)
	(segment
		(start 185.701639 123.914884)
		(end 185.701638 123.914885)
		(width 0.148)
		(layer "In6.Cu")
		(net 205)
	)
	(segment
		(start 180.0125 118.148896)
		(end 179.974111 118.187284)
		(width 0.148)
		(layer "In6.Cu")
		(net 205)
	)
	(segment
		(start 187.649251 125.149252)
		(end 187.649252 125.149252)
		(width 0.148)
		(layer "In6.Cu")
		(net 205)
	)
	(segment
		(start 186.37646 124.512856)
		(end 186.338064 124.551251)
		(width 0.148)
		(layer "In6.Cu")
		(net 205)
	)
	(segment
		(start 183.156092 121.369263)
		(end 183.156091 121.369264)
		(width 0.148)
		(layer "In6.Cu")
		(net 205)
	)
	(segment
		(start 190.792829 129.00603)
		(end 190.831231 128.967627)
		(width 0.148)
		(layer "In6.Cu")
		(net 205)
	)
	(segment
		(start 185.103667 123.240065)
		(end 185.103668 123.240064)
		(width 0.148)
		(layer "In6.Cu")
		(net 205)
	)
	(segment
		(start 186.338064 125.187647)
		(end 186.338064 125.187648)
		(width 0.148)
		(layer "In6.Cu")
		(net 205)
	)
	(segment
		(start 191.467627 128.967627)
		(end 191.467628 128.967628)
		(width 0.148)
		(layer "In6.Cu")
		(net 205)
	)
	(segment
		(start 181.285291 118.785291)
		(end 181.285292 118.785292)
		(width 0.148)
		(layer "In6.Cu")
		(net 205)
	)
	(segment
		(start 184.428846 122.642093)
		(end 184.467271 122.603667)
		(width 0.148)
		(layer "In6.Cu")
		(net 205)
	)
	(segment
		(start 180.610507 118.82368)
		(end 180.648895 118.785291)
		(width 0.148)
		(layer "In6.Cu")
		(net 205)
	)
	(segment
		(start 185.701638 123.914885)
		(end 185.740063 123.876459)
		(width 0.148)
		(layer "In6.Cu")
		(net 205)
	)
	(segment
		(start 186.974461 125.187647)
		(end 186.97446 125.187648)
		(width 0.148)
		(layer "In6.Cu")
		(net 205)
	)
	(segment
		(start 188.247245 126.460446)
		(end 188.247244 126.460447)
		(width 0.148)
		(layer "In6.Cu")
		(net 205)
	)
	(segment
		(start 188.247244 126.460447)
		(end 188.285647 126.422043)
		(width 0.148)
		(layer "In6.Cu")
		(net 205)
	)
	(segment
		(start 185.103668 123.240064)
		(end 185.065242 123.278489)
		(width 0.148)
		(layer "In6.Cu")
		(net 205)
	)
	(segment
		(start 190.194835 128.331233)
		(end 190.194836 128.331232)
		(width 0.148)
		(layer "In6.Cu")
		(net 205)
	)
	(segment
		(start 169.2 113.875)
		(end 172.6 117.275)
		(width 0.148)
		(layer "In6.Cu")
		(net 205)
	)
	(segment
		(start 186.376459 123.876459)
		(end 186.37646 123.87646)
		(width 0.148)
		(layer "In6.Cu")
		(net 205)
	)
	(segment
		(start 190.194836 128.331232)
		(end 190.156433 128.369634)
		(width 0.148)
		(layer "In6.Cu")
		(net 205)
	)
	(segment
		(start 186.376459 124.512857)
		(end 186.37646 124.512856)
		(width 0.148)
		(layer "In6.Cu")
		(net 205)
	)
	(segment
		(start 187.649251 125.785649)
		(end 187.649252 125.785648)
		(width 0.148)
		(layer "In6.Cu")
		(net 205)
	)
	(segment
		(start 190 144)
		(end 189.5 144.5)
		(width 0.148)
		(layer "In6.Cu")
		(net 205)
	)
	(segment
		(start 183.830875 121.330875)
		(end 183.830876 121.330876)
		(width 0.148)
		(layer "In6.Cu")
		(net 205)
	)
	(segment
		(start 181.8833 120.096471)
		(end 181.883299 120.096472)
		(width 0.148)
		(layer "In6.Cu")
		(net 205)
	)
	(segment
		(start 183.830875 121.967273)
		(end 183.830876 121.967272)
		(width 0.148)
		(layer "In6.Cu")
		(net 205)
	)
	(segment
		(start 182.558084 120.69448)
		(end 182.519695 120.732868)
		(width 0.148)
		(layer "In6.Cu")
		(net 205)
	)
	(segment
		(start 186.97446 125.187648)
		(end 187.012855 125.149252)
		(width 0.148)
		(layer "In6.Cu")
		(net 205)
	)
	(segment
		(start 190.194835 127.694835)
		(end 190.194836 127.694836)
		(width 0.148)
		(layer "In6.Cu")
		(net 205)
	)
	(arc
		(start 186.37646 123.87646)
		(mid 186.508262 124.194659)
		(end 186.376459 124.512857)
		(width 0.148)
		(layer "In6.Cu")
		(net 205)
	)
	(arc
		(start 185.065242 123.914885)
		(mid 185.383441 124.046687)
		(end 185.701639 123.914884)
		(width 0.148)
		(layer "In6.Cu")
		(net 205)
	)
	(arc
		(start 180.648895 118.785291)
		(mid 180.967093 118.653489)
		(end 181.285291 118.785291)
		(width 0.148)
		(layer "In6.Cu")
		(net 205)
	)
	(arc
		(start 179.974111 118.82368)
		(mid 180.29231 118.955482)
		(end 180.610508 118.823679)
		(width 0.148)
		(layer "In6.Cu")
		(net 205)
	)
	(arc
		(start 183.194479 121.330875)
		(mid 183.512677 121.199073)
		(end 183.830875 121.330875)
		(width 0.148)
		(layer "In6.Cu")
		(net 205)
	)
	(arc
		(start 189.558439 127.694835)
		(mid 189.876637 127.563033)
		(end 190.194835 127.694835)
		(width 0.148)
		(layer "In6.Cu")
		(net 205)
	)
	(arc
		(start 183.79245 122.642093)
		(mid 184.110649 122.773895)
		(end 184.428847 122.642092)
		(width 0.148)
		(layer "In6.Cu")
		(net 205)
	)
	(arc
		(start 188.883682 127.733197)
		(mid 189.201881 127.864999)
		(end 189.520079 127.733196)
		(width 0.148)
		(layer "In6.Cu")
		(net 205)
	)
	(arc
		(start 183.830876 121.330876)
		(mid 183.962678 121.649075)
		(end 183.830875 121.967273)
		(width 0.148)
		(layer "In6.Cu")
		(net 205)
	)
	(arc
		(start 186.338064 125.187648)
		(mid 186.656263 125.31945)
		(end 186.974461 125.187647)
		(width 0.148)
		(layer "In6.Cu")
		(net 205)
	)
	(arc
		(start 180.0125 117.5125)
		(mid 180.144302 117.830699)
		(end 180.012499 118.148897)
		(width 0.148)
		(layer "In6.Cu")
		(net 205)
	)
	(arc
		(start 179.974111 118.187284)
		(mid 179.842309 118.505482)
		(end 179.974111 118.82368)
		(width 0.148)
		(layer "In6.Cu")
		(net 205)
	)
	(arc
		(start 190.831231 128.967627)
		(mid 191.149429 128.835825)
		(end 191.467627 128.967627)
		(width 0.148)
		(layer "In6.Cu")
		(net 205)
	)
	(arc
		(start 187.610848 126.460447)
		(mid 187.929047 126.592249)
		(end 188.247245 126.460446)
		(width 0.148)
		(layer "In6.Cu")
		(net 205)
	)
	(arc
		(start 185.065242 123.278489)
		(mid 184.93344 123.596687)
		(end 185.065242 123.914885)
		(width 0.148)
		(layer "In6.Cu")
		(net 205)
	)
	(arc
		(start 181.921687 120.058083)
		(mid 182.239885 119.926281)
		(end 182.558083 120.058083)
		(width 0.148)
		(layer "In6.Cu")
		(net 205)
	)
	(arc
		(start 190.194836 127.694836)
		(mid 190.326638 128.013035)
		(end 190.194835 128.331233)
		(width 0.148)
		(layer "In6.Cu")
		(net 205)
	)
	(arc
		(start 184.467271 122.603667)
		(mid 184.785469 122.471865)
		(end 185.103667 122.603667)
		(width 0.148)
		(layer "In6.Cu")
		(net 205)
	)
	(arc
		(start 190.156433 129.00603)
		(mid 190.474632 129.137832)
		(end 190.79283 129.006029)
		(width 0.148)
		(layer "In6.Cu")
		(net 205)
	)
	(arc
		(start 188.883682 127.096801)
		(mid 188.75188 127.414999)
		(end 188.883682 127.733197)
		(width 0.148)
		(layer "In6.Cu")
		(net 205)
	)
	(arc
		(start 187.649252 125.149252)
		(mid 187.781054 125.467451)
		(end 187.649251 125.785649)
		(width 0.148)
		(layer "In6.Cu")
		(net 205)
	)
	(arc
		(start 190.156433 128.369634)
		(mid 190.024631 128.687832)
		(end 190.156433 129.00603)
		(width 0.148)
		(layer "In6.Cu")
		(net 205)
	)
	(arc
		(start 181.246903 119.460076)
		(mid 181.115101 119.778274)
		(end 181.246903 120.096472)
		(width 0.148)
		(layer "In6.Cu")
		(net 205)
	)
	(arc
		(start 187.610848 125.824051)
		(mid 187.479046 126.142249)
		(end 187.610848 126.460447)
		(width 0.148)
		(layer "In6.Cu")
		(net 205)
	)
	(arc
		(start 182.519695 121.369264)
		(mid 182.837894 121.501066)
		(end 183.156092 121.369263)
		(width 0.148)
		(layer "In6.Cu")
		(net 205)
	)
	(arc
		(start 183.79245 122.005697)
		(mid 183.660648 122.323895)
		(end 183.79245 122.642093)
		(width 0.148)
		(layer "In6.Cu")
		(net 205)
	)
	(arc
		(start 181.285292 118.785292)
		(mid 181.417094 119.103491)
		(end 181.285291 119.421689)
		(width 0.148)
		(layer "In6.Cu")
		(net 205)
	)
	(arc
		(start 185.103668 122.603668)
		(mid 185.23547 122.921867)
		(end 185.103667 123.240065)
		(width 0.148)
		(layer "In6.Cu")
		(net 205)
	)
	(arc
		(start 188.285647 126.422043)
		(mid 188.603845 126.290241)
		(end 188.922043 126.422043)
		(width 0.148)
		(layer "In6.Cu")
		(net 205)
	)
	(arc
		(start 187.012855 125.149252)
		(mid 187.331053 125.01745)
		(end 187.649251 125.149252)
		(width 0.148)
		(layer "In6.Cu")
		(net 205)
	)
	(arc
		(start 188.922044 126.422044)
		(mid 189.053846 126.740243)
		(end 188.922043 127.058441)
		(width 0.148)
		(layer "In6.Cu")
		(net 205)
	)
	(arc
		(start 181.246903 120.096472)
		(mid 181.565102 120.228274)
		(end 181.8833 120.096471)
		(width 0.148)
		(layer "In6.Cu")
		(net 205)
	)
	(arc
		(start 182.558084 120.058084)
		(mid 182.689886 120.376283)
		(end 182.558083 120.694481)
		(width 0.148)
		(layer "In6.Cu")
		(net 205)
	)
	(arc
		(start 186.338064 124.551251)
		(mid 186.206262 124.869449)
		(end 186.338064 125.187647)
		(width 0.148)
		(layer "In6.Cu")
		(net 205)
	)
	(arc
		(start 185.740063 123.876459)
		(mid 186.058261 123.744657)
		(end 186.376459 123.876459)
		(width 0.148)
		(layer "In6.Cu")
		(net 205)
	)
	(arc
		(start 182.519695 120.732868)
		(mid 182.387893 121.051066)
		(end 182.519695 121.369264)
		(width 0.148)
		(layer "In6.Cu")
		(net 205)
	)
	(segment
		(start 233.7 167.251)
		(end 233.7 166.7)
		(width 0.4)
		(layer "F.Cu")
		(net 206)
	)
	(segment
		(start 196.0005 151.9995)
		(end 196.5 151.5)
		(width 0.256)
		(layer "F.Cu")
		(net 206)
	)
	(via
		(at 196.5 151.5)
		(size 0.45)
		(drill 0.1)
		(layers "F.Cu" "B.Cu")
		(remove_unused_layers yes)
		(keep_end_layers yes)
		(zone_layer_connections)
		(net 206)
	)
	(via
		(at 233.7 166.7)
		(size 0.45)
		(drill 0.1)
		(layers "F.Cu" "B.Cu")
		(remove_unused_layers yes)
		(keep_end_layers yes)
		(zone_layer_connections)
		(net 206)
	)
	(segment
		(start 202.1 152)
		(end 203.95 150.15)
		(width 0.1)
		(layer "In6.Cu")
		(net 206)
	)
	(segment
		(start 197.3 149.97)
		(end 199.8 149.97)
		(width 0.1)
		(layer "In6.Cu")
		(net 206)
	)
	(segment
		(start 200.03 150.2)
		(end 200.03 150.84)
		(width 0.1)
		(layer "In6.Cu")
		(net 206)
	)
	(segment
		(start 200.91 151.3)
		(end 200.91 151.61)
		(width 0.1)
		(layer "In6.Cu")
		(net 206)
	)
	(segment
		(start 206.6445 150.2845)
		(end 208.0055 150.2845)
		(width 0.1)
		(layer "In6.Cu")
		(net 206)
	)
	(segment
		(start 216.57 148.57)
		(end 218.15 150.15)
		(width 0.1)
		(layer "In6.Cu")
		(net 206)
	)
	(segment
		(start 201.3 152)
		(end 202.1 152)
		(width 0.1)
		(layer "In6.Cu")
		(net 206)
	)
	(segment
		(start 199.8 149.97)
		(end 200.03 150.2)
		(width 0.1)
		(layer "In6.Cu")
		(net 206)
	)
	(segment
		(start 233.7 161.9)
		(end 233.7 166.7)
		(width 0.1)
		(layer "In6.Cu")
		(net 206)
	)
	(segment
		(start 210.93 148.57)
		(end 216.57 148.57)
		(width 0.1)
		(layer "In6.Cu")
		(net 206)
	)
	(segment
		(start 196.5 151.5)
		(end 196.98 151.02)
		(width 0.1)
		(layer "In6.Cu")
		(net 206)
	)
	(segment
		(start 209.61 149.89)
		(end 210.93 148.57)
		(width 0.1)
		(layer "In6.Cu")
		(net 206)
	)
	(segment
		(start 206.51 150.15)
		(end 206.6445 150.2845)
		(width 0.1)
		(layer "In6.Cu")
		(net 206)
	)
	(segment
		(start 196.98 150.29)
		(end 197.3 149.97)
		(width 0.1)
		(layer "In6.Cu")
		(net 206)
	)
	(segment
		(start 221.95 150.15)
		(end 233.7 161.9)
		(width 0.1)
		(layer "In6.Cu")
		(net 206)
	)
	(segment
		(start 200.63 151.02)
		(end 200.91 151.3)
		(width 0.1)
		(layer "In6.Cu")
		(net 206)
	)
	(segment
		(start 200.91 151.61)
		(end 201.3 152)
		(width 0.1)
		(layer "In6.Cu")
		(net 206)
	)
	(segment
		(start 203.95 150.15)
		(end 206.51 150.15)
		(width 0.1)
		(layer "In6.Cu")
		(net 206)
	)
	(segment
		(start 196.98 151.02)
		(end 196.98 150.29)
		(width 0.1)
		(layer "In6.Cu")
		(net 206)
	)
	(segment
		(start 208.0055 150.2845)
		(end 208.4 149.89)
		(width 0.1)
		(layer "In6.Cu")
		(net 206)
	)
	(segment
		(start 200.03 150.84)
		(end 200.21 151.02)
		(width 0.1)
		(layer "In6.Cu")
		(net 206)
	)
	(segment
		(start 208.4 149.89)
		(end 209.61 149.89)
		(width 0.1)
		(layer "In6.Cu")
		(net 206)
	)
	(segment
		(start 200.21 151.02)
		(end 200.63 151.02)
		(width 0.1)
		(layer "In6.Cu")
		(net 206)
	)
	(segment
		(start 218.15 150.15)
		(end 221.95 150.15)
		(width 0.1)
		(layer "In6.Cu")
		(net 206)
	)
	(segment
		(start 197.0005 143.9995)
		(end 197.5 143.5)
		(width 0.256)
		(layer "F.Cu")
		(net 208)
	)
	(segment
		(start 223.6 110.598)
		(end 223.6 111.75)
		(width 0.38)
		(layer "F.Cu")
		(net 208)
	)
	(via
		(at 223.6 111.75)
		(size 0.45)
		(drill 0.1)
		(layers "F.Cu" "B.Cu")
		(remove_unused_layers yes)
		(keep_end_layers yes)
		(zone_layer_connections)
		(net 208)
	)
	(via
		(at 197.5 143.5)
		(size 0.45)
		(drill 0.1)
		(layers "F.Cu" "B.Cu")
		(remove_unused_layers yes)
		(keep_end_layers yes)
		(zone_layer_connections)
		(net 208)
	)
	(segment
		(start 195.495 115.725)
		(end 195.495 115.995)
		(width 0.13)
		(layer "In2.Cu")
		(net 208)
	)
	(segment
		(start 192.545 120.42)
		(end 191.375 120.42)
		(width 0.13)
		(layer "In2.Cu")
		(net 208)
	)
	(segment
		(start 197.1 143.45)
		(end 197.1 139.22)
		(width 0.1)
		(layer "In2.Cu")
		(net 208)
	)
	(segment
		(start 191.02 123.000294)
		(end 197.12 129.100294)
		(width 0.13)
		(layer "In2.Cu")
		(net 208)
	)
	(segment
		(start 197.1 139.22)
		(end 197.12 139.2)
		(width 0.1)
		(layer "In2.Cu")
		(net 208)
	)
	(segment
		(start 193.509854 115.709854)
		(end 193.081299 116.138405)
		(width 0.13)
		(layer "In2.Cu")
		(net 208)
	)
	(segment
		(start 192.538923 117.887058)
		(end 192.538923 117.887057)
		(width 0.13)
		(layer "In2.Cu")
		(net 208)
	)
	(segment
		(start 194.405 115.995)
		(end 194.405 115.725)
		(width 0.13)
		(layer "In2.Cu")
		(net 208)
	)
	(segment
		(start 220.899706 115.42)
		(end 195.8 115.42)
		(width 0.13)
		(layer "In2.Cu")
		(net 208)
	)
	(segment
		(start 192.538923 117.887057)
		(end 192.204487 117.552621)
		(width 0.13)
		(layer "In2.Cu")
		(net 208)
	)
	(segment
		(start 194.1 115.42)
		(end 193.799706 115.42)
		(width 0.13)
		(layer "In2.Cu")
		(net 208)
	)
	(segment
		(start 223.575 111.75)
		(end 223.295 112.03)
		(width 0.13)
		(layer "In2.Cu")
		(net 208)
	)
	(segment
		(start 193.415735 117.887056)
		(end 193.415736 117.887056)
		(width 0.13)
		(layer "In2.Cu")
		(net 208)
	)
	(segment
		(start 191.667086 117.55262)
		(end 191.667085 117.552622)
		(width 0.13)
		(layer "In2.Cu")
		(net 208)
	)
	(segment
		(start 191.667085 117.552622)
		(end 191.596377 117.623333)
		(width 0.13)
		(layer "In2.Cu")
		(net 208)
	)
	(segment
		(start 191.02 118.199706)
		(end 191.02 118.875)
		(width 0.13)
		(layer "In2.Cu")
		(net 208)
	)
	(segment
		(start 197.15 143.5)
		(end 197.1 143.45)
		(width 0.1)
		(layer "In2.Cu")
		(net 208)
	)
	(segment
		(start 191.375 121.13)
		(end 192.545 121.13)
		(width 0.13)
		(layer "In2.Cu")
		(net 208)
	)
	(segment
		(start 223.295 112.03)
		(end 223.295 113.024706)
		(width 0.13)
		(layer "In2.Cu")
		(net 208)
	)
	(segment
		(start 191.375 119.23)
		(end 192.545 119.23)
		(width 0.13)
		(layer "In2.Cu")
		(net 208)
	)
	(segment
		(start 223.295 113.024706)
		(end 220.899706 115.42)
		(width 0.13)
		(layer "In2.Cu")
		(net 208)
	)
	(segment
		(start 192.545 122.32)
		(end 191.375 122.32)
		(width 0.13)
		(layer "In2.Cu")
		(net 208)
	)
	(segment
		(start 223.6 111.75)
		(end 223.575 111.75)
		(width 0.13)
		(layer "In2.Cu")
		(net 208)
	)
	(segment
		(start 197.5 143.5)
		(end 197.15 143.5)
		(width 0.1)
		(layer "In2.Cu")
		(net 208)
	)
	(segment
		(start 193.799706 115.42)
		(end 193.509854 115.709854)
		(width 0.13)
		(layer "In2.Cu")
		(net 208)
	)
	(segment
		(start 193.081298 116.675807)
		(end 193.415735 117.010244)
		(width 0.13)
		(layer "In2.Cu")
		(net 208)
	)
	(segment
		(start 193.081299 116.675807)
		(end 193.081298 116.675807)
		(width 0.13)
		(layer "In2.Cu")
		(net 208)
	)
	(segment
		(start 193.415736 117.887056)
		(end 193.415735 117.887058)
		(width 0.13)
		(layer "In2.Cu")
		(net 208)
	)
	(segment
		(start 191.596377 117.623333)
		(end 191.02 118.199706)
		(width 0.13)
		(layer "In2.Cu")
		(net 208)
	)
	(segment
		(start 197.12 129.100294)
		(end 197.12 139.2)
		(width 0.13)
		(layer "In2.Cu")
		(net 208)
	)
	(segment
		(start 191.02 122.675)
		(end 191.02 123.000294)
		(width 0.13)
		(layer "In2.Cu")
		(net 208)
	)
	(arc
		(start 192.545 119.23)
		(mid 192.965729 119.404271)
		(end 193.14 119.825)
		(width 0.13)
		(layer "In2.Cu")
		(net 208)
	)
	(arc
		(start 195.8 115.42)
		(mid 195.584332 115.509332)
		(end 195.495 115.725)
		(width 0.13)
		(layer "In2.Cu")
		(net 208)
	)
	(arc
		(start 193.415735 117.887058)
		(mid 192.977329 118.068652)
		(end 192.538923 117.887058)
		(width 0.13)
		(layer "In2.Cu")
		(net 208)
	)
	(arc
		(start 193.14 121.725)
		(mid 192.965729 122.145729)
		(end 192.545 122.32)
		(width 0.13)
		(layer "In2.Cu")
		(net 208)
	)
	(arc
		(start 192.204487 117.552621)
		(mid 191.935787 117.441321)
		(end 191.667086 117.55262)
		(width 0.13)
		(layer "In2.Cu")
		(net 208)
	)
	(arc
		(start 193.081299 116.138405)
		(mid 192.969998 116.407107)
		(end 193.081299 116.675807)
		(width 0.13)
		(layer "In2.Cu")
		(net 208)
	)
	(arc
		(start 195.495 115.995)
		(mid 195.335373 116.380373)
		(end 194.95 116.54)
		(width 0.13)
		(layer "In2.Cu")
		(net 208)
	)
	(arc
		(start 194.95 116.54)
		(mid 194.564627 116.380373)
		(end 194.405 115.995)
		(width 0.13)
		(layer "In2.Cu")
		(net 208)
	)
	(arc
		(start 194.405 115.725)
		(mid 194.315668 115.509332)
		(end 194.1 115.42)
		(width 0.13)
		(layer "In2.Cu")
		(net 208)
	)
	(arc
		(start 191.375 122.32)
		(mid 191.123977 122.423977)
		(end 191.02 122.675)
		(width 0.13)
		(layer "In2.Cu")
		(net 208)
	)
	(arc
		(start 193.415735 117.010244)
		(mid 193.597329 117.44865)
		(end 193.415735 117.887056)
		(width 0.13)
		(layer "In2.Cu")
		(net 208)
	)
	(arc
		(start 191.375 120.42)
		(mid 191.123977 120.523977)
		(end 191.02 120.775)
		(width 0.13)
		(layer "In2.Cu")
		(net 208)
	)
	(arc
		(start 193.14 119.825)
		(mid 192.965729 120.245729)
		(end 192.545 120.42)
		(width 0.13)
		(layer "In2.Cu")
		(net 208)
	)
	(arc
		(start 192.545 121.13)
		(mid 192.965729 121.304271)
		(end 193.14 121.725)
		(width 0.13)
		(layer "In2.Cu")
		(net 208)
	)
	(arc
		(start 191.02 118.875)
		(mid 191.123977 119.126023)
		(end 191.375 119.23)
		(width 0.13)
		(layer "In2.Cu")
		(net 208)
	)
	(arc
		(start 191.02 120.775)
		(mid 191.123977 121.026023)
		(end 191.375 121.13)
		(width 0.13)
		(layer "In2.Cu")
		(net 208)
	)
	(segment
		(start 222.75 110.598)
		(end 222.75 111.75)
		(width 0.38)
		(layer "F.Cu")
		(net 209)
	)
	(segment
		(start 196.0005 143.9995)
		(end 196.5 143.5)
		(width 0.256)
		(layer "F.Cu")
		(net 209)
	)
	(via
		(at 196.5 143.5)
		(size 0.45)
		(drill 0.1)
		(layers "F.Cu" "B.Cu")
		(remove_unused_layers yes)
		(keep_end_layers yes)
		(zone_layer_connections)
		(net 209)
	)
	(via
		(at 222.75 111.75)
		(size 0.45)
		(drill 0.1)
		(layers "F.Cu" "B.Cu")
		(remove_unused_layers yes)
		(keep_end_layers yes)
		(zone_layer_connections)
		(net 209)
	)
	(segment
		(start 191.375 121.37)
		(end 192.545 121.37)
		(width 0.13)
		(layer "In2.Cu")
		(net 209)
	)
	(segment
		(start 196.88 129.199706)
		(end 196.88 139.2)
		(width 0.13)
		(layer "In2.Cu")
		(net 209)
	)
	(segment
		(start 191.426669 117.453617)
		(end 191.426669 117.453625)
		(width 0.13)
		(layer "In2.Cu")
		(net 209)
	)
	(segment
		(start 191.375 119.47)
		(end 192.545 119.47)
		(width 0.13)
		(layer "In2.Cu")
		(net 209)
	)
	(segment
		(start 192.545 120.18)
		(end 191.375 120.18)
		(width 0.13)
		(layer "In2.Cu")
		(net 209)
	)
	(segment
		(start 192.708629 117.717352)
		(end 192.374193 117.382916)
		(width 0.13)
		(layer "In2.Cu")
		(net 209)
	)
	(segment
		(start 223.055 112.925294)
		(end 220.800294 115.18)
		(width 0.13)
		(layer "In2.Cu")
		(net 209)
	)
	(segment
		(start 193.700294 115.18)
		(end 193.340147 115.540147)
		(width 0.13)
		(layer "In2.Cu")
		(net 209)
	)
	(segment
		(start 190.78 122.675)
		(end 190.78 123.099706)
		(width 0.13)
		(layer "In2.Cu")
		(net 209)
	)
	(segment
		(start 196.9 143.4)
		(end 196.9 139.22)
		(width 0.1)
		(layer "In2.Cu")
		(net 209)
	)
	(segment
		(start 223.055 112.055)
		(end 223.055 112.925294)
		(width 0.13)
		(layer "In2.Cu")
		(net 209)
	)
	(segment
		(start 193.246032 117.71735)
		(end 193.24603 117.717351)
		(width 0.13)
		(layer "In2.Cu")
		(net 209)
	)
	(segment
		(start 222.75 111.75)
		(end 223.055 112.055)
		(width 0.13)
		(layer "In2.Cu")
		(net 209)
	)
	(segment
		(start 191.497381 117.382916)
		(end 191.497381 117.382915)
		(width 0.13)
		(layer "In2.Cu")
		(net 209)
	)
	(segment
		(start 196.5 143.5)
		(end 196.8 143.5)
		(width 0.1)
		(layer "In2.Cu")
		(net 209)
	)
	(segment
		(start 190.78 118.100294)
		(end 190.78 118.875)
		(width 0.13)
		(layer "In2.Cu")
		(net 209)
	)
	(segment
		(start 191.426669 117.453625)
		(end 190.78 118.100294)
		(width 0.13)
		(layer "In2.Cu")
		(net 209)
	)
	(segment
		(start 192.545 122.08)
		(end 191.375 122.08)
		(width 0.13)
		(layer "In2.Cu")
		(net 209)
	)
	(segment
		(start 220.800294 115.18)
		(end 195.8 115.18)
		(width 0.13)
		(layer "In2.Cu")
		(net 209)
	)
	(segment
		(start 196.9 139.22)
		(end 196.88 139.2)
		(width 0.1)
		(layer "In2.Cu")
		(net 209)
	)
	(segment
		(start 192.70863 117.717352)
		(end 192.708629 117.717352)
		(width 0.13)
		(layer "In2.Cu")
		(net 209)
	)
	(segment
		(start 192.91159 115.968696)
		(end 192.911594 115.9687)
		(width 0.13)
		(layer "In2.Cu")
		(net 209)
	)
	(segment
		(start 191.497381 117.382915)
		(end 191.497379 117.382914)
		(width 0.13)
		(layer "In2.Cu")
		(net 209)
	)
	(segment
		(start 193.24603 117.717351)
		(end 193.246031 117.717351)
		(width 0.13)
		(layer "In2.Cu")
		(net 209)
	)
	(segment
		(start 193.340147 115.540147)
		(end 192.91159 115.968696)
		(width 0.13)
		(layer "In2.Cu")
		(net 209)
	)
	(segment
		(start 191.497379 117.382914)
		(end 191.426669 117.453617)
		(width 0.13)
		(layer "In2.Cu")
		(net 209)
	)
	(segment
		(start 192.911594 116.845512)
		(end 193.246031 117.179949)
		(width 0.13)
		(layer "In2.Cu")
		(net 209)
	)
	(segment
		(start 194.645 115.995)
		(end 194.645 115.725)
		(width 0.13)
		(layer "In2.Cu")
		(net 209)
	)
	(segment
		(start 194.1 115.18)
		(end 193.700294 115.18)
		(width 0.13)
		(layer "In2.Cu")
		(net 209)
	)
	(segment
		(start 195.255 115.725)
		(end 195.255 115.995)
		(width 0.13)
		(layer "In2.Cu")
		(net 209)
	)
	(segment
		(start 190.78 123.099706)
		(end 196.88 129.199706)
		(width 0.13)
		(layer "In2.Cu")
		(net 209)
	)
	(segment
		(start 196.8 143.5)
		(end 196.9 143.4)
		(width 0.1)
		(layer "In2.Cu")
		(net 209)
	)
	(arc
		(start 190.78 120.775)
		(mid 190.954271 121.195729)
		(end 191.375 121.37)
		(width 0.13)
		(layer "In2.Cu")
		(net 209)
	)
	(arc
		(start 192.374193 117.382916)
		(mid 191.935787 117.201322)
		(end 191.497381 117.382916)
		(width 0.13)
		(layer "In2.Cu")
		(net 209)
	)
	(arc
		(start 193.246031 117.717351)
		(mid 192.977331 117.828651)
		(end 192.70863 117.717352)
		(width 0.13)
		(layer "In2.Cu")
		(net 209)
	)
	(arc
		(start 194.95 116.3)
		(mid 194.734332 116.210668)
		(end 194.645 115.995)
		(width 0.13)
		(layer "In2.Cu")
		(net 209)
	)
	(arc
		(start 191.375 120.18)
		(mid 190.954271 120.354271)
		(end 190.78 120.775)
		(width 0.13)
		(layer "In2.Cu")
		(net 209)
	)
	(arc
		(start 195.8 115.18)
		(mid 195.414627 115.339627)
		(end 195.255 115.725)
		(width 0.13)
		(layer "In2.Cu")
		(net 209)
	)
	(arc
		(start 192.9 121.725)
		(mid 192.796023 121.976023)
		(end 192.545 122.08)
		(width 0.13)
		(layer "In2.Cu")
		(net 209)
	)
	(arc
		(start 190.78 118.875)
		(mid 190.954271 119.295729)
		(end 191.375 119.47)
		(width 0.13)
		(layer "In2.Cu")
		(net 209)
	)
	(arc
		(start 192.545 121.37)
		(mid 192.796023 121.473977)
		(end 192.9 121.725)
		(width 0.13)
		(layer "In2.Cu")
		(net 209)
	)
	(arc
		(start 195.255 115.995)
		(mid 195.165668 116.210668)
		(end 194.95 116.3)
		(width 0.13)
		(layer "In2.Cu")
		(net 209)
	)
	(arc
		(start 194.645 115.725)
		(mid 194.485373 115.339627)
		(end 194.1 115.18)
		(width 0.13)
		(layer "In2.Cu")
		(net 209)
	)
	(arc
		(start 192.911594 115.9687)
		(mid 192.73 116.407106)
		(end 192.911594 116.845512)
		(width 0.13)
		(layer "In2.Cu")
		(net 209)
	)
	(arc
		(start 192.545 119.47)
		(mid 192.796023 119.573977)
		(end 192.9 119.825)
		(width 0.13)
		(layer "In2.Cu")
		(net 209)
	)
	(arc
		(start 191.375 122.08)
		(mid 190.954271 122.254271)
		(end 190.78 122.675)
		(width 0.13)
		(layer "In2.Cu")
		(net 209)
	)
	(arc
		(start 192.9 119.825)
		(mid 192.796023 120.076023)
		(end 192.545 120.18)
		(width 0.13)
		(layer "In2.Cu")
		(net 209)
	)
	(arc
		(start 193.246031 117.179949)
		(mid 193.357331 117.448649)
		(end 193.246032 117.71735)
		(width 0.13)
		(layer "In2.Cu")
		(net 209)
	)
	(segment
		(start 164.95 110.598)
		(end 164.95 111.75)
		(width 0.38)
		(layer "F.Cu")
		(net 210)
	)
	(segment
		(start 187.9995 143.9995)
		(end 187.5 143.5)
		(width 0.256)
		(layer "F.Cu")
		(net 210)
	)
	(via
		(at 164.95 111.75)
		(size 0.45)
		(drill 0.1)
		(layers "F.Cu" "B.Cu")
		(remove_unused_layers yes)
		(keep_end_layers yes)
		(zone_layer_connections)
		(net 210)
	)
	(via
		(at 187.5 143.5)
		(size 0.45)
		(drill 0.1)
		(layers "F.Cu" "B.Cu")
		(remove_unused_layers yes)
		(keep_end_layers yes)
		(zone_layer_connections)
		(net 210)
	)
	(segment
		(start 164.95 111.75)
		(end 164.95 118.2)
		(width 0.148)
		(layer "In6.Cu")
		(net 210)
	)
	(segment
		(start 174.306443 127.389878)
		(end 174.306442 127.389877)
		(width 0.148)
		(layer "In6.Cu")
		(net 210)
	)
	(segment
		(start 177.488443 129.511176)
		(end 179.081979 127.917639)
		(width 0.148)
		(layer "In6.Cu")
		(net 210)
	)
	(segment
		(start 181.623637 129.398636)
		(end 181.69387 129.46887)
		(width 0.148)
		(layer "In6.Cu")
		(net 210)
	)
	(segment
		(start 180.5625 129.328404)
		(end 180.632732 129.398636)
		(width 0.148)
		(layer "In6.Cu")
		(net 210)
	)
	(segment
		(start 178.021319 126.856981)
		(end 178.02132 126.85698)
		(width 0.148)
		(layer "In6.Cu")
		(net 210)
	)
	(segment
		(start 175.367103 127.389876)
		(end 175.367102 127.389877)
		(width 0.148)
		(layer "In6.Cu")
		(net 210)
	)
	(segment
		(start 180.562499 128.832953)
		(end 180.5625 128.832952)
		(width 0.148)
		(layer "In6.Cu")
		(net 210)
	)
	(segment
		(start 178.02132 126.85698)
		(end 176.427783 128.450516)
		(width 0.148)
		(layer "In6.Cu")
		(net 210)
	)
	(segment
		(start 177.488444 129.511175)
		(end 177.488443 129.511176)
		(width 0.148)
		(layer "In6.Cu")
		(net 210)
	)
	(segment
		(start 183.975 131.75)
		(end 184.8 131.75)
		(width 0.148)
		(layer "In6.Cu")
		(net 210)
	)
	(segment
		(start 181.69387 129.46887)
		(end 183.975 131.75)
		(width 0.148)
		(layer "In6.Cu")
		(net 210)
	)
	(segment
		(start 188.025 142.725)
		(end 187.5 143.25)
		(width 0.148)
		(layer "In6.Cu")
		(net 210)
	)
	(segment
		(start 188.3 135.25)
		(end 188.3 138.2)
		(width 0.148)
		(layer "In6.Cu")
		(net 210)
	)
	(segment
		(start 188.3 138.2)
		(end 188.5 138.4)
		(width 0.148)
		(layer "In6.Cu")
		(net 210)
	)
	(segment
		(start 188.5 138.4)
		(end 188.5 141.9)
		(width 0.148)
		(layer "In6.Cu")
		(net 210)
	)
	(segment
		(start 164.95 118.2)
		(end 169.975 123.225)
		(width 0.148)
		(layer "In6.Cu")
		(net 210)
	)
	(segment
		(start 175.9 124.73566)
		(end 174.306442 126.329217)
		(width 0.148)
		(layer "In6.Cu")
		(net 210)
	)
	(segment
		(start 169.975 123.225)
		(end 175.45 123.225)
		(width 0.148)
		(layer "In6.Cu")
		(net 210)
	)
	(segment
		(start 187.5 143.25)
		(end 187.5 143.5)
		(width 0.148)
		(layer "In6.Cu")
		(net 210)
	)
	(segment
		(start 181.128185 129.398637)
		(end 181.128185 129.398636)
		(width 0.148)
		(layer "In6.Cu")
		(net 210)
	)
	(segment
		(start 184.8 131.75)
		(end 188.3 135.25)
		(width 0.148)
		(layer "In6.Cu")
		(net 210)
	)
	(segment
		(start 188.025 142.375)
		(end 188.025 142.725)
		(width 0.148)
		(layer "In6.Cu")
		(net 210)
	)
	(segment
		(start 175.367102 127.389877)
		(end 176.960659 125.796319)
		(width 0.148)
		(layer "In6.Cu")
		(net 210)
	)
	(segment
		(start 175.899999 124.735661)
		(end 175.9 124.73566)
		(width 0.148)
		(layer "In6.Cu")
		(net 210)
	)
	(segment
		(start 188.5 141.9)
		(end 188.025 142.375)
		(width 0.148)
		(layer "In6.Cu")
		(net 210)
	)
	(segment
		(start 175.45 123.225)
		(end 175.9 123.675)
		(width 0.148)
		(layer "In6.Cu")
		(net 210)
	)
	(segment
		(start 180.142639 127.917639)
		(end 180.5625 128.3375)
		(width 0.148)
		(layer "In6.Cu")
		(net 210)
	)
	(arc
		(start 180.5625 128.3375)
		(mid 180.665111 128.585227)
		(end 180.562499 128.832953)
		(width 0.148)
		(layer "In6.Cu")
		(net 210)
	)
	(arc
		(start 178.02132 125.79632)
		(mid 178.24099 126.326651)
		(end 178.021319 126.856981)
		(width 0.148)
		(layer "In6.Cu")
		(net 210)
	)
	(arc
		(start 174.306442 127.389877)
		(mid 174.836773 127.609547)
		(end 175.367103 127.389876)
		(width 0.148)
		(layer "In6.Cu")
		(net 210)
	)
	(arc
		(start 181.128185 129.398636)
		(mid 181.375911 129.296025)
		(end 181.623637 129.398636)
		(width 0.148)
		(layer "In6.Cu")
		(net 210)
	)
	(arc
		(start 176.427783 128.450516)
		(mid 176.208113 128.980846)
		(end 176.427783 129.511176)
		(width 0.148)
		(layer "In6.Cu")
		(net 210)
	)
	(arc
		(start 180.632732 129.398636)
		(mid 180.880458 129.501248)
		(end 181.128185 129.398637)
		(width 0.148)
		(layer "In6.Cu")
		(net 210)
	)
	(arc
		(start 174.306442 126.329217)
		(mid 174.086772 126.859548)
		(end 174.306443 127.389878)
		(width 0.148)
		(layer "In6.Cu")
		(net 210)
	)
	(arc
		(start 176.960659 125.796319)
		(mid 177.49099 125.576649)
		(end 178.02132 125.79632)
		(width 0.148)
		(layer "In6.Cu")
		(net 210)
	)
	(arc
		(start 180.5625 128.832952)
		(mid 180.459889 129.080678)
		(end 180.5625 129.328404)
		(width 0.148)
		(layer "In6.Cu")
		(net 210)
	)
	(arc
		(start 179.081979 127.917639)
		(mid 179.612309 127.697969)
		(end 180.142639 127.917639)
		(width 0.148)
		(layer "In6.Cu")
		(net 210)
	)
	(arc
		(start 175.9 123.675)
		(mid 176.11967 124.205331)
		(end 175.899999 124.735661)
		(width 0.148)
		(layer "In6.Cu")
		(net 210)
	)
	(arc
		(start 176.427783 129.511176)
		(mid 176.958114 129.730846)
		(end 177.488444 129.511175)
		(width 0.148)
		(layer "In6.Cu")
		(net 210)
	)
	(segment
		(start 163.25 110.598)
		(end 163.25 111.75)
		(width 0.38)
		(layer "F.Cu")
		(net 211)
	)
	(segment
		(start 187.9995 146.9995)
		(end 187.5 146.5)
		(width 0.256)
		(layer "F.Cu")
		(net 211)
	)
	(via
		(at 163.25 111.75)
		(size 0.45)
		(drill 0.1)
		(layers "F.Cu" "B.Cu")
		(remove_unused_layers yes)
		(keep_end_layers yes)
		(zone_layer_connections)
		(net 211)
	)
	(via
		(at 187.5 146.5)
		(size 0.45)
		(drill 0.1)
		(layers "F.Cu" "B.Cu")
		(remove_unused_layers yes)
		(keep_end_layers yes)
		(zone_layer_connections)
		(net 211)
	)
	(segment
		(start 171.444481 128.608083)
		(end 171.44448 128.608084)
		(width 0.148)
		(layer "In6.Cu")
		(net 211)
	)
	(segment
		(start 172.141392 129.183965)
		(end 172.080875 129.244479)
		(width 0.148)
		(layer "In6.Cu")
		(net 211)
	)
	(segment
		(start 175.457105 133.257105)
		(end 175.575 133.375)
		(width 0.148)
		(layer "In6.Cu")
		(net 211)
	)
	(segment
		(start 175.575 133.375)
		(end 184.7 133.375)
		(width 0.148)
		(layer "In6.Cu")
		(net 211)
	)
	(segment
		(start 168.898896 126.0625)
		(end 168.959421 126.001976)
		(width 0.148)
		(layer "In6.Cu")
		(net 211)
	)
	(segment
		(start 169.535291 127.335291)
		(end 169.535292 127.335292)
		(width 0.148)
		(layer "In6.Cu")
		(net 211)
	)
	(segment
		(start 162.55 120.35)
		(end 168.2625 126.0625)
		(width 0.148)
		(layer "In6.Cu")
		(net 211)
	)
	(segment
		(start 175.492191 132.514915)
		(end 175.492191 132.514916)
		(width 0.148)
		(layer "In6.Cu")
		(net 211)
	)
	(segment
		(start 173.990064 131.153668)
		(end 174.050608 131.093125)
		(width 0.148)
		(layer "In6.Cu")
		(net 211)
	)
	(segment
		(start 173.353667 131.153667)
		(end 173.353668 131.153668)
		(width 0.148)
		(layer "In6.Cu")
		(net 211)
	)
	(segment
		(start 172.717272 129.880876)
		(end 172.777825 129.820324)
		(width 0.148)
		(layer "In6.Cu")
		(net 211)
	)
	(segment
		(start 184.7 133.375)
		(end 187.05 135.725)
		(width 0.148)
		(layer "In6.Cu")
		(net 211)
	)
	(segment
		(start 172.080875 129.880875)
		(end 172.080876 129.880876)
		(width 0.148)
		(layer "In6.Cu")
		(net 211)
	)
	(segment
		(start 173.414221 130.45672)
		(end 173.353667 130.517271)
		(width 0.148)
		(layer "In6.Cu")
		(net 211)
	)
	(segment
		(start 170.868609 127.911164)
		(end 170.808083 127.971687)
		(width 0.148)
		(layer "In6.Cu")
		(net 211)
	)
	(segment
		(start 173.990065 131.153667)
		(end 173.990064 131.153668)
		(width 0.148)
		(layer "In6.Cu")
		(net 211)
	)
	(segment
		(start 175.457106 133.257107)
		(end 175.457105 133.257105)
		(width 0.148)
		(layer "In6.Cu")
		(net 211)
	)
	(segment
		(start 168.898897 126.062499)
		(end 168.898896 126.0625)
		(width 0.148)
		(layer "In6.Cu")
		(net 211)
	)
	(segment
		(start 169.595816 126.638373)
		(end 169.595817 126.638372)
		(width 0.148)
		(layer "In6.Cu")
		(net 211)
	)
	(segment
		(start 174.62646 132.42646)
		(end 174.75 132.55)
		(width 0.148)
		(layer "In6.Cu")
		(net 211)
	)
	(segment
		(start 172.717273 129.880875)
		(end 172.717272 129.880876)
		(width 0.148)
		(layer "In6.Cu")
		(net 211)
	)
	(segment
		(start 169.595817 126.638372)
		(end 169.535291 126.698895)
		(width 0.148)
		(layer "In6.Cu")
		(net 211)
	)
	(segment
		(start 187.05 146.05)
		(end 187.5 146.5)
		(width 0.148)
		(layer "In6.Cu")
		(net 211)
	)
	(segment
		(start 170.171688 127.335292)
		(end 170.232213 127.274768)
		(width 0.148)
		(layer "In6.Cu")
		(net 211)
	)
	(segment
		(start 173.41422 130.456721)
		(end 173.414221 130.45672)
		(width 0.148)
		(layer "In6.Cu")
		(net 211)
	)
	(segment
		(start 171.44448 128.608084)
		(end 171.504996 128.547569)
		(width 0.148)
		(layer "In6.Cu")
		(net 211)
	)
	(segment
		(start 175.49219 132.868468)
		(end 175.457106 132.903553)
		(width 0.148)
		(layer "In6.Cu")
		(net 211)
	)
	(segment
		(start 170.808083 128.608083)
		(end 170.808084 128.608084)
		(width 0.148)
		(layer "In6.Cu")
		(net 211)
	)
	(segment
		(start 187.05 135.725)
		(end 187.05 142.625)
		(width 0.148)
		(layer "In6.Cu")
		(net 211)
	)
	(segment
		(start 175.103553 132.549999)
		(end 175.103554 132.550001)
		(width 0.148)
		(layer "In6.Cu")
		(net 211)
	)
	(segment
		(start 175.103554 132.550001)
		(end 175.138637 132.514915)
		(width 0.148)
		(layer "In6.Cu")
		(net 211)
	)
	(segment
		(start 186 143.4)
		(end 186 144.7)
		(width 0.148)
		(layer "In6.Cu")
		(net 211)
	)
	(segment
		(start 186.4 143)
		(end 186 143.4)
		(width 0.148)
		(layer "In6.Cu")
		(net 211)
	)
	(segment
		(start 186 144.7)
		(end 186.3 145)
		(width 0.148)
		(layer "In6.Cu")
		(net 211)
	)
	(segment
		(start 174.687004 131.729521)
		(end 174.626459 131.790063)
		(width 0.148)
		(layer "In6.Cu")
		(net 211)
	)
	(segment
		(start 186.3 145)
		(end 186.7 145)
		(width 0.148)
		(layer "In6.Cu")
		(net 211)
	)
	(segment
		(start 170.171689 127.335291)
		(end 170.171688 127.335292)
		(width 0.148)
		(layer "In6.Cu")
		(net 211)
	)
	(segment
		(start 186.675 143)
		(end 186.4 143)
		(width 0.148)
		(layer "In6.Cu")
		(net 211)
	)
	(segment
		(start 186.7 145)
		(end 187.05 145.35)
		(width 0.148)
		(layer "In6.Cu")
		(net 211)
	)
	(segment
		(start 174.626459 132.426459)
		(end 174.62646 132.42646)
		(width 0.148)
		(layer "In6.Cu")
		(net 211)
	)
	(segment
		(start 162.55 112.45)
		(end 162.55 120.35)
		(width 0.148)
		(layer "In6.Cu")
		(net 211)
	)
	(segment
		(start 170.868608 127.911165)
		(end 170.868609 127.911164)
		(width 0.148)
		(layer "In6.Cu")
		(net 211)
	)
	(segment
		(start 187.05 145.35)
		(end 187.05 146.05)
		(width 0.148)
		(layer "In6.Cu")
		(net 211)
	)
	(segment
		(start 174.687003 131.729522)
		(end 174.687004 131.729521)
		(width 0.148)
		(layer "In6.Cu")
		(net 211)
	)
	(segment
		(start 163.25 111.75)
		(end 162.55 112.45)
		(width 0.148)
		(layer "In6.Cu")
		(net 211)
	)
	(segment
		(start 187.05 142.625)
		(end 186.675 143)
		(width 0.148)
		(layer "In6.Cu")
		(net 211)
	)
	(segment
		(start 175.49219 132.868469)
		(end 175.49219 132.868468)
		(width 0.148)
		(layer "In6.Cu")
		(net 211)
	)
	(segment
		(start 172.141391 129.183966)
		(end 172.141392 129.183965)
		(width 0.148)
		(layer "In6.Cu")
		(net 211)
	)
	(arc
		(start 172.080876 129.880876)
		(mid 172.399076 130.012679)
		(end 172.717273 129.880875)
		(width 0.148)
		(layer "In6.Cu")
		(net 211)
	)
	(arc
		(start 169.535291 126.698895)
		(mid 169.403489 127.017093)
		(end 169.535291 127.335291)
		(width 0.148)
		(layer "In6.Cu")
		(net 211)
	)
	(arc
		(start 175.457106 132.903553)
		(mid 175.383883 133.08033)
		(end 175.457106 133.257107)
		(width 0.148)
		(layer "In6.Cu")
		(net 211)
	)
	(arc
		(start 174.050608 131.093125)
		(mid 174.368806 130.961323)
		(end 174.687004 131.093125)
		(width 0.148)
		(layer "In6.Cu")
		(net 211)
	)
	(arc
		(start 170.868609 127.274768)
		(mid 171.00041 127.592966)
		(end 170.868608 127.911165)
		(width 0.148)
		(layer "In6.Cu")
		(net 211)
	)
	(arc
		(start 170.808084 128.608084)
		(mid 171.126284 128.739887)
		(end 171.444481 128.608083)
		(width 0.148)
		(layer "In6.Cu")
		(net 211)
	)
	(arc
		(start 175.492191 132.514916)
		(mid 175.565414 132.691693)
		(end 175.49219 132.868469)
		(width 0.148)
		(layer "In6.Cu")
		(net 211)
	)
	(arc
		(start 175.138637 132.514915)
		(mid 175.315414 132.441692)
		(end 175.492191 132.514915)
		(width 0.148)
		(layer "In6.Cu")
		(net 211)
	)
	(arc
		(start 174.75 132.55)
		(mid 174.926777 132.623223)
		(end 175.103553 132.549999)
		(width 0.148)
		(layer "In6.Cu")
		(net 211)
	)
	(arc
		(start 168.2625 126.0625)
		(mid 168.5807 126.194303)
		(end 168.898897 126.062499)
		(width 0.148)
		(layer "In6.Cu")
		(net 211)
	)
	(arc
		(start 168.959421 126.001976)
		(mid 169.277619 125.870174)
		(end 169.595817 126.001976)
		(width 0.148)
		(layer "In6.Cu")
		(net 211)
	)
	(arc
		(start 172.777825 129.820324)
		(mid 173.096023 129.688522)
		(end 173.414221 129.820324)
		(width 0.148)
		(layer "In6.Cu")
		(net 211)
	)
	(arc
		(start 173.353668 131.153668)
		(mid 173.671868 131.285471)
		(end 173.990065 131.153667)
		(width 0.148)
		(layer "In6.Cu")
		(net 211)
	)
	(arc
		(start 172.080875 129.244479)
		(mid 171.949073 129.562677)
		(end 172.080875 129.880875)
		(width 0.148)
		(layer "In6.Cu")
		(net 211)
	)
	(arc
		(start 173.353667 130.517271)
		(mid 173.221865 130.835469)
		(end 173.353667 131.153667)
		(width 0.148)
		(layer "In6.Cu")
		(net 211)
	)
	(arc
		(start 173.414221 129.820324)
		(mid 173.546022 130.138522)
		(end 173.41422 130.456721)
		(width 0.148)
		(layer "In6.Cu")
		(net 211)
	)
	(arc
		(start 170.808083 127.971687)
		(mid 170.676281 128.289885)
		(end 170.808083 128.608083)
		(width 0.148)
		(layer "In6.Cu")
		(net 211)
	)
	(arc
		(start 169.595817 126.001976)
		(mid 169.727618 126.320174)
		(end 169.595816 126.638373)
		(width 0.148)
		(layer "In6.Cu")
		(net 211)
	)
	(arc
		(start 171.504996 128.547569)
		(mid 171.823194 128.415767)
		(end 172.141392 128.547569)
		(width 0.148)
		(layer "In6.Cu")
		(net 211)
	)
	(arc
		(start 170.232213 127.274768)
		(mid 170.550411 127.142966)
		(end 170.868609 127.274768)
		(width 0.148)
		(layer "In6.Cu")
		(net 211)
	)
	(arc
		(start 169.535292 127.335292)
		(mid 169.853492 127.467095)
		(end 170.171689 127.335291)
		(width 0.148)
		(layer "In6.Cu")
		(net 211)
	)
	(arc
		(start 172.141392 128.547569)
		(mid 172.273193 128.865767)
		(end 172.141391 129.183966)
		(width 0.148)
		(layer "In6.Cu")
		(net 211)
	)
	(arc
		(start 174.687004 131.093125)
		(mid 174.818805 131.411323)
		(end 174.687003 131.729522)
		(width 0.148)
		(layer "In6.Cu")
		(net 211)
	)
	(arc
		(start 174.626459 131.790063)
		(mid 174.494657 132.108261)
		(end 174.626459 132.426459)
		(width 0.148)
		(layer "In6.Cu")
		(net 211)
	)
	(segment
		(start 161.55 110.598)
		(end 161.55 111.75)
		(width 0.38)
		(layer "F.Cu")
		(net 212)
	)
	(segment
		(start 183.9995 146.9995)
		(end 183.5 146.5)
		(width 0.256)
		(layer "F.Cu")
		(net 212)
	)
	(via
		(at 161.55 111.75)
		(size 0.45)
		(drill 0.1)
		(layers "F.Cu" "B.Cu")
		(remove_unused_layers yes)
		(keep_end_layers yes)
		(zone_layer_connections)
		(net 212)
	)
	(via
		(at 183.5 146.5)
		(size 0.45)
		(drill 0.1)
		(layers "F.Cu" "B.Cu")
		(remove_unused_layers yes)
		(keep_end_layers yes)
		(zone_layer_connections)
		(net 212)
	)
	(segment
		(start 184.025 148.589272)
		(end 184.025 148.325)
		(width 0.148)
		(layer "In2.Cu")
		(net 212)
	)
	(segment
		(start 188.825 148)
		(end 187.875 148.95)
		(width 0.148)
		(layer "In2.Cu")
		(net 212)
	)
	(segment
		(start 192.3 144.025)
		(end 192.025 144.3)
		(width 0.148)
		(layer "In2.Cu")
		(net 212)
	)
	(segment
		(start 192.025 144.3)
		(end 192.025 147.65)
		(width 0.148)
		(layer "In2.Cu")
		(net 212)
	)
	(segment
		(start 184.025 148.325)
		(end 183.675 147.975)
		(width 0.148)
		(layer "In2.Cu")
		(net 212)
	)
	(segment
		(start 184.55 118.125)
		(end 184.55 123.375)
		(width 0.148)
		(layer "In2.Cu")
		(net 212)
	)
	(segment
		(start 191.675 148)
		(end 188.825 148)
		(width 0.148)
		(layer "In2.Cu")
		(net 212)
	)
	(segment
		(start 163.5 113.725)
		(end 180.15 113.725)
		(width 0.148)
		(layer "In2.Cu")
		(net 212)
	)
	(segment
		(start 183.35 147.975)
		(end 183 147.625)
		(width 0.148)
		(layer "In2.Cu")
		(net 212)
	)
	(segment
		(start 161.55 111.775)
		(end 163.5 113.725)
		(width 0.148)
		(layer "In2.Cu")
		(net 212)
	)
	(segment
		(start 184.385728 148.95)
		(end 184.025 148.589272)
		(width 0.148)
		(layer "In2.Cu")
		(net 212)
	)
	(segment
		(start 187.875 148.95)
		(end 184.385728 148.95)
		(width 0.148)
		(layer "In2.Cu")
		(net 212)
	)
	(segment
		(start 180.15 113.725)
		(end 184.55 118.125)
		(width 0.148)
		(layer "In2.Cu")
		(net 212)
	)
	(segment
		(start 183.675 147.975)
		(end 183.35 147.975)
		(width 0.148)
		(layer "In2.Cu")
		(net 212)
	)
	(segment
		(start 193 143.725)
		(end 192.7 144.025)
		(width 0.148)
		(layer "In2.Cu")
		(net 212)
	)
	(segment
		(start 183 147)
		(end 183.5 146.5)
		(width 0.148)
		(layer "In2.Cu")
		(net 212)
	)
	(segment
		(start 192.025 147.65)
		(end 191.675 148)
		(width 0.148)
		(layer "In2.Cu")
		(net 212)
	)
	(segment
		(start 193 131.825)
		(end 193 143.725)
		(width 0.148)
		(layer "In2.Cu")
		(net 212)
	)
	(segment
		(start 183 147.625)
		(end 183 147)
		(width 0.148)
		(layer "In2.Cu")
		(net 212)
	)
	(segment
		(start 184.55 123.375)
		(end 193 131.825)
		(width 0.148)
		(layer "In2.Cu")
		(net 212)
	)
	(segment
		(start 161.55 111.748)
		(end 161.55 111.775)
		(width 0.148)
		(layer "In2.Cu")
		(net 212)
	)
	(segment
		(start 192.7 144.025)
		(end 192.3 144.025)
		(width 0.148)
		(layer "In2.Cu")
		(net 212)
	)
	(segment
		(start 183.9995 145.9995)
		(end 183.5 145.499999)
		(width 0.256)
		(layer "F.Cu")
		(net 213)
	)
	(segment
		(start 159.85 110.598)
		(end 159.85 109.446)
		(width 0.38)
		(layer "F.Cu")
		(net 213)
	)
	(via
		(at 159.85 109.446)
		(size 0.45)
		(drill 0.1)
		(layers "F.Cu" "B.Cu")
		(remove_unused_layers yes)
		(keep_end_layers yes)
		(zone_layer_connections)
		(net 213)
	)
	(via
		(at 183.5 145.499999)
		(size 0.45)
		(drill 0.1)
		(layers "F.Cu" "B.Cu")
		(remove_unused_layers yes)
		(keep_end_layers yes)
		(zone_layer_connections)
		(net 213)
	)
	(segment
		(start 191.2 143.975)
		(end 191.025 144.15)
		(width 0.148)
		(layer "In2.Cu")
		(net 213)
	)
	(segment
		(start 183.325 118.65)
		(end 183.325 123.5)
		(width 0.148)
		(layer "In2.Cu")
		(net 213)
	)
	(segment
		(start 160.8 112.85)
		(end 162.825 114.875)
		(width 0.148)
		(layer "In2.Cu")
		(net 213)
	)
	(segment
		(start 191.025 144.15)
		(end 191.025 146.741272)
		(width 0.148)
		(layer "In2.Cu")
		(net 213)
	)
	(segment
		(start 183.325 123.5)
		(end 192 132.175)
		(width 0.148)
		(layer "In2.Cu")
		(net 213)
	)
	(segment
		(start 184.35 148)
		(end 184.025 147.675)
		(width 0.148)
		(layer "In2.Cu")
		(net 213)
	)
	(segment
		(start 184.025 147.675)
		(end 184.025 146.024999)
		(width 0.148)
		(layer "In2.Cu")
		(net 213)
	)
	(segment
		(start 159.85 109.446)
		(end 160.8 110.396)
		(width 0.148)
		(layer "In2.Cu")
		(net 213)
	)
	(segment
		(start 191.025 146.741272)
		(end 190.816272 146.95)
		(width 0.148)
		(layer "In2.Cu")
		(net 213)
	)
	(segment
		(start 180.548527 115.873527)
		(end 183.325 118.65)
		(width 0.148)
		(layer "In2.Cu")
		(net 213)
	)
	(segment
		(start 160.8 110.396)
		(end 160.8 112.85)
		(width 0.148)
		(layer "In2.Cu")
		(net 213)
	)
	(segment
		(start 191.75 143.975)
		(end 191.2 143.975)
		(width 0.148)
		(layer "In2.Cu")
		(net 213)
	)
	(segment
		(start 192 143.725)
		(end 191.75 143.975)
		(width 0.148)
		(layer "In2.Cu")
		(net 213)
	)
	(segment
		(start 189.025 146.95)
		(end 187.975 148)
		(width 0.148)
		(layer "In2.Cu")
		(net 213)
	)
	(segment
		(start 184.025 146.024999)
		(end 183.5 145.499999)
		(width 0.148)
		(layer "In2.Cu")
		(net 213)
	)
	(segment
		(start 162.825 114.875)
		(end 179.55 114.875)
		(width 0.148)
		(layer "In2.Cu")
		(net 213)
	)
	(segment
		(start 179.55 114.875)
		(end 179.7 115.025)
		(width 0.148)
		(layer "In2.Cu")
		(net 213)
	)
	(segment
		(start 187.975 148)
		(end 184.35 148)
		(width 0.148)
		(layer "In2.Cu")
		(net 213)
	)
	(segment
		(start 179.699999 115.449265)
		(end 179.483045 115.666218)
		(width 0.148)
		(layer "In2.Cu")
		(net 213)
	)
	(segment
		(start 192 132.175)
		(end 192 143.725)
		(width 0.148)
		(layer "In2.Cu")
		(net 213)
	)
	(segment
		(start 179.90731 116.090481)
		(end 180.124263 115.873527)
		(width 0.148)
		(layer "In2.Cu")
		(net 213)
	)
	(segment
		(start 190.816272 146.95)
		(end 189.025 146.95)
		(width 0.148)
		(layer "In2.Cu")
		(net 213)
	)
	(arc
		(start 180.124263 115.873527)
		(mid 180.336395 115.785659)
		(end 180.548527 115.873527)
		(width 0.148)
		(layer "In2.Cu")
		(net 213)
	)
	(arc
		(start 179.7 115.025)
		(mid 179.787868 115.237133)
		(end 179.699999 115.449265)
		(width 0.148)
		(layer "In2.Cu")
		(net 213)
	)
	(arc
		(start 179.483045 115.666218)
		(mid 179.395177 115.87835)
		(end 179.483045 116.090482)
		(width 0.148)
		(layer "In2.Cu")
		(net 213)
	)
	(arc
		(start 179.483045 116.090482)
		(mid 179.695178 116.17835)
		(end 179.90731 116.090481)
		(width 0.148)
		(layer "In2.Cu")
		(net 213)
	)
	(segment
		(start 214.25 110.598)
		(end 214.25 111.75)
		(width 0.38)
		(layer "F.Cu")
		(net 214)
	)
	(segment
		(start 199.0005 139.9995)
		(end 199.5 139.5)
		(width 0.256)
		(layer "F.Cu")
		(net 214)
	)
	(via
		(at 214.25 111.75)
		(size 0.45)
		(drill 0.1)
		(layers "F.Cu" "B.Cu")
		(remove_unused_layers yes)
		(keep_end_layers yes)
		(zone_layer_connections)
		(net 214)
	)
	(via
		(at 199.5 139.5)
		(size 0.45)
		(drill 0.1)
		(layers "F.Cu" "B.Cu")
		(remove_unused_layers yes)
		(keep_end_layers yes)
		(zone_layer_connections)
		(net 214)
	)
	(segment
		(start 201.570424 124.426757)
		(end 200.663906 123.520239)
		(width 0.13)
		(layer "In6.Cu")
		(net 214)
	)
	(segment
		(start 200.962311 125.982391)
		(end 199.895 127.049706)
		(width 0.13)
		(layer "In6.Cu")
		(net 214)
	)
	(segment
		(start 199.149999 139.499999)
		(end 199.1 139.45)
		(width 0.1)
		(layer "In6.Cu")
		(net 214)
	)
	(segment
		(start 201.611394 122.572679)
		(end 201.611394 122.57268)
		(width 0.13)
		(layer "In6.Cu")
		(net 214)
	)
	(segment
		(start 204.722694 119.46144)
		(end 205.629216 120.367962)
		(width 0.13)
		(layer "In6.Cu")
		(net 214)
	)
	(segment
		(start 204.073581 122.87112)
		(end 204.073582 122.871122)
		(width 0.13)
		(layer "In6.Cu")
		(net 214)
	)
	(segment
		(start 204.681695 121.315487)
		(end 204.681694 121.315487)
		(width 0.13)
		(layer "In6.Cu")
		(net 214)
	)
	(segment
		(start 214.25 111.75)
		(end 214.15 111.75)
		(width 0.13)
		(layer "In6.Cu")
		(net 214)
	)
	(segment
		(start 199.895 127.049706)
		(end 199.895 137.149706)
		(width 0.13)
		(layer "In6.Cu")
		(net 214)
	)
	(segment
		(start 203.167094 121.017109)
		(end 203.167094 121.01711)
		(width 0.13)
		(layer "In6.Cu")
		(net 214)
	)
	(segment
		(start 201.611394 122.57268)
		(end 202.517946 123.479232)
		(width 0.13)
		(layer "In6.Cu")
		(net 214)
	)
	(segment
		(start 206.237329 119.759852)
		(end 205.330806 118.853329)
		(width 0.13)
		(layer "In6.Cu")
		(net 214)
	)
	(segment
		(start 204.681694 121.315487)
		(end 203.775206 120.408999)
		(width 0.13)
		(layer "In6.Cu")
		(net 214)
	)
	(segment
		(start 214.15 111.75)
		(end 213.945 111.955)
		(width 0.13)
		(layer "In6.Cu")
		(net 214)
	)
	(segment
		(start 201.570425 124.426757)
		(end 201.570424 124.426757)
		(width 0.13)
		(layer "In6.Cu")
		(net 214)
	)
	(segment
		(start 199.1 139.45)
		(end 199.1 139.045)
		(width 0.1)
		(layer "In6.Cu")
		(net 214)
	)
	(segment
		(start 206.23733 119.759852)
		(end 206.237329 119.759852)
		(width 0.13)
		(layer "In6.Cu")
		(net 214)
	)
	(segment
		(start 207.624706 119.32)
		(end 207.184852 119.759852)
		(width 0.13)
		(layer "In6.Cu")
		(net 214)
	)
	(segment
		(start 203.167094 121.01711)
		(end 204.073581 121.923597)
		(width 0.13)
		(layer "In6.Cu")
		(net 214)
	)
	(segment
		(start 199.1 139.045)
		(end 199.12 139.025)
		(width 0.1)
		(layer "In6.Cu")
		(net 214)
	)
	(segment
		(start 200.055794 124.128349)
		(end 200.055794 124.12835)
		(width 0.13)
		(layer "In6.Cu")
		(net 214)
	)
	(segment
		(start 202.517946 124.426755)
		(end 202.517947 124.426757)
		(width 0.13)
		(layer "In6.Cu")
		(net 214)
	)
	(segment
		(start 205.629217 121.315485)
		(end 205.629216 121.315486)
		(width 0.13)
		(layer "In6.Cu")
		(net 214)
	)
	(segment
		(start 199.895 137.149706)
		(end 199.12 137.924706)
		(width 0.13)
		(layer "In6.Cu")
		(net 214)
	)
	(segment
		(start 205.629216 121.315486)
		(end 205.629217 121.315487)
		(width 0.13)
		(layer "In6.Cu")
		(net 214)
	)
	(segment
		(start 199.12 137.924706)
		(end 199.12 139.025)
		(width 0.13)
		(layer "In6.Cu")
		(net 214)
	)
	(segment
		(start 200.962312 125.98239)
		(end 200.962311 125.982391)
		(width 0.13)
		(layer "In6.Cu")
		(net 214)
	)
	(segment
		(start 204.722694 119.461439)
		(end 204.722694 119.46144)
		(width 0.13)
		(layer "In6.Cu")
		(net 214)
	)
	(segment
		(start 203.12606 122.871122)
		(end 203.126059 122.871122)
		(width 0.13)
		(layer "In6.Cu")
		(net 214)
	)
	(segment
		(start 209.249706 119.32)
		(end 207.624706 119.32)
		(width 0.13)
		(layer "In6.Cu")
		(net 214)
	)
	(segment
		(start 199.5 139.499999)
		(end 199.149999 139.499999)
		(width 0.1)
		(layer "In6.Cu")
		(net 214)
	)
	(segment
		(start 200.055794 124.12835)
		(end 200.962311 125.034867)
		(width 0.13)
		(layer "In6.Cu")
		(net 214)
	)
	(segment
		(start 204.073582 122.87112)
		(end 204.073581 122.87112)
		(width 0.13)
		(layer "In6.Cu")
		(net 214)
	)
	(segment
		(start 213.945 111.955)
		(end 213.945 114.624706)
		(width 0.13)
		(layer "In6.Cu")
		(net 214)
	)
	(segment
		(start 202.517947 124.426755)
		(end 202.517946 124.426755)
		(width 0.13)
		(layer "In6.Cu")
		(net 214)
	)
	(segment
		(start 213.945 114.624706)
		(end 209.249706 119.32)
		(width 0.13)
		(layer "In6.Cu")
		(net 214)
	)
	(segment
		(start 203.126059 122.871122)
		(end 202.219506 121.964569)
		(width 0.13)
		(layer "In6.Cu")
		(net 214)
	)
	(segment
		(start 200.055795 123.520238)
		(end 200.055794 123.520239)
		(width 0.13)
		(layer "In6.Cu")
		(net 214)
	)
	(arc
		(start 205.629217 121.315487)
		(mid 205.155456 121.511725)
		(end 204.681695 121.315487)
		(width 0.13)
		(layer "In6.Cu")
		(net 214)
	)
	(arc
		(start 202.517947 124.426757)
		(mid 202.044186 124.622995)
		(end 201.570425 124.426757)
		(width 0.13)
		(layer "In6.Cu")
		(net 214)
	)
	(arc
		(start 202.517946 123.479232)
		(mid 202.714185 123.952993)
		(end 202.517947 124.426755)
		(width 0.13)
		(layer "In6.Cu")
		(net 214)
	)
	(arc
		(start 203.775206 120.408999)
		(mid 203.47115 120.283055)
		(end 203.167094 120.408999)
		(width 0.13)
		(layer "In6.Cu")
		(net 214)
	)
	(arc
		(start 201.611394 121.964569)
		(mid 201.48545 122.268624)
		(end 201.611394 122.572679)
		(width 0.13)
		(layer "In6.Cu")
		(net 214)
	)
	(arc
		(start 200.962311 125.034867)
		(mid 201.15855 125.508628)
		(end 200.962312 125.98239)
		(width 0.13)
		(layer "In6.Cu")
		(net 214)
	)
	(arc
		(start 202.219506 121.964569)
		(mid 201.91545 121.838625)
		(end 201.611394 121.964569)
		(width 0.13)
		(layer "In6.Cu")
		(net 214)
	)
	(arc
		(start 200.055794 123.520239)
		(mid 199.92985 123.824294)
		(end 200.055794 124.128349)
		(width 0.13)
		(layer "In6.Cu")
		(net 214)
	)
	(arc
		(start 204.073581 121.923597)
		(mid 204.26982 122.397358)
		(end 204.073582 122.87112)
		(width 0.13)
		(layer "In6.Cu")
		(net 214)
	)
	(arc
		(start 200.663906 123.520239)
		(mid 200.359851 123.394295)
		(end 200.055795 123.520238)
		(width 0.13)
		(layer "In6.Cu")
		(net 214)
	)
	(arc
		(start 204.073582 122.871122)
		(mid 203.599821 123.06736)
		(end 203.12606 122.871122)
		(width 0.13)
		(layer "In6.Cu")
		(net 214)
	)
	(arc
		(start 207.184852 119.759852)
		(mid 206.711091 119.95609)
		(end 206.23733 119.759852)
		(width 0.13)
		(layer "In6.Cu")
		(net 214)
	)
	(arc
		(start 203.167094 120.408999)
		(mid 203.04115 120.713054)
		(end 203.167094 121.017109)
		(width 0.13)
		(layer "In6.Cu")
		(net 214)
	)
	(arc
		(start 204.722694 118.853329)
		(mid 204.59675 119.157384)
		(end 204.722694 119.461439)
		(width 0.13)
		(layer "In6.Cu")
		(net 214)
	)
	(arc
		(start 205.629216 120.367962)
		(mid 205.825455 120.841723)
		(end 205.629217 121.315485)
		(width 0.13)
		(layer "In6.Cu")
		(net 214)
	)
	(arc
		(start 205.330806 118.853329)
		(mid 205.02675 118.727385)
		(end 204.722694 118.853329)
		(width 0.13)
		(layer "In6.Cu")
		(net 214)
	)
	(segment
		(start 255.274499 151.149)
		(end 255.293 151.167501)
		(width 0.177)
		(layer "F.Cu")
		(net 215)
	)
	(segment
		(start 255.293 151.167501)
		(end 255.293 152.1705)
		(width 0.177)
		(layer "F.Cu")
		(net 215)
	)
	(segment
		(start 246.903 144.1)
		(end 247.904 144.1)
		(width 0.256)
		(layer "F.Cu")
		(net 215)
	)
	(via
		(at 255.274499 151.149)
		(size 0.45)
		(drill 0.1)
		(layers "F.Cu" "B.Cu")
		(remove_unused_layers yes)
		(keep_end_layers yes)
		(zone_layer_connections)
		(net 215)
	)
	(via
		(at 247.904 144.1)
		(size 0.45)
		(drill 0.1)
		(layers "F.Cu" "B.Cu")
		(remove_unused_layers yes)
		(keep_end_layers yes)
		(zone_layer_connections)
		(net 215)
	)
	(segment
		(start 255.274499 151.149)
		(end 255.274499 150.216158)
		(width 0.1)
		(layer "In2.Cu")
		(net 215)
	)
	(segment
		(start 248.504 144.7)
		(end 247.904 144.1)
		(width 0.1)
		(layer "In2.Cu")
		(net 215)
	)
	(segment
		(start 249.758341 144.7)
		(end 248.504 144.7)
		(width 0.1)
		(layer "In2.Cu")
		(net 215)
	)
	(segment
		(start 255.274499 150.216158)
		(end 249.758341 144.7)
		(width 0.1)
		(layer "In2.Cu")
		(net 215)
	)
	(segment
		(start 198.0005 139.9995)
		(end 198.5 139.5)
		(width 0.256)
		(layer "F.Cu")
		(net 216)
	)
	(segment
		(start 213.4 110.598)
		(end 213.4 111.75)
		(width 0.38)
		(layer "F.Cu")
		(net 216)
	)
	(via
		(at 198.5 139.5)
		(size 0.45)
		(drill 0.1)
		(layers "F.Cu" "B.Cu")
		(remove_unused_layers yes)
		(keep_end_layers yes)
		(zone_layer_connections)
		(net 216)
	)
	(via
		(at 213.4 111.75)
		(size 0.45)
		(drill 0.1)
		(layers "F.Cu" "B.Cu")
		(remove_unused_layers yes)
		(keep_end_layers yes)
		(zone_layer_connections)
		(net 216)
	)
	(segment
		(start 200.792607 125.812687)
		(end 199.655 126.950294)
		(width 0.13)
		(layer "In6.Cu")
		(net 216)
	)
	(segment
		(start 203.903876 122.701416)
		(end 203.903877 122.701417)
		(width 0.13)
		(layer "In6.Cu")
		(net 216)
	)
	(segment
		(start 199.655 126.950294)
		(end 199.655 137.050294)
		(width 0.13)
		(layer "In6.Cu")
		(net 216)
	)
	(segment
		(start 204.8514 121.145782)
		(end 203.944912 120.239294)
		(width 0.13)
		(layer "In6.Cu")
		(net 216)
	)
	(segment
		(start 198.775 139.5)
		(end 198.9 139.375)
		(width 0.1)
		(layer "In6.Cu")
		(net 216)
	)
	(segment
		(start 200.792605 125.812686)
		(end 200.792607 125.812687)
		(width 0.13)
		(layer "In6.Cu")
		(net 216)
	)
	(segment
		(start 202.348241 124.257051)
		(end 202.348242 124.257052)
		(width 0.13)
		(layer "In6.Cu")
		(net 216)
	)
	(segment
		(start 202.997389 120.239293)
		(end 202.997389 120.239294)
		(width 0.13)
		(layer "In6.Cu")
		(net 216)
	)
	(segment
		(start 200.792606 125.812685)
		(end 200.792605 125.812686)
		(width 0.13)
		(layer "In6.Cu")
		(net 216)
	)
	(segment
		(start 198.9 139.375)
		(end 198.9 139.045)
		(width 0.1)
		(layer "In6.Cu")
		(net 216)
	)
	(segment
		(start 198.5 139.5)
		(end 198.775 139.5)
		(width 0.1)
		(layer "In6.Cu")
		(net 216)
	)
	(segment
		(start 202.997389 121.186817)
		(end 203.903876 122.093304)
		(width 0.13)
		(layer "In6.Cu")
		(net 216)
	)
	(segment
		(start 205.45951 121.145781)
		(end 205.459512 121.145782)
		(width 0.13)
		(layer "In6.Cu")
		(net 216)
	)
	(segment
		(start 213.4 111.75)
		(end 213.425 111.75)
		(width 0.13)
		(layer "In6.Cu")
		(net 216)
	)
	(segment
		(start 198.88 137.825294)
		(end 198.88 139.025)
		(width 0.13)
		(layer "In6.Cu")
		(net 216)
	)
	(segment
		(start 204.552988 119.631147)
		(end 205.45951 120.537669)
		(width 0.13)
		(layer "In6.Cu")
		(net 216)
	)
	(segment
		(start 198.9 139.045)
		(end 198.88 139.025)
		(width 0.1)
		(layer "In6.Cu")
		(net 216)
	)
	(segment
		(start 213.705 114.525294)
		(end 209.150294 119.08)
		(width 0.13)
		(layer "In6.Cu")
		(net 216)
	)
	(segment
		(start 201.441689 121.794863)
		(end 201.441689 121.794864)
		(width 0.13)
		(layer "In6.Cu")
		(net 216)
	)
	(segment
		(start 201.441689 122.742387)
		(end 202.348241 123.648939)
		(width 0.13)
		(layer "In6.Cu")
		(net 216)
	)
	(segment
		(start 201.441689 122.742386)
		(end 201.441689 122.742387)
		(width 0.13)
		(layer "In6.Cu")
		(net 216)
	)
	(segment
		(start 206.407035 119.590147)
		(end 205.500512 118.683624)
		(width 0.13)
		(layer "In6.Cu")
		(net 216)
	)
	(segment
		(start 207.525294 119.08)
		(end 207.015147 119.590147)
		(width 0.13)
		(layer "In6.Cu")
		(net 216)
	)
	(segment
		(start 203.295765 122.701417)
		(end 202.389212 121.794864)
		(width 0.13)
		(layer "In6.Cu")
		(net 216)
	)
	(segment
		(start 199.886089 123.350533)
		(end 199.886088 123.350534)
		(width 0.13)
		(layer "In6.Cu")
		(net 216)
	)
	(segment
		(start 204.552988 119.631146)
		(end 204.552988 119.631147)
		(width 0.13)
		(layer "In6.Cu")
		(net 216)
	)
	(segment
		(start 199.886088 124.298057)
		(end 200.792605 125.204574)
		(width 0.13)
		(layer "In6.Cu")
		(net 216)
	)
	(segment
		(start 213.425 111.75)
		(end 213.705 112.03)
		(width 0.13)
		(layer "In6.Cu")
		(net 216)
	)
	(segment
		(start 213.705 112.03)
		(end 213.705 114.525294)
		(width 0.13)
		(layer "In6.Cu")
		(net 216)
	)
	(segment
		(start 202.997389 121.186816)
		(end 202.997389 121.186817)
		(width 0.13)
		(layer "In6.Cu")
		(net 216)
	)
	(segment
		(start 199.655 137.050294)
		(end 198.88 137.825294)
		(width 0.13)
		(layer "In6.Cu")
		(net 216)
	)
	(segment
		(start 201.74013 124.257052)
		(end 200.833612 123.350534)
		(width 0.13)
		(layer "In6.Cu")
		(net 216)
	)
	(segment
		(start 199.886088 124.298056)
		(end 199.886088 124.298057)
		(width 0.13)
		(layer "In6.Cu")
		(net 216)
	)
	(segment
		(start 204.552989 118.683623)
		(end 204.552988 118.683624)
		(width 0.13)
		(layer "In6.Cu")
		(net 216)
	)
	(segment
		(start 209.150294 119.08)
		(end 207.525294 119.08)
		(width 0.13)
		(layer "In6.Cu")
		(net 216)
	)
	(arc
		(start 202.348242 124.257052)
		(mid 202.044186 124.382996)
		(end 201.74013 124.257052)
		(width 0.13)
		(layer "In6.Cu")
		(net 216)
	)
	(arc
		(start 205.459512 121.145782)
		(mid 205.155456 121.271726)
		(end 204.8514 121.145782)
		(width 0.13)
		(layer "In6.Cu")
		(net 216)
	)
	(arc
		(start 203.944912 120.239294)
		(mid 203.471151 120.043055)
		(end 202.997389 120.239293)
		(width 0.13)
		(layer "In6.Cu")
		(net 216)
	)
	(arc
		(start 200.833612 123.350534)
		(mid 200.359851 123.154295)
		(end 199.886089 123.350533)
		(width 0.13)
		(layer "In6.Cu")
		(net 216)
	)
	(arc
		(start 202.348241 123.648939)
		(mid 202.474185 123.952995)
		(end 202.348241 124.257051)
		(width 0.13)
		(layer "In6.Cu")
		(net 216)
	)
	(arc
		(start 203.903877 122.701417)
		(mid 203.599821 122.827361)
		(end 203.295765 122.701417)
		(width 0.13)
		(layer "In6.Cu")
		(net 216)
	)
	(arc
		(start 207.015147 119.590147)
		(mid 206.711091 119.716091)
		(end 206.407035 119.590147)
		(width 0.13)
		(layer "In6.Cu")
		(net 216)
	)
	(arc
		(start 203.903876 122.093304)
		(mid 204.02982 122.39736)
		(end 203.903876 122.701416)
		(width 0.13)
		(layer "In6.Cu")
		(net 216)
	)
	(arc
		(start 202.389212 121.794864)
		(mid 201.915451 121.598625)
		(end 201.441689 121.794863)
		(width 0.13)
		(layer "In6.Cu")
		(net 216)
	)
	(arc
		(start 200.792605 125.204574)
		(mid 200.918549 125.508629)
		(end 200.792606 125.812685)
		(width 0.13)
		(layer "In6.Cu")
		(net 216)
	)
	(arc
		(start 205.500512 118.683624)
		(mid 205.026751 118.487385)
		(end 204.552989 118.683623)
		(width 0.13)
		(layer "In6.Cu")
		(net 216)
	)
	(arc
		(start 202.997389 120.239294)
		(mid 202.801151 120.713055)
		(end 202.997389 121.186816)
		(width 0.13)
		(layer "In6.Cu")
		(net 216)
	)
	(arc
		(start 199.886088 123.350534)
		(mid 199.68985 123.824295)
		(end 199.886088 124.298056)
		(width 0.13)
		(layer "In6.Cu")
		(net 216)
	)
	(arc
		(start 204.552988 118.683624)
		(mid 204.35675 119.157385)
		(end 204.552988 119.631146)
		(width 0.13)
		(layer "In6.Cu")
		(net 216)
	)
	(arc
		(start 201.441689 121.794864)
		(mid 201.245451 122.268625)
		(end 201.441689 122.742386)
		(width 0.13)
		(layer "In6.Cu")
		(net 216)
	)
	(arc
		(start 205.45951 120.537669)
		(mid 205.585454 120.841725)
		(end 205.45951 121.145781)
		(width 0.13)
		(layer "In6.Cu")
		(net 216)
	)
	(segment
		(start 155.6 110.598)
		(end 155.6 111.75)
		(width 0.38)
		(layer "F.Cu")
		(net 217)
	)
	(segment
		(start 185.9995 145.9995)
		(end 185.5 145.5)
		(width 0.256)
		(layer "F.Cu")
		(net 217)
	)
	(via
		(at 185.5 145.5)
		(size 0.45)
		(drill 0.1)
		(layers "F.Cu" "B.Cu")
		(remove_unused_layers yes)
		(keep_end_layers yes)
		(zone_layer_connections)
		(net 217)
	)
	(via
		(at 155.6 111.75)
		(size 0.45)
		(drill 0.1)
		(layers "F.Cu" "B.Cu")
		(remove_unused_layers yes)
		(keep_end_layers yes)
		(zone_layer_connections)
		(net 217)
	)
	(segment
		(start 186 143.2)
		(end 186.2 143)
		(width 0.148)
		(layer "In2.Cu")
		(net 217)
	)
	(segment
		(start 186 143.7)
		(end 186 143.2)
		(width 0.148)
		(layer "In2.Cu")
		(net 217)
	)
	(segment
		(start 162.5 122.85)
		(end 161.7 122.85)
		(width 0.148)
		(layer "In2.Cu")
		(net 217)
	)
	(segment
		(start 188.05 139.125)
		(end 187.75 138.825)
		(width 0.148)
		(layer "In2.Cu")
		(net 217)
	)
	(segment
		(start 157.107355 118.307355)
		(end 157.107356 118.307356)
		(width 0.148)
		(layer "In2.Cu")
		(net 217)
	)
	(segment
		(start 156.577024 118.307355)
		(end 156.452321 118.432059)
		(width 0.148)
		(layer "In2.Cu")
		(net 217)
	)
	(segment
		(start 158.043297 120.023064)
		(end 158.168016 119.898346)
		(width 0.148)
		(layer "In2.Cu")
		(net 217)
	)
	(segment
		(start 159.10394 121.083743)
		(end 159.228677 120.959007)
		(width 0.148)
		(layer "In2.Cu")
		(net 217)
	)
	(segment
		(start 157.637686 119.368016)
		(end 157.637685 119.368016)
		(width 0.148)
		(layer "In2.Cu")
		(net 217)
	)
	(segment
		(start 174.85 122.85)
		(end 174.5 122.85)
		(width 0.148)
		(layer "In2.Cu")
		(net 217)
	)
	(segment
		(start 157.637685 119.368016)
		(end 157.51294 119.492762)
		(width 0.148)
		(layer "In2.Cu")
		(net 217)
	)
	(segment
		(start 165.875 123.475)
		(end 165.875 123.225)
		(width 0.148)
		(layer "In2.Cu")
		(net 217)
	)
	(segment
		(start 173.375 123.475)
		(end 173.375 123.225)
		(width 0.148)
		(layer "In2.Cu")
		(net 217)
	)
	(segment
		(start 156.046693 117.246693)
		(end 155.6 116.8)
		(width 0.148)
		(layer "In2.Cu")
		(net 217)
	)
	(segment
		(start 165.125 123.225)
		(end 165.125 123.475)
		(width 0.148)
		(layer "In2.Cu")
		(net 217)
	)
	(segment
		(start 170.375 123.475)
		(end 170.375 123.225)
		(width 0.148)
		(layer "In2.Cu")
		(net 217)
	)
	(segment
		(start 155.921991 118.432059)
		(end 155.921989 118.432058)
		(width 0.148)
		(layer "In2.Cu")
		(net 217)
	)
	(segment
		(start 186.7 143)
		(end 188.05 141.65)
		(width 0.148)
		(layer "In2.Cu")
		(net 217)
	)
	(segment
		(start 158.698346 120.428677)
		(end 158.573628 120.553396)
		(width 0.148)
		(layer "In2.Cu")
		(net 217)
	)
	(segment
		(start 164.375 123.475)
		(end 164.375 123.225)
		(width 0.148)
		(layer "In2.Cu")
		(net 217)
	)
	(segment
		(start 174.125 123.225)
		(end 174.125 123.475)
		(width 0.148)
		(layer "In2.Cu")
		(net 217)
	)
	(segment
		(start 185.7 144)
		(end 186 143.7)
		(width 0.148)
		(layer "In2.Cu")
		(net 217)
	)
	(segment
		(start 158.168016 119.368016)
		(end 158.168017 119.368017)
		(width 0.148)
		(layer "In2.Cu")
		(net 217)
	)
	(segment
		(start 156.046692 117.246693)
		(end 156.046693 117.246693)
		(width 0.148)
		(layer "In2.Cu")
		(net 217)
	)
	(segment
		(start 171.875 123.475)
		(end 171.875 123.225)
		(width 0.148)
		(layer "In2.Cu")
		(net 217)
	)
	(segment
		(start 171.125 123.225)
		(end 171.125 123.475)
		(width 0.148)
		(layer "In2.Cu")
		(net 217)
	)
	(segment
		(start 187.75 138.825)
		(end 187.75 135.75)
		(width 0.148)
		(layer "In2.Cu")
		(net 217)
	)
	(segment
		(start 161.7 122.85)
		(end 161.65 122.85)
		(width 0.148)
		(layer "In2.Cu")
		(net 217)
	)
	(segment
		(start 185.4 144)
		(end 185.7 144)
		(width 0.148)
		(layer "In2.Cu")
		(net 217)
	)
	(segment
		(start 168.125 123.225)
		(end 168.125 123.475)
		(width 0.148)
		(layer "In2.Cu")
		(net 217)
	)
	(segment
		(start 158.698347 120.428677)
		(end 158.698346 120.428677)
		(width 0.148)
		(layer "In2.Cu")
		(net 217)
	)
	(segment
		(start 185 144.4)
		(end 185.4 144)
		(width 0.148)
		(layer "In2.Cu")
		(net 217)
	)
	(segment
		(start 160.819668 122.549999)
		(end 160.694923 122.674745)
		(width 0.148)
		(layer "In2.Cu")
		(net 217)
	)
	(segment
		(start 159.10394 121.083744)
		(end 159.10394 121.083743)
		(width 0.148)
		(layer "In2.Cu")
		(net 217)
	)
	(segment
		(start 167.375 123.475)
		(end 167.375 123.225)
		(width 0.148)
		(layer "In2.Cu")
		(net 217)
	)
	(segment
		(start 160.164592 122.144414)
		(end 160.164592 122.144413)
		(width 0.148)
		(layer "In2.Cu")
		(net 217)
	)
	(segment
		(start 172.625 123.225)
		(end 172.625 123.475)
		(width 0.148)
		(layer "In2.Cu")
		(net 217)
	)
	(segment
		(start 187.75 135.75)
		(end 174.85 122.85)
		(width 0.148)
		(layer "In2.Cu")
		(net 217)
	)
	(segment
		(start 159.759007 121.489338)
		(end 159.634271 121.614075)
		(width 0.148)
		(layer "In2.Cu")
		(net 217)
	)
	(segment
		(start 156.982609 118.96243)
		(end 157.107355 118.837685)
		(width 0.148)
		(layer "In2.Cu")
		(net 217)
	)
	(segment
		(start 160.289338 121.489338)
		(end 160.289339 121.489339)
		(width 0.148)
		(layer "In2.Cu")
		(net 217)
	)
	(segment
		(start 159.228677 120.428677)
		(end 159.228678 120.428678)
		(width 0.148)
		(layer "In2.Cu")
		(net 217)
	)
	(segment
		(start 169.625 123.225)
		(end 169.625 123.475)
		(width 0.148)
		(layer "In2.Cu")
		(net 217)
	)
	(segment
		(start 161.65 122.85)
		(end 161.35 122.55)
		(width 0.148)
		(layer "In2.Cu")
		(net 217)
	)
	(segment
		(start 188.05 141.65)
		(end 188.05 139.125)
		(width 0.148)
		(layer "In2.Cu")
		(net 217)
	)
	(segment
		(start 155.92199 117.901728)
		(end 156.046692 117.777023)
		(width 0.148)
		(layer "In2.Cu")
		(net 217)
	)
	(segment
		(start 162.875 123.475)
		(end 162.875 123.225)
		(width 0.148)
		(layer "In2.Cu")
		(net 217)
	)
	(segment
		(start 185.5 145.5)
		(end 185 145)
		(width 0.148)
		(layer "In2.Cu")
		(net 217)
	)
	(segment
		(start 158.043297 120.023065)
		(end 158.043297 120.023064)
		(width 0.148)
		(layer "In2.Cu")
		(net 217)
	)
	(segment
		(start 185 145)
		(end 185 144.4)
		(width 0.148)
		(layer "In2.Cu")
		(net 217)
	)
	(segment
		(start 166.625 123.225)
		(end 166.625 123.475)
		(width 0.148)
		(layer "In2.Cu")
		(net 217)
	)
	(segment
		(start 156.982609 118.962431)
		(end 156.982609 118.96243)
		(width 0.148)
		(layer "In2.Cu")
		(net 217)
	)
	(segment
		(start 156.577025 118.307355)
		(end 156.577024 118.307355)
		(width 0.148)
		(layer "In2.Cu")
		(net 217)
	)
	(segment
		(start 155.921988 117.901727)
		(end 155.92199 117.901728)
		(width 0.148)
		(layer "In2.Cu")
		(net 217)
	)
	(segment
		(start 160.819669 122.549999)
		(end 160.819668 122.549999)
		(width 0.148)
		(layer "In2.Cu")
		(net 217)
	)
	(segment
		(start 163.625 123.225)
		(end 163.625 123.475)
		(width 0.148)
		(layer "In2.Cu")
		(net 217)
	)
	(segment
		(start 155.6 116.8)
		(end 155.6 111.748)
		(width 0.148)
		(layer "In2.Cu")
		(net 217)
	)
	(segment
		(start 159.759008 121.489338)
		(end 159.759007 121.489338)
		(width 0.148)
		(layer "In2.Cu")
		(net 217)
	)
	(segment
		(start 168.875 123.475)
		(end 168.875 123.225)
		(width 0.148)
		(layer "In2.Cu")
		(net 217)
	)
	(segment
		(start 160.164592 122.144413)
		(end 160.289338 122.019668)
		(width 0.148)
		(layer "In2.Cu")
		(net 217)
	)
	(segment
		(start 186.2 143)
		(end 186.7 143)
		(width 0.148)
		(layer "In2.Cu")
		(net 217)
	)
	(arc
		(start 173 122.85)
		(mid 172.734835 122.959835)
		(end 172.625 123.225)
		(width 0.148)
		(layer "In2.Cu")
		(net 217)
	)
	(arc
		(start 157.51294 119.492762)
		(mid 157.247775 119.602597)
		(end 156.98261 119.492762)
		(width 0.148)
		(layer "In2.Cu")
		(net 217)
	)
	(arc
		(start 160.694923 122.674745)
		(mid 160.429758 122.78458)
		(end 160.164593 122.674745)
		(width 0.148)
		(layer "In2.Cu")
		(net 217)
	)
	(arc
		(start 174.5 122.85)
		(mid 174.234835 122.959835)
		(end 174.125 123.225)
		(width 0.148)
		(layer "In2.Cu")
		(net 217)
	)
	(arc
		(start 173.375 123.225)
		(mid 173.265165 122.959835)
		(end 173 122.85)
		(width 0.148)
		(layer "In2.Cu")
		(net 217)
	)
	(arc
		(start 169.25 123.85)
		(mid 168.984835 123.740165)
		(end 168.875 123.475)
		(width 0.148)
		(layer "In2.Cu")
		(net 217)
	)
	(arc
		(start 155.921989 118.432058)
		(mid 155.812154 118.166894)
		(end 155.921988 117.901727)
		(width 0.148)
		(layer "In2.Cu")
		(net 217)
	)
	(arc
		(start 170 122.85)
		(mid 169.734835 122.959835)
		(end 169.625 123.225)
		(width 0.148)
		(layer "In2.Cu")
		(net 217)
	)
	(arc
		(start 165.875 123.225)
		(mid 165.765165 122.959835)
		(end 165.5 122.85)
		(width 0.148)
		(layer "In2.Cu")
		(net 217)
	)
	(arc
		(start 159.103941 121.614075)
		(mid 158.994104 121.348909)
		(end 159.10394 121.083744)
		(width 0.148)
		(layer "In2.Cu")
		(net 217)
	)
	(arc
		(start 174.125 123.475)
		(mid 174.015165 123.740165)
		(end 173.75 123.85)
		(width 0.148)
		(layer "In2.Cu")
		(net 217)
	)
	(arc
		(start 159.228677 120.959007)
		(mid 159.338512 120.693842)
		(end 159.228677 120.428677)
		(width 0.148)
		(layer "In2.Cu")
		(net 217)
	)
	(arc
		(start 164 122.85)
		(mid 163.734835 122.959835)
		(end 163.625 123.225)
		(width 0.148)
		(layer "In2.Cu")
		(net 217)
	)
	(arc
		(start 173.75 123.85)
		(mid 173.484835 123.740165)
		(end 173.375 123.475)
		(width 0.148)
		(layer "In2.Cu")
		(net 217)
	)
	(arc
		(start 161.35 122.55)
		(mid 161.084834 122.440163)
		(end 160.819669 122.549999)
		(width 0.148)
		(layer "In2.Cu")
		(net 217)
	)
	(arc
		(start 171.875 123.225)
		(mid 171.765165 122.959835)
		(end 171.5 122.85)
		(width 0.148)
		(layer "In2.Cu")
		(net 217)
	)
	(arc
		(start 168.125 123.475)
		(mid 168.015165 123.740165)
		(end 167.75 123.85)
		(width 0.148)
		(layer "In2.Cu")
		(net 217)
	)
	(arc
		(start 158.043298 120.553396)
		(mid 157.933461 120.28823)
		(end 158.043297 120.023065)
		(width 0.148)
		(layer "In2.Cu")
		(net 217)
	)
	(arc
		(start 157.107355 118.837685)
		(mid 157.21719 118.57252)
		(end 157.107355 118.307355)
		(width 0.148)
		(layer "In2.Cu")
		(net 217)
	)
	(arc
		(start 167 122.85)
		(mid 166.734835 122.959835)
		(end 166.625 123.225)
		(width 0.148)
		(layer "In2.Cu")
		(net 217)
	)
	(arc
		(start 163.625 123.475)
		(mid 163.515165 123.740165)
		(end 163.25 123.85)
		(width 0.148)
		(layer "In2.Cu")
		(net 217)
	)
	(arc
		(start 162.875 123.225)
		(mid 162.765165 122.959835)
		(end 162.5 122.85)
		(width 0.148)
		(layer "In2.Cu")
		(net 217)
	)
	(arc
		(start 159.634271 121.614075)
		(mid 159.369106 121.72391)
		(end 159.103941 121.614075)
		(width 0.148)
		(layer "In2.Cu")
		(net 217)
	)
	(arc
		(start 170.75 123.85)
		(mid 170.484835 123.740165)
		(end 170.375 123.475)
		(width 0.148)
		(layer "In2.Cu")
		(net 217)
	)
	(arc
		(start 166.25 123.85)
		(mid 165.984835 123.740165)
		(end 165.875 123.475)
		(width 0.148)
		(layer "In2.Cu")
		(net 217)
	)
	(arc
		(start 169.625 123.475)
		(mid 169.515165 123.740165)
		(end 169.25 123.85)
		(width 0.148)
		(layer "In2.Cu")
		(net 217)
	)
	(arc
		(start 168.5 122.85)
		(mid 168.234835 122.959835)
		(end 168.125 123.225)
		(width 0.148)
		(layer "In2.Cu")
		(net 217)
	)
	(arc
		(start 172.25 123.85)
		(mid 171.984835 123.740165)
		(end 171.875 123.475)
		(width 0.148)
		(layer "In2.Cu")
		(net 217)
	)
	(arc
		(start 171.5 122.85)
		(mid 171.234835 122.959835)
		(end 171.125 123.225)
		(width 0.148)
		(layer "In2.Cu")
		(net 217)
	)
	(arc
		(start 171.125 123.475)
		(mid 171.015165 123.740165)
		(end 170.75 123.85)
		(width 0.148)
		(layer "In2.Cu")
		(net 217)
	)
	(arc
		(start 168.875 123.225)
		(mid 168.765165 122.959835)
		(end 168.5 122.85)
		(width 0.148)
		(layer "In2.Cu")
		(net 217)
	)
	(arc
		(start 163.25 123.85)
		(mid 162.984835 123.740165)
		(end 162.875 123.475)
		(width 0.148)
		(layer "In2.Cu")
		(net 217)
	)
	(arc
		(start 160.164593 122.674745)
		(mid 160.054756 122.409579)
		(end 160.164592 122.144414)
		(width 0.148)
		(layer "In2.Cu")
		(net 217)
	)
	(arc
		(start 159.228678 120.428678)
		(mid 158.963512 120.318841)
		(end 158.698347 120.428677)
		(width 0.148)
		(layer "In2.Cu")
		(net 217)
	)
	(arc
		(start 170.375 123.225)
		(mid 170.265165 122.959835)
		(end 170 122.85)
		(width 0.148)
		(layer "In2.Cu")
		(net 217)
	)
	(arc
		(start 160.289339 121.489339)
		(mid 160.024173 121.379502)
		(end 159.759008 121.489338)
		(width 0.148)
		(layer "In2.Cu")
		(net 217)
	)
	(arc
		(start 156.046692 117.777023)
		(mid 156.156527 117.511858)
		(end 156.046692 117.246693)
		(width 0.148)
		(layer "In2.Cu")
		(net 217)
	)
	(arc
		(start 156.98261 119.492762)
		(mid 156.872773 119.227596)
		(end 156.982609 118.962431)
		(width 0.148)
		(layer "In2.Cu")
		(net 217)
	)
	(arc
		(start 164.375 123.225)
		(mid 164.265165 122.959835)
		(end 164 122.85)
		(width 0.148)
		(layer "In2.Cu")
		(net 217)
	)
	(arc
		(start 167.75 123.85)
		(mid 167.484835 123.740165)
		(end 167.375 123.475)
		(width 0.148)
		(layer "In2.Cu")
		(net 217)
	)
	(arc
		(start 157.107356 118.307356)
		(mid 156.84219 118.197519)
		(end 156.577025 118.307355)
		(width 0.148)
		(layer "In2.Cu")
		(net 217)
	)
	(arc
		(start 165.125 123.475)
		(mid 165.015165 123.740165)
		(end 164.75 123.85)
		(width 0.148)
		(layer "In2.Cu")
		(net 217)
	)
	(arc
		(start 158.573628 120.553396)
		(mid 158.308463 120.663231)
		(end 158.043298 120.553396)
		(width 0.148)
		(layer "In2.Cu")
		(net 217)
	)
	(arc
		(start 165.5 122.85)
		(mid 165.234835 122.959835)
		(end 165.125 123.225)
		(width 0.148)
		(layer "In2.Cu")
		(net 217)
	)
	(arc
		(start 166.625 123.475)
		(mid 166.515165 123.740165)
		(end 166.25 123.85)
		(width 0.148)
		(layer "In2.Cu")
		(net 217)
	)
	(arc
		(start 164.75 123.85)
		(mid 164.484835 123.740165)
		(end 164.375 123.475)
		(width 0.148)
		(layer "In2.Cu")
		(net 217)
	)
	(arc
		(start 160.289338 122.019668)
		(mid 160.399173 121.754503)
		(end 160.289338 121.489338)
		(width 0.148)
		(layer "In2.Cu")
		(net 217)
	)
	(arc
		(start 158.168017 119.368017)
		(mid 157.902851 119.25818)
		(end 157.637686 119.368016)
		(width 0.148)
		(layer "In2.Cu")
		(net 217)
	)
	(arc
		(start 172.625 123.475)
		(mid 172.515165 123.740165)
		(end 172.25 123.85)
		(width 0.148)
		(layer "In2.Cu")
		(net 217)
	)
	(arc
		(start 158.168016 119.898346)
		(mid 158.277851 119.633181)
		(end 158.168016 119.368016)
		(width 0.148)
		(layer "In2.Cu")
		(net 217)
	)
	(arc
		(start 167.375 123.225)
		(mid 167.265165 122.959835)
		(end 167 122.85)
		(width 0.148)
		(layer "In2.Cu")
		(net 217)
	)
	(arc
		(start 156.452321 118.432059)
		(mid 156.187156 118.541894)
		(end 155.921991 118.432059)
		(width 0.148)
		(layer "In2.Cu")
		(net 217)
	)
	(segment
		(start 153.9 110.598)
		(end 153.9 111.75)
		(width 0.38)
		(layer "F.Cu")
		(net 218)
	)
	(segment
		(start 183.9995 144.9995)
		(end 183.5 144.500001)
		(width 0.256)
		(layer "F.Cu")
		(net 218)
	)
	(via
		(at 183.5 144.500001)
		(size 0.45)
		(drill 0.1)
		(layers "F.Cu" "B.Cu")
		(remove_unused_layers yes)
		(keep_end_layers yes)
		(zone_layer_connections)
		(net 218)
	)
	(via
		(at 153.9 111.75)
		(size 0.45)
		(drill 0.1)
		(layers "F.Cu" "B.Cu")
		(remove_unused_layers yes)
		(keep_end_layers yes)
		(zone_layer_connections)
		(net 218)
	)
	(segment
		(start 161.4 127.8)
		(end 161.4 131.202992)
		(width 0.148)
		(layer "In2.Cu")
		(net 218)
	)
	(segment
		(start 185 137.025)
		(end 180.4375 132.4625)
		(width 0.148)
		(layer "In2.Cu")
		(net 218)
	)
	(segment
		(start 183.5 144.500001)
		(end 183 144.000001)
		(width 0.148)
		(layer "In2.Cu")
		(net 218)
	)
	(segment
		(start 184.7 140)
		(end 185 139.7)
		(width 0.148)
		(layer "In2.Cu")
		(net 218)
	)
	(segment
		(start 183.5 141.899)
		(end 183.751 141.899)
		(width 0.148)
		(layer "In2.Cu")
		(net 218)
	)
	(segment
		(start 152 113.648)
		(end 153.9 111.748)
		(width 0.148)
		(layer "In2.Cu")
		(net 218)
	)
	(segment
		(start 168.75 127.3)
		(end 163.9 127.3)
		(width 0.148)
		(layer "In2.Cu")
		(net 218)
	)
	(segment
		(start 185 139.7)
		(end 185 137.025)
		(width 0.148)
		(layer "In2.Cu")
		(net 218)
	)
	(segment
		(start 159.65 127.3)
		(end 152 119.65)
		(width 0.148)
		(layer "In2.Cu")
		(net 218)
	)
	(segment
		(start 152 119.65)
		(end 152 113.648)
		(width 0.148)
		(layer "In2.Cu")
		(net 218)
	)
	(segment
		(start 184.375 140)
		(end 184.7 140)
		(width 0.148)
		(layer "In2.Cu")
		(net 218)
	)
	(segment
		(start 183.751 141.899)
		(end 184 141.65)
		(width 0.148)
		(layer "In2.Cu")
		(net 218)
	)
	(segment
		(start 162.4 131.203011)
		(end 162.4 127.8)
		(width 0.148)
		(layer "In2.Cu")
		(net 218)
	)
	(segment
		(start 159.9 127.3)
		(end 159.65 127.3)
		(width 0.148)
		(layer "In2.Cu")
		(net 218)
	)
	(segment
		(start 183 144.000001)
		(end 183 142.399)
		(width 0.148)
		(layer "In2.Cu")
		(net 218)
	)
	(segment
		(start 163.4 127.8)
		(end 163.4 131.203011)
		(width 0.148)
		(layer "In2.Cu")
		(net 218)
	)
	(segment
		(start 173.9125 132.4625)
		(end 168.75 127.3)
		(width 0.148)
		(layer "In2.Cu")
		(net 218)
	)
	(segment
		(start 184 140.375)
		(end 184.375 140)
		(width 0.148)
		(layer "In2.Cu")
		(net 218)
	)
	(segment
		(start 184 141.65)
		(end 184 140.375)
		(width 0.148)
		(layer "In2.Cu")
		(net 218)
	)
	(segment
		(start 183 142.399)
		(end 183.5 141.899)
		(width 0.148)
		(layer "In2.Cu")
		(net 218)
	)
	(segment
		(start 180.4375 132.4625)
		(end 173.9125 132.4625)
		(width 0.148)
		(layer "In2.Cu")
		(net 218)
	)
	(segment
		(start 160.4 131.202992)
		(end 160.4 127.8)
		(width 0.148)
		(layer "In2.Cu")
		(net 218)
	)
	(arc
		(start 161.4 131.202992)
		(mid 161.253553 131.556545)
		(end 160.9 131.702992)
		(width 0.148)
		(layer "In2.Cu")
		(net 218)
	)
	(arc
		(start 160.9 131.702992)
		(mid 160.546447 131.556545)
		(end 160.4 131.202992)
		(width 0.148)
		(layer "In2.Cu")
		(net 218)
	)
	(arc
		(start 163.9 127.3)
		(mid 163.546447 127.446447)
		(end 163.4 127.8)
		(width 0.148)
		(layer "In2.Cu")
		(net 218)
	)
	(arc
		(start 161.9 127.3)
		(mid 161.546447 127.446447)
		(end 161.4 127.8)
		(width 0.148)
		(layer "In2.Cu")
		(net 218)
	)
	(arc
		(start 160.4 127.8)
		(mid 160.253553 127.446447)
		(end 159.9 127.3)
		(width 0.148)
		(layer "In2.Cu")
		(net 218)
	)
	(arc
		(start 162.9 131.703011)
		(mid 162.546447 131.556564)
		(end 162.4 131.203011)
		(width 0.148)
		(layer "In2.Cu")
		(net 218)
	)
	(arc
		(start 163.4 131.203011)
		(mid 163.253553 131.556564)
		(end 162.9 131.703011)
		(width 0.148)
		(layer "In2.Cu")
		(net 218)
	)
	(arc
		(start 162.4 127.8)
		(mid 162.253553 127.446447)
		(end 161.9 127.3)
		(width 0.148)
		(layer "In2.Cu")
		(net 218)
	)
	(segment
		(start 184.9995 139.9995)
		(end 184.5 139.500001)
		(width 0.256)
		(layer "F.Cu")
		(net 219)
	)
	(segment
		(start 152.2 110.598)
		(end 152.2 111.75)
		(width 0.38)
		(layer "F.Cu")
		(net 219)
	)
	(via
		(at 152.2 111.75)
		(size 0.45)
		(drill 0.1)
		(layers "F.Cu" "B.Cu")
		(remove_unused_layers yes)
		(keep_end_layers yes)
		(zone_layer_connections)
		(net 219)
	)
	(via
		(at 184.5 139.500001)
		(size 0.45)
		(drill 0.1)
		(layers "F.Cu" "B.Cu")
		(remove_unused_layers yes)
		(keep_end_layers yes)
		(zone_layer_connections)
		(net 219)
	)
	(segment
		(start 184.5 138.5)
		(end 184.5 139.500001)
		(width 0.148)
		(layer "In6.Cu")
		(net 219)
	)
	(segment
		(start 155.282645 127.665)
		(end 154.515 127.665)
		(width 0.148)
		(layer "In6.Cu")
		(net 219)
	)
	(segment
		(start 154.515 124.815)
		(end 155.282645 124.815)
		(width 0.148)
		(layer "In6.Cu")
		(net 219)
	)
	(segment
		(start 163.55 138.75)
		(end 172.25 138.75)
		(width 0.148)
		(layer "In6.Cu")
		(net 219)
	)
	(segment
		(start 155.282633 120.065)
		(end 154.515 120.065)
		(width 0.148)
		(layer "In6.Cu")
		(net 219)
	)
	(segment
		(start 154.515 121.015)
		(end 155.282645 121.015)
		(width 0.148)
		(layer "In6.Cu")
		(net 219)
	)
	(segment
		(start 155.282645 121.965)
		(end 154.515 121.965)
		(width 0.148)
		(layer "In6.Cu")
		(net 219)
	)
	(segment
		(start 154.04 129.24)
		(end 163.55 138.75)
		(width 0.148)
		(layer "In6.Cu")
		(net 219)
	)
	(segment
		(start 154.04 129.14)
		(end 154.04 129.24)
		(width 0.148)
		(layer "In6.Cu")
		(net 219)
	)
	(segment
		(start 183.75 137.75)
		(end 184.5 138.5)
		(width 0.148)
		(layer "In6.Cu")
		(net 219)
	)
	(segment
		(start 154.04 128.14)
		(end 154.04 129.14)
		(width 0.148)
		(layer "In6.Cu")
		(net 219)
	)
	(segment
		(start 155.282645 123.865)
		(end 154.515 123.865)
		(width 0.148)
		(layer "In6.Cu")
		(net 219)
	)
	(segment
		(start 172.25 138.75)
		(end 173.25 137.75)
		(width 0.148)
		(layer "In6.Cu")
		(net 219)
	)
	(segment
		(start 155.282645 125.765)
		(end 154.515 125.765)
		(width 0.148)
		(layer "In6.Cu")
		(net 219)
	)
	(segment
		(start 154.04 113.588)
		(end 154.04 118.64)
		(width 0.148)
		(layer "In6.Cu")
		(net 219)
	)
	(segment
		(start 154.515 122.915)
		(end 155.282645 122.915)
		(width 0.148)
		(layer "In6.Cu")
		(net 219)
	)
	(segment
		(start 152.2 111.748)
		(end 154.04 113.588)
		(width 0.148)
		(layer "In6.Cu")
		(net 219)
	)
	(segment
		(start 154.515 119.115)
		(end 155.282633 119.115)
		(width 0.148)
		(layer "In6.Cu")
		(net 219)
	)
	(segment
		(start 154.515 126.715)
		(end 155.282645 126.715)
		(width 0.148)
		(layer "In6.Cu")
		(net 219)
	)
	(segment
		(start 173.25 137.75)
		(end 183.75 137.75)
		(width 0.148)
		(layer "In6.Cu")
		(net 219)
	)
	(arc
		(start 155.757645 127.19)
		(mid 155.618521 127.525876)
		(end 155.282645 127.665)
		(width 0.148)
		(layer "In6.Cu")
		(net 219)
	)
	(arc
		(start 155.282645 122.915)
		(mid 155.618521 123.054124)
		(end 155.757645 123.39)
		(width 0.148)
		(layer "In6.Cu")
		(net 219)
	)
	(arc
		(start 154.04 122.44)
		(mid 154.179124 122.775876)
		(end 154.515 122.915)
		(width 0.148)
		(layer "In6.Cu")
		(net 219)
	)
	(arc
		(start 155.757645 125.29)
		(mid 155.618521 125.625876)
		(end 155.282645 125.765)
		(width 0.148)
		(layer "In6.Cu")
		(net 219)
	)
	(arc
		(start 155.282645 126.715)
		(mid 155.618521 126.854124)
		(end 155.757645 127.19)
		(width 0.148)
		(layer "In6.Cu")
		(net 219)
	)
	(arc
		(start 154.515 125.765)
		(mid 154.179124 125.904124)
		(end 154.04 126.24)
		(width 0.148)
		(layer "In6.Cu")
		(net 219)
	)
	(arc
		(start 154.515 121.965)
		(mid 154.179124 122.104124)
		(end 154.04 122.44)
		(width 0.148)
		(layer "In6.Cu")
		(net 219)
	)
	(arc
		(start 154.515 123.865)
		(mid 154.179124 124.004124)
		(end 154.04 124.34)
		(width 0.148)
		(layer "In6.Cu")
		(net 219)
	)
	(arc
		(start 154.04 126.24)
		(mid 154.179124 126.575876)
		(end 154.515 126.715)
		(width 0.148)
		(layer "In6.Cu")
		(net 219)
	)
	(arc
		(start 155.282645 124.815)
		(mid 155.618521 124.954124)
		(end 155.757645 125.29)
		(width 0.148)
		(layer "In6.Cu")
		(net 219)
	)
	(arc
		(start 154.04 118.64)
		(mid 154.179124 118.975876)
		(end 154.515 119.115)
		(width 0.148)
		(layer "In6.Cu")
		(net 219)
	)
	(arc
		(start 154.515 120.065)
		(mid 154.179124 120.204124)
		(end 154.04 120.54)
		(width 0.148)
		(layer "In6.Cu")
		(net 219)
	)
	(arc
		(start 154.04 124.34)
		(mid 154.179124 124.675876)
		(end 154.515 124.815)
		(width 0.148)
		(layer "In6.Cu")
		(net 219)
	)
	(arc
		(start 155.757645 123.39)
		(mid 155.618521 123.725876)
		(end 155.282645 123.865)
		(width 0.148)
		(layer "In6.Cu")
		(net 219)
	)
	(arc
		(start 154.04 120.54)
		(mid 154.179124 120.875876)
		(end 154.515 121.015)
		(width 0.148)
		(layer "In6.Cu")
		(net 219)
	)
	(arc
		(start 155.757645 121.49)
		(mid 155.618521 121.825876)
		(end 155.282645 121.965)
		(width 0.148)
		(layer "In6.Cu")
		(net 219)
	)
	(arc
		(start 155.282633 119.115)
		(mid 155.618509 119.254124)
		(end 155.757633 119.59)
		(width 0.148)
		(layer "In6.Cu")
		(net 219)
	)
	(arc
		(start 155.757633 119.59)
		(mid 155.618509 119.925876)
		(end 155.282633 120.065)
		(width 0.148)
		(layer "In6.Cu")
		(net 219)
	)
	(arc
		(start 154.515 127.665)
		(mid 154.179124 127.804124)
		(end 154.04 128.14)
		(width 0.148)
		(layer "In6.Cu")
		(net 219)
	)
	(arc
		(start 155.282645 121.015)
		(mid 155.618521 121.154124)
		(end 155.757645 121.49)
		(width 0.148)
		(layer "In6.Cu")
		(net 219)
	)
	(segment
		(start 116.46 138.6)
		(end 117.5 138.6)
		(width 0.4)
		(layer "F.Cu")
		(net 220)
	)
	(segment
		(start 254.748 144.552)
		(end 254.974 144.552)
		(width 0.201)
		(layer "F.Cu")
		(net 221)
	)
	(segment
		(start 254.751 144.551)
		(end 254.974 144.551)
		(width 0.201)
		(layer "F.Cu")
		(net 221)
	)
	(segment
		(start 253.27 143.45)
		(end 253.65 143.45)
		(width 0.201)
		(layer "F.Cu")
		(net 221)
	)
	(segment
		(start 253.65 143.45)
		(end 254.751 144.551)
		(width 0.201)
		(layer "F.Cu")
		(net 221)
	)
	(segment
		(start 215.186 180.175)
		(end 215.186 179.190001)
		(width 0.256)
		(layer "F.Cu")
		(net 222)
	)
	(segment
		(start 215.865 180.165)
		(end 215.196 180.165)
		(width 0.256)
		(layer "F.Cu")
		(net 222)
	)
	(segment
		(start 215.196 180.165)
		(end 215.186 180.175)
		(width 0.256)
		(layer "F.Cu")
		(net 222)
	)
	(segment
		(start 216.245001 180.545001)
		(end 215.865 180.165)
		(width 0.256)
		(layer "F.Cu")
		(net 222)
	)
	(segment
		(start 216.895001 180.545001)
		(end 216.245001 180.545001)
		(width 0.256)
		(layer "F.Cu")
		(net 222)
	)
	(segment
		(start 222.835 175.46)
		(end 221.71 175.46)
		(width 0.15)
		(layer "F.Cu")
		(net 223)
	)
	(segment
		(start 223.135 176.085)
		(end 223.135 175.76)
		(width 0.15)
		(layer "F.Cu")
		(net 223)
	)
	(segment
		(start 223.135 175.76)
		(end 222.835 175.46)
		(width 0.15)
		(layer "F.Cu")
		(net 223)
	)
	(via
		(at 220.159999 170.035)
		(size 0.45)
		(drill 0.1)
		(layers "F.Cu" "B.Cu")
		(remove_unused_layers yes)
		(keep_end_layers yes)
		(zone_layer_connections)
		(net 223)
	)
	(via
		(at 219.160001 169.535)
		(size 0.45)
		(drill 0.1)
		(layers "F.Cu" "B.Cu")
		(remove_unused_layers yes)
		(keep_end_layers yes)
		(zone_layer_connections)
		(net 223)
	)
	(via
		(at 219.785 169.535)
		(size 0.45)
		(drill 0.1)
		(layers "F.Cu" "B.Cu")
		(remove_unused_layers yes)
		(keep_end_layers yes)
		(zone_layer_connections)
		(net 223)
	)
	(via
		(at 217.385001 170.585)
		(size 0.45)
		(drill 0.1)
		(layers "F.Cu" "B.Cu")
		(remove_unused_layers yes)
		(keep_end_layers yes)
		(zone_layer_connections)
		(net 223)
	)
	(via
		(at 217.960001 170.585)
		(size 0.45)
		(drill 0.1)
		(layers "F.Cu" "B.Cu")
		(remove_unused_layers yes)
		(keep_end_layers yes)
		(zone_layer_connections)
		(net 223)
	)
	(via
		(at 220.459999 170.585)
		(size 0.45)
		(drill 0.1)
		(layers "F.Cu" "B.Cu")
		(remove_unused_layers yes)
		(keep_end_layers yes)
		(zone_layer_connections)
		(net 223)
	)
	(via
		(at 217.385 169.535)
		(size 0.45)
		(drill 0.1)
		(layers "F.Cu" "B.Cu")
		(remove_unused_layers yes)
		(keep_end_layers yes)
		(zone_layer_connections)
		(net 223)
	)
	(via
		(at 218.91 170.035)
		(size 0.45)
		(drill 0.1)
		(layers "F.Cu" "B.Cu")
		(remove_unused_layers yes)
		(keep_end_layers yes)
		(zone_layer_connections)
		(net 223)
	)
	(via
		(at 217.76 170.035)
		(size 0.45)
		(drill 0.1)
		(layers "F.Cu" "B.Cu")
		(remove_unused_layers yes)
		(keep_end_layers yes)
		(zone_layer_connections)
		(net 223)
	)
	(via
		(at 218.335001 170.035)
		(size 0.45)
		(drill 0.1)
		(layers "F.Cu" "B.Cu")
		(remove_unused_layers yes)
		(keep_end_layers yes)
		(zone_layer_connections)
		(net 223)
	)
	(via
		(at 220.459999 169.535)
		(size 0.45)
		(drill 0.1)
		(layers "F.Cu" "B.Cu")
		(remove_unused_layers yes)
		(keep_end_layers yes)
		(zone_layer_connections)
		(net 223)
	)
	(via
		(at 218.535001 169.535)
		(size 0.45)
		(drill 0.1)
		(layers "F.Cu" "B.Cu")
		(remove_unused_layers yes)
		(keep_end_layers yes)
		(zone_layer_connections)
		(net 223)
	)
	(via
		(at 217.960001 169.535)
		(size 0.45)
		(drill 0.1)
		(layers "F.Cu" "B.Cu")
		(remove_unused_layers yes)
		(keep_end_layers yes)
		(zone_layer_connections)
		(net 223)
	)
	(via
		(at 219.160001 170.585)
		(size 0.45)
		(drill 0.1)
		(layers "F.Cu" "B.Cu")
		(remove_unused_layers yes)
		(keep_end_layers yes)
		(zone_layer_connections)
		(net 223)
	)
	(via
		(at 218.535001 170.585)
		(size 0.45)
		(drill 0.1)
		(layers "F.Cu" "B.Cu")
		(remove_unused_layers yes)
		(keep_end_layers yes)
		(zone_layer_connections)
		(net 223)
	)
	(via
		(at 219.535 170.035)
		(size 0.45)
		(drill 0.1)
		(layers "F.Cu" "B.Cu")
		(remove_unused_layers yes)
		(keep_end_layers yes)
		(zone_layer_connections)
		(net 223)
	)
	(via
		(at 223.135 176.085)
		(size 0.45)
		(drill 0.1)
		(layers "F.Cu" "B.Cu")
		(remove_unused_layers yes)
		(keep_end_layers yes)
		(zone_layer_connections)
		(net 223)
	)
	(via
		(at 219.81 170.585)
		(size 0.45)
		(drill 0.1)
		(layers "F.Cu" "B.Cu")
		(remove_unused_layers yes)
		(keep_end_layers yes)
		(zone_layer_connections)
		(net 223)
	)
	(segment
		(start 222.86 177.435)
		(end 222.86 176.36)
		(width 0.15)
		(layer "B.Cu")
		(net 223)
	)
	(segment
		(start 222.86 176.36)
		(end 223.135 176.085)
		(width 0.15)
		(layer "B.Cu")
		(net 223)
	)
	(via
		(at 229.01 170.06)
		(size 0.45)
		(drill 0.1)
		(layers "F.Cu" "B.Cu")
		(remove_unused_layers yes)
		(keep_end_layers yes)
		(zone_layer_connections)
		(net 224)
	)
	(via
		(at 230.584999 169.51)
		(size 0.45)
		(drill 0.1)
		(layers "F.Cu" "B.Cu")
		(remove_unused_layers yes)
		(keep_end_layers yes)
		(zone_layer_connections)
		(net 224)
	)
	(via
		(at 230.009999 170.56)
		(size 0.45)
		(drill 0.1)
		(layers "F.Cu" "B.Cu")
		(remove_unused_layers yes)
		(keep_end_layers yes)
		(zone_layer_connections)
		(net 224)
	)
	(via
		(at 230.21 170.06)
		(size 0.45)
		(drill 0.1)
		(layers "F.Cu" "B.Cu")
		(remove_unused_layers yes)
		(keep_end_layers yes)
		(zone_layer_connections)
		(net 224)
	)
	(via
		(at 228.085001 169.51)
		(size 0.45)
		(drill 0.1)
		(layers "F.Cu" "B.Cu")
		(remove_unused_layers yes)
		(keep_end_layers yes)
		(zone_layer_connections)
		(net 224)
	)
	(via
		(at 230.009999 169.51)
		(size 0.45)
		(drill 0.1)
		(layers "F.Cu" "B.Cu")
		(remove_unused_layers yes)
		(keep_end_layers yes)
		(zone_layer_connections)
		(net 224)
	)
	(via
		(at 229.384999 169.51)
		(size 0.45)
		(drill 0.1)
		(layers "F.Cu" "B.Cu")
		(remove_unused_layers yes)
		(keep_end_layers yes)
		(zone_layer_connections)
		(net 224)
	)
	(via
		(at 231.159999 169.51)
		(size 0.45)
		(drill 0.1)
		(layers "F.Cu" "B.Cu")
		(remove_unused_layers yes)
		(keep_end_layers yes)
		(zone_layer_connections)
		(net 224)
	)
	(via
		(at 228.085001 170.56)
		(size 0.45)
		(drill 0.1)
		(layers "F.Cu" "B.Cu")
		(remove_unused_layers yes)
		(keep_end_layers yes)
		(zone_layer_connections)
		(net 224)
	)
	(via
		(at 230.584999 170.56)
		(size 0.45)
		(drill 0.1)
		(layers "F.Cu" "B.Cu")
		(remove_unused_layers yes)
		(keep_end_layers yes)
		(zone_layer_connections)
		(net 224)
	)
	(via
		(at 230.785 170.06)
		(size 0.45)
		(drill 0.1)
		(layers "F.Cu" "B.Cu")
		(remove_unused_layers yes)
		(keep_end_layers yes)
		(zone_layer_connections)
		(net 224)
	)
	(via
		(at 229.635 170.06)
		(size 0.45)
		(drill 0.1)
		(layers "F.Cu" "B.Cu")
		(remove_unused_layers yes)
		(keep_end_layers yes)
		(zone_layer_connections)
		(net 224)
	)
	(via
		(at 229.384999 170.56)
		(size 0.45)
		(drill 0.1)
		(layers "F.Cu" "B.Cu")
		(remove_unused_layers yes)
		(keep_end_layers yes)
		(zone_layer_connections)
		(net 224)
	)
	(via
		(at 228.385001 170.06)
		(size 0.45)
		(drill 0.1)
		(layers "F.Cu" "B.Cu")
		(remove_unused_layers yes)
		(keep_end_layers yes)
		(zone_layer_connections)
		(net 224)
	)
	(via
		(at 228.76 169.51)
		(size 0.45)
		(drill 0.1)
		(layers "F.Cu" "B.Cu")
		(remove_unused_layers yes)
		(keep_end_layers yes)
		(zone_layer_connections)
		(net 224)
	)
	(via
		(at 228.76 170.56)
		(size 0.45)
		(drill 0.1)
		(layers "F.Cu" "B.Cu")
		(remove_unused_layers yes)
		(keep_end_layers yes)
		(zone_layer_connections)
		(net 224)
	)
	(via
		(at 231.159999 170.56)
		(size 0.45)
		(drill 0.1)
		(layers "F.Cu" "B.Cu")
		(remove_unused_layers yes)
		(keep_end_layers yes)
		(zone_layer_connections)
		(net 224)
	)
	(segment
		(start 257.3 179.775)
		(end 258.099 179.775)
		(width 0.1)
		(layer "F.Cu")
		(net 225)
	)
	(segment
		(start 258.099 179.775)
		(end 258.1 179.774)
		(width 0.1)
		(layer "F.Cu")
		(net 225)
	)
	(segment
		(start 232.290001 181.840002)
		(end 233.282822 181.840002)
		(width 0.1)
		(layer "F.Cu")
		(net 226)
	)
	(segment
		(start 233.282822 181.840002)
		(end 233.293911 181.851091)
		(width 0.1)
		(layer "F.Cu")
		(net 226)
	)
	(segment
		(start 221.595001 181.845001)
		(end 222.587822 181.845001)
		(width 0.1)
		(layer "F.Cu")
		(net 226)
	)
	(segment
		(start 222.587822 181.845001)
		(end 222.598911 181.85609)
		(width 0.1)
		(layer "F.Cu")
		(net 226)
	)
	(via
		(at 222.598911 181.85609)
		(size 0.45)
		(drill 0.1)
		(layers "F.Cu" "B.Cu")
		(remove_unused_layers yes)
		(keep_end_layers yes)
		(zone_layer_connections)
		(net 226)
	)
	(via
		(at 233.293911 181.851091)
		(size 0.45)
		(drill 0.1)
		(layers "F.Cu" "B.Cu")
		(remove_unused_layers yes)
		(keep_end_layers yes)
		(zone_layer_connections)
		(net 226)
	)
	(segment
		(start 222.598911 181.476089)
		(end 222.865 181.21)
		(width 0.256)
		(layer "B.Cu")
		(net 226)
	)
	(segment
		(start 222.598911 181.85609)
		(end 222.598911 181.476089)
		(width 0.256)
		(layer "B.Cu")
		(net 226)
	)
	(segment
		(start 222.865 180.27)
		(end 222.86 180.265)
		(width 0.256)
		(layer "B.Cu")
		(net 226)
	)
	(segment
		(start 222.865 181.21)
		(end 222.865 180.27)
		(width 0.256)
		(layer "B.Cu")
		(net 226)
	)
	(segment
		(start 221.885 180.265)
		(end 222.86 180.265)
		(width 0.256)
		(layer "B.Cu")
		(net 226)
	)
	(segment
		(start 222.752821 182.01)
		(end 224.635 182.01)
		(width 0.1)
		(layer "In4.Cu")
		(net 226)
	)
	(segment
		(start 231.567842 180.36)
		(end 233.058933 181.851091)
		(width 0.1)
		(layer "In4.Cu")
		(net 226)
	)
	(segment
		(start 226.285 180.36)
		(end 231.567842 180.36)
		(width 0.1)
		(layer "In4.Cu")
		(net 226)
	)
	(segment
		(start 224.635 182.01)
		(end 226.285 180.36)
		(width 0.1)
		(layer "In4.Cu")
		(net 226)
	)
	(segment
		(start 233.058933 181.851091)
		(end 233.293911 181.851091)
		(width 0.1)
		(layer "In4.Cu")
		(net 226)
	)
	(segment
		(start 222.598911 181.85609)
		(end 222.752821 182.01)
		(width 0.1)
		(layer "In4.Cu")
		(net 226)
	)
	(segment
		(start 145.625 140.157851)
		(end 145.625 138.622851)
		(width 0.15)
		(layer "F.Cu")
		(net 227)
	)
	(segment
		(start 141.525 141.322851)
		(end 142.21 141.322851)
		(width 0.15)
		(layer "F.Cu")
		(net 227)
	)
	(segment
		(start 142.21 141.322851)
		(end 142.525 141.007851)
		(width 0.15)
		(layer "F.Cu")
		(net 227)
	)
	(segment
		(start 144.775 141.007851)
		(end 142.525 141.007851)
		(width 0.15)
		(layer "F.Cu")
		(net 227)
	)
	(segment
		(start 144.775 141.007851)
		(end 145.625 140.157851)
		(width 0.15)
		(layer "F.Cu")
		(net 227)
	)
	(segment
		(start 140.824298 141.322851)
		(end 140.662149 141.485)
		(width 0.15)
		(layer "F.Cu")
		(net 227)
	)
	(segment
		(start 140.662149 141.485)
		(end 138.102149 141.485)
		(width 0.15)
		(layer "F.Cu")
		(net 227)
	)
	(segment
		(start 141.525 141.322851)
		(end 140.824298 141.322851)
		(width 0.15)
		(layer "F.Cu")
		(net 227)
	)
	(segment
		(start 143.44 143.407851)
		(end 143.44 142.072851)
		(width 0.15)
		(layer "F.Cu")
		(net 228)
	)
	(segment
		(start 141.525 142.292851)
		(end 142.76 142.292851)
		(width 0.15)
		(layer "F.Cu")
		(net 228)
	)
	(segment
		(start 138.102149 141.985)
		(end 140.587851 141.985)
		(width 0.15)
		(layer "F.Cu")
		(net 228)
	)
	(segment
		(start 140.587851 141.985)
		(end 140.895702 142.292851)
		(width 0.15)
		(layer "F.Cu")
		(net 228)
	)
	(segment
		(start 140.895702 142.292851)
		(end 141.525 142.292851)
		(width 0.15)
		(layer "F.Cu")
		(net 228)
	)
	(segment
		(start 150.5 110.598)
		(end 150.5 111.75)
		(width 0.38)
		(layer "F.Cu")
		(net 229)
	)
	(segment
		(start 184.9995 140.9995)
		(end 184.5 140.5)
		(width 0.256)
		(layer "F.Cu")
		(net 229)
	)
	(via
		(at 184.5 140.5)
		(size 0.45)
		(drill 0.1)
		(layers "F.Cu" "B.Cu")
		(remove_unused_layers yes)
		(keep_end_layers yes)
		(zone_layer_connections)
		(net 229)
	)
	(via
		(at 150.5 111.75)
		(size 0.45)
		(drill 0.1)
		(layers "F.Cu" "B.Cu")
		(remove_unused_layers yes)
		(keep_end_layers yes)
		(zone_layer_connections)
		(net 229)
	)
	(segment
		(start 152.31 118.32)
		(end 151.146071 118.32)
		(width 0.148)
		(layer "In6.Cu")
		(net 229)
	)
	(segment
		(start 152.76 120.09636)
		(end 152.76 129.585)
		(width 0.148)
		(layer "In6.Cu")
		(net 229)
	)
	(segment
		(start 151.849527 113.097527)
		(end 151.849528 113.097528)
		(width 0.148)
		(layer "In6.Cu")
		(net 229)
	)
	(segment
		(start 184 140)
		(end 184.5 140.5)
		(width 0.148)
		(layer "In6.Cu")
		(net 229)
	)
	(segment
		(start 151.146071 119.22)
		(end 152.31 119.22)
		(width 0.148)
		(layer "In6.Cu")
		(net 229)
	)
	(segment
		(start 151.849528 113.097528)
		(end 152.76 114.008)
		(width 0.148)
		(layer "In6.Cu")
		(net 229)
	)
	(segment
		(start 151.313903 113.208888)
		(end 151.425263 113.097527)
		(width 0.148)
		(layer "In6.Cu")
		(net 229)
	)
	(segment
		(start 152.31 114.72)
		(end 151.146086 114.72)
		(width 0.148)
		(layer "In6.Cu")
		(net 229)
	)
	(segment
		(start 184 139)
		(end 184 140)
		(width 0.148)
		(layer "In6.Cu")
		(net 229)
	)
	(segment
		(start 151.146086 117.42)
		(end 152.31 117.42)
		(width 0.148)
		(layer "In6.Cu")
		(net 229)
	)
	(segment
		(start 150.5 111.748)
		(end 151.001 112.249)
		(width 0.148)
		(layer "In6.Cu")
		(net 229)
	)
	(segment
		(start 152.76 129.585)
		(end 162.925 139.75)
		(width 0.148)
		(layer "In6.Cu")
		(net 229)
	)
	(segment
		(start 151.313904 113.208887)
		(end 151.313903 113.208888)
		(width 0.148)
		(layer "In6.Cu")
		(net 229)
	)
	(segment
		(start 172.675 139.75)
		(end 173.775 138.65)
		(width 0.148)
		(layer "In6.Cu")
		(net 229)
	)
	(segment
		(start 151.000999 112.673265)
		(end 151.001 112.673264)
		(width 0.148)
		(layer "In6.Cu")
		(net 229)
	)
	(segment
		(start 152.31 116.52)
		(end 151.146086 116.52)
		(width 0.148)
		(layer "In6.Cu")
		(net 229)
	)
	(segment
		(start 183.65 138.65)
		(end 184 139)
		(width 0.148)
		(layer "In6.Cu")
		(net 229)
	)
	(segment
		(start 152.76 114.008)
		(end 152.76 114.27)
		(width 0.148)
		(layer "In6.Cu")
		(net 229)
	)
	(segment
		(start 162.925 139.75)
		(end 172.675 139.75)
		(width 0.148)
		(layer "In6.Cu")
		(net 229)
	)
	(segment
		(start 151.001 112.673264)
		(end 150.889639 112.784624)
		(width 0.148)
		(layer "In6.Cu")
		(net 229)
	)
	(segment
		(start 152.76 119.67)
		(end 152.76 120.09636)
		(width 0.148)
		(layer "In6.Cu")
		(net 229)
	)
	(segment
		(start 151.146086 115.62)
		(end 152.31 115.62)
		(width 0.148)
		(layer "In6.Cu")
		(net 229)
	)
	(segment
		(start 173.775 138.65)
		(end 183.65 138.65)
		(width 0.148)
		(layer "In6.Cu")
		(net 229)
	)
	(arc
		(start 150.889639 112.784624)
		(mid 150.801771 112.996756)
		(end 150.889639 113.208888)
		(width 0.148)
		(layer "In6.Cu")
		(net 229)
	)
	(arc
		(start 152.76 114.27)
		(mid 152.628198 114.588198)
		(end 152.31 114.72)
		(width 0.148)
		(layer "In6.Cu")
		(net 229)
	)
	(arc
		(start 150.889639 113.208888)
		(mid 151.101772 113.296756)
		(end 151.313904 113.208887)
		(width 0.148)
		(layer "In6.Cu")
		(net 229)
	)
	(arc
		(start 152.31 117.42)
		(mid 152.628198 117.551802)
		(end 152.76 117.87)
		(width 0.148)
		(layer "In6.Cu")
		(net 229)
	)
	(arc
		(start 152.76 117.87)
		(mid 152.628198 118.188198)
		(end 152.31 118.32)
		(width 0.148)
		(layer "In6.Cu")
		(net 229)
	)
	(arc
		(start 151.425263 113.097527)
		(mid 151.637395 113.009659)
		(end 151.849527 113.097527)
		(width 0.148)
		(layer "In6.Cu")
		(net 229)
	)
	(arc
		(start 150.696086 116.97)
		(mid 150.827888 117.288198)
		(end 151.146086 117.42)
		(width 0.148)
		(layer "In6.Cu")
		(net 229)
	)
	(arc
		(start 151.146086 114.72)
		(mid 150.827888 114.851802)
		(end 150.696086 115.17)
		(width 0.148)
		(layer "In6.Cu")
		(net 229)
	)
	(arc
		(start 151.146086 116.52)
		(mid 150.827888 116.651802)
		(end 150.696086 116.97)
		(width 0.148)
		(layer "In6.Cu")
		(net 229)
	)
	(arc
		(start 152.76 116.07)
		(mid 152.628198 116.388198)
		(end 152.31 116.52)
		(width 0.148)
		(layer "In6.Cu")
		(net 229)
	)
	(arc
		(start 151.146071 118.32)
		(mid 150.827873 118.451802)
		(end 150.696071 118.77)
		(width 0.148)
		(layer "In6.Cu")
		(net 229)
	)
	(arc
		(start 152.31 119.22)
		(mid 152.628198 119.351802)
		(end 152.76 119.67)
		(width 0.148)
		(layer "In6.Cu")
		(net 229)
	)
	(arc
		(start 151.001 112.249)
		(mid 151.088868 112.461133)
		(end 151.000999 112.673265)
		(width 0.148)
		(layer "In6.Cu")
		(net 229)
	)
	(arc
		(start 152.31 115.62)
		(mid 152.628198 115.751802)
		(end 152.76 116.07)
		(width 0.148)
		(layer "In6.Cu")
		(net 229)
	)
	(arc
		(start 150.696086 115.17)
		(mid 150.827888 115.488198)
		(end 151.146086 115.62)
		(width 0.148)
		(layer "In6.Cu")
		(net 229)
	)
	(arc
		(start 150.696071 118.77)
		(mid 150.827873 119.088198)
		(end 151.146071 119.22)
		(width 0.148)
		(layer "In6.Cu")
		(net 229)
	)
	(segment
		(start 110.699 101.561)
		(end 110.699 100.839)
		(width 0.1)
		(layer "F.Cu")
		(net 230)
	)
	(via
		(at 110.695 100.835)
		(size 0.45)
		(drill 0.1)
		(layers "F.Cu" "B.Cu")
		(remove_unused_layers yes)
		(keep_end_layers yes)
		(zone_layer_connections)
		(net 230)
	)
	(segment
		(start 110.7 101.65)
		(end 110.7 100.84)
		(width 0.1)
		(layer "B.Cu")
		(net 230)
	)
	(segment
		(start 107.999 101.511)
		(end 107.999 100.789)
		(width 0.1)
		(layer "F.Cu")
		(net 231)
	)
	(via
		(at 107.995 100.785)
		(size 0.45)
		(drill 0.1)
		(layers "F.Cu" "B.Cu")
		(remove_unused_layers yes)
		(keep_end_layers yes)
		(zone_layer_connections)
		(net 231)
	)
	(segment
		(start 108 101.6)
		(end 108 100.79)
		(width 0.1)
		(layer "B.Cu")
		(net 231)
	)
	(segment
		(start 105.299 101.511)
		(end 105.299 100.789)
		(width 0.1)
		(layer "F.Cu")
		(net 232)
	)
	(via
		(at 105.295 100.785)
		(size 0.45)
		(drill 0.1)
		(layers "F.Cu" "B.Cu")
		(remove_unused_layers yes)
		(keep_end_layers yes)
		(zone_layer_connections)
		(net 232)
	)
	(segment
		(start 105.3 101.6)
		(end 105.3 100.79)
		(width 0.1)
		(layer "B.Cu")
		(net 232)
	)
	(segment
		(start 102.604 100.754)
		(end 102.6 100.75)
		(width 0.1)
		(layer "F.Cu")
		(net 233)
	)
	(segment
		(start 102.604 101.476)
		(end 102.604 100.754)
		(width 0.1)
		(layer "F.Cu")
		(net 233)
	)
	(via
		(at 102.6 100.75)
		(size 0.45)
		(drill 0.1)
		(layers "F.Cu" "B.Cu")
		(remove_unused_layers yes)
		(keep_end_layers yes)
		(zone_layer_connections)
		(net 233)
	)
	(segment
		(start 102.605 100.755)
		(end 102.6 100.75)
		(width 0.1)
		(layer "B.Cu")
		(net 233)
	)
	(segment
		(start 102.605 101.565)
		(end 102.605 100.755)
		(width 0.1)
		(layer "B.Cu")
		(net 233)
	)
	(segment
		(start 193.0005 143.9995)
		(end 193.5 143.5)
		(width 0.256)
		(layer "F.Cu")
		(net 234)
	)
	(segment
		(start 204.9 110.598)
		(end 204.9 111.75)
		(width 0.38)
		(layer "F.Cu")
		(net 234)
	)
	(via
		(at 204.9 111.75)
		(size 0.45)
		(drill 0.1)
		(layers "F.Cu" "B.Cu")
		(remove_unused_layers yes)
		(keep_end_layers yes)
		(zone_layer_connections)
		(net 234)
	)
	(via
		(at 193.5 143.5)
		(size 0.45)
		(drill 0.1)
		(layers "F.Cu" "B.Cu")
		(remove_unused_layers yes)
		(keep_end_layers yes)
		(zone_layer_connections)
		(net 234)
	)
	(segment
		(start 193.9 143.24)
		(end 193.9 143.280363)
		(width 0.1)
		(layer "In4.Cu")
		(net 234)
	)
	(segment
		(start 196.294339 133.528084)
		(end 196.209487 133.443232)
		(width 0.13)
		(layer "In4.Cu")
		(net 234)
	)
	(segment
		(start 206.72 106.649706)
		(end 206.72 107.539706)
		(width 0.13)
		(layer "In4.Cu")
		(net 234)
	)
	(segment
		(start 193.88 136.450294)
		(end 194.385148 135.945148)
		(width 0.13)
		(layer "In4.Cu")
		(net 234)
	)
	(segment
		(start 193.775 142.865)
		(end 193.752003 142.865)
		(width 0.1)
		(layer "In4.Cu")
		(net 234)
	)
	(segment
		(start 193.88 138)
		(end 193.88 136.450294)
		(width 0.13)
		(layer "In4.Cu")
		(net 234)
	)
	(segment
		(start 200.027867 128.777568)
		(end 200.304883 128.500553)
		(width 0.13)
		(layer "In4.Cu")
		(net 234)
	)
	(segment
		(start 194.300297 134.50492)
		(end 194.577204 134.228014)
		(width 0.13)
		(layer "In4.Cu")
		(net 234)
	)
	(segment
		(start 193.9 143.708578)
		(end 193.708578 143.9)
		(width 0.1)
		(layer "In4.Cu")
		(net 234)
	)
	(segment
		(start 196.017432 134.312867)
		(end 196.017433 134.312866)
		(width 0.13)
		(layer "In4.Cu")
		(net 234)
	)
	(segment
		(start 206.221653 108.250186)
		(end 206.221654 108.250187)
		(width 0.13)
		(layer "In4.Cu")
		(net 234)
	)
	(segment
		(start 199.835703 130.494597)
		(end 199.835704 130.494595)
		(width 0.13)
		(layer "In4.Cu")
		(net 234)
	)
	(segment
		(start 211.29 107.708277)
		(end 211.381723 107.708277)
		(width 0.13)
		(layer "In4.Cu")
		(net 234)
	)
	(segment
		(start 193.88 138)
		(end 193.9 138.02)
		(width 0.1)
		(layer "In4.Cu")
		(net 234)
	)
	(segment
		(start 197.333786 132.318932)
		(end 197.333787 132.318933)
		(width 0.13)
		(layer "In4.Cu")
		(net 234)
	)
	(segment
		(start 211.58 107.51)
		(end 211.58 106.749706)
		(width 0.13)
		(layer "In4.Cu")
		(net 234)
	)
	(segment
		(start 212.38 117.950294)
		(end 212.38 110.524706)
		(width 0.13)
		(layer "In4.Cu")
		(net 234)
	)
	(segment
		(start 197.333787 132.318933)
		(end 197.41864 132.403786)
		(width 0.13)
		(layer "In4.Cu")
		(net 234)
	)
	(segment
		(start 198.203529 131.618894)
		(end 198.118677 131.534042)
		(width 0.13)
		(layer "In4.Cu")
		(net 234)
	)
	(segment
		(start 211.58 109.724706)
		(end 211.58 108.456554)
		(width 0.13)
		(layer "In4.Cu")
		(net 234)
	)
	(segment
		(start 206.009521 108.250188)
		(end 204.595 109.664706)
		(width 0.13)
		(layer "In4.Cu")
		(net 234)
	)
	(segment
		(start 211.091723 108.06)
		(end 211.091723 107.906554)
		(width 0.13)
		(layer "In4.Cu")
		(net 234)
	)
	(segment
		(start 196.017433 134.312866)
		(end 196.294338 134.035958)
		(width 0.13)
		(layer "In4.Cu")
		(net 234)
	)
	(segment
		(start 201.744893 128.585407)
		(end 201.744894 128.585405)
		(width 0.13)
		(layer "In4.Cu")
		(net 234)
	)
	(segment
		(start 195.424598 134.228013)
		(end 195.509451 134.312866)
		(width 0.13)
		(layer "In4.Cu")
		(net 234)
	)
	(segment
		(start 206.539853 107.931987)
		(end 206.539852 107.931987)
		(width 0.13)
		(layer "In4.Cu")
		(net 234)
	)
	(segment
		(start 200.112719 129.709704)
		(end 200.027867 129.624852)
		(width 0.13)
		(layer "In4.Cu")
		(net 234)
	)
	(segment
		(start 198.118677 130.686758)
		(end 198.395693 130.409743)
		(width 0.13)
		(layer "In4.Cu")
		(net 234)
	)
	(segment
		(start 196.209487 132.595948)
		(end 196.486503 132.318933)
		(width 0.13)
		(layer "In4.Cu")
		(net 234)
	)
	(segment
		(start 193.55 143.9)
		(end 193.5 143.85)
		(width 0.1)
		(layer "In4.Cu")
		(net 234)
	)
	(segment
		(start 211.250294 106.42)
		(end 206.949706 106.42)
		(width 0.13)
		(layer "In4.Cu")
		(net 234)
	)
	(segment
		(start 206.72 107.539706)
		(end 206.539853 107.719853)
		(width 0.13)
		(layer "In4.Cu")
		(net 234)
	)
	(segment
		(start 199.242977 130.409743)
		(end 199.32783 130.494596)
		(width 0.13)
		(layer "In4.Cu")
		(net 234)
	)
	(segment
		(start 193.752003 143.115)
		(end 193.775 143.115)
		(width 0.1)
		(layer "In4.Cu")
		(net 234)
	)
	(segment
		(start 201.152166 128.500552)
		(end 201.152167 128.500553)
		(width 0.13)
		(layer "In4.Cu")
		(net 234)
	)
	(segment
		(start 202.373963 127.956331)
		(end 212.38 117.950294)
		(width 0.13)
		(layer "In4.Cu")
		(net 234)
	)
	(segment
		(start 206.949706 106.42)
		(end 206.72 106.649706)
		(width 0.13)
		(layer "In4.Cu")
		(net 234)
	)
	(segment
		(start 206.539853 108.144119)
		(end 206.433786 108.250187)
		(width 0.13)
		(layer "In4.Cu")
		(net 234)
	)
	(segment
		(start 200.112718 129.709704)
		(end 200.112719 129.709704)
		(width 0.13)
		(layer "In4.Cu")
		(net 234)
	)
	(segment
		(start 201.152167 128.500553)
		(end 201.23702 128.585406)
		(width 0.13)
		(layer "In4.Cu")
		(net 234)
	)
	(segment
		(start 198.203528 131.618894)
		(end 198.203529 131.618894)
		(width 0.13)
		(layer "In4.Cu")
		(net 234)
	)
	(segment
		(start 195.424597 134.228013)
		(end 195.424598 134.228013)
		(width 0.13)
		(layer "In4.Cu")
		(net 234)
	)
	(segment
		(start 206.539853 108.14412)
		(end 206.539853 108.144119)
		(width 0.13)
		(layer "In4.Cu")
		(net 234)
	)
	(segment
		(start 204.595 109.664706)
		(end 204.595 111.445)
		(width 0.13)
		(layer "In4.Cu")
		(net 234)
	)
	(segment
		(start 197.926514 132.403785)
		(end 198.203528 132.126768)
		(width 0.13)
		(layer "In4.Cu")
		(net 234)
	)
	(segment
		(start 194.385148 135.437166)
		(end 194.300296 135.352314)
		(width 0.13)
		(layer "In4.Cu")
		(net 234)
	)
	(segment
		(start 194.300295 134.504921)
		(end 194.300297 134.50492)
		(width 0.13)
		(layer "In4.Cu")
		(net 234)
	)
	(segment
		(start 196.294338 133.528084)
		(end 196.294339 133.528084)
		(width 0.13)
		(layer "In4.Cu")
		(net 234)
	)
	(segment
		(start 197.926513 132.403787)
		(end 197.926514 132.403785)
		(width 0.13)
		(layer "In4.Cu")
		(net 234)
	)
	(segment
		(start 193.9 143.280363)
		(end 193.9 143.708578)
		(width 0.1)
		(layer "In4.Cu")
		(net 234)
	)
	(segment
		(start 204.595 111.445)
		(end 204.9 111.75)
		(width 0.13)
		(layer "In4.Cu")
		(net 234)
	)
	(segment
		(start 193.708578 143.9)
		(end 193.55 143.9)
		(width 0.1)
		(layer "In4.Cu")
		(net 234)
	)
	(segment
		(start 199.242976 130.409742)
		(end 199.242977 130.409743)
		(width 0.13)
		(layer "In4.Cu")
		(net 234)
	)
	(segment
		(start 193.9 138.02)
		(end 193.9 142.74)
		(width 0.1)
		(layer "In4.Cu")
		(net 234)
	)
	(segment
		(start 193.5 143.85)
		(end 193.5 143.5)
		(width 0.1)
		(layer "In4.Cu")
		(net 234)
	)
	(segment
		(start 199.835704 130.494595)
		(end 200.112718 130.217578)
		(width 0.13)
		(layer "In4.Cu")
		(net 234)
	)
	(segment
		(start 212.38 110.524706)
		(end 211.58 109.724706)
		(width 0.13)
		(layer "In4.Cu")
		(net 234)
	)
	(segment
		(start 211.58 106.749706)
		(end 211.250294 106.42)
		(width 0.13)
		(layer "In4.Cu")
		(net 234)
	)
	(segment
		(start 201.744894 128.585405)
		(end 202.373963 127.956331)
		(width 0.13)
		(layer "In4.Cu")
		(net 234)
	)
	(segment
		(start 211.381723 108.258277)
		(end 211.29 108.258277)
		(width 0.13)
		(layer "In4.Cu")
		(net 234)
	)
	(arc
		(start 198.395693 130.409743)
		(mid 198.819334 130.234264)
		(end 199.242976 130.409742)
		(width 0.13)
		(layer "In4.Cu")
		(net 234)
	)
	(arc
		(start 211.58 108.456554)
		(mid 211.521926 108.316351)
		(end 211.381723 108.258277)
		(width 0.13)
		(layer "In4.Cu")
		(net 234)
	)
	(arc
		(start 193.9 142.74)
		(mid 193.863388 142.828388)
		(end 193.775 142.865)
		(width 0.1)
		(layer "In4.Cu")
		(net 234)
	)
	(arc
		(start 196.294338 134.035958)
		(mid 196.399523 133.78202)
		(end 196.294338 133.528084)
		(width 0.13)
		(layer "In4.Cu")
		(net 234)
	)
	(arc
		(start 206.221654 108.250187)
		(mid 206.115588 108.206252)
		(end 206.009521 108.250188)
		(width 0.13)
		(layer "In4.Cu")
		(net 234)
	)
	(arc
		(start 206.433786 108.250187)
		(mid 206.32772 108.29412)
		(end 206.221653 108.250186)
		(width 0.13)
		(layer "In4.Cu")
		(net 234)
	)
	(arc
		(start 201.23702 128.585406)
		(mid 201.490956 128.69059)
		(end 201.744893 128.585407)
		(width 0.13)
		(layer "In4.Cu")
		(net 234)
	)
	(arc
		(start 194.385148 135.945148)
		(mid 194.490355 135.691157)
		(end 194.385148 135.437166)
		(width 0.13)
		(layer "In4.Cu")
		(net 234)
	)
	(arc
		(start 200.027867 129.624852)
		(mid 199.852389 129.20121)
		(end 200.027867 128.777568)
		(width 0.13)
		(layer "In4.Cu")
		(net 234)
	)
	(arc
		(start 193.775 143.115)
		(mid 193.863388 143.151612)
		(end 193.9 143.24)
		(width 0.1)
		(layer "In4.Cu")
		(net 234)
	)
	(arc
		(start 211.29 108.258277)
		(mid 211.149797 108.200203)
		(end 211.091723 108.06)
		(width 0.13)
		(layer "In4.Cu")
		(net 234)
	)
	(arc
		(start 200.304883 128.500553)
		(mid 200.728524 128.325074)
		(end 201.152166 128.500552)
		(width 0.13)
		(layer "In4.Cu")
		(net 234)
	)
	(arc
		(start 193.627003 142.99)
		(mid 193.663615 143.078388)
		(end 193.752003 143.115)
		(width 0.1)
		(layer "In4.Cu")
		(net 234)
	)
	(arc
		(start 196.209487 133.443232)
		(mid 196.034009 133.01959)
		(end 196.209487 132.595948)
		(width 0.13)
		(layer "In4.Cu")
		(net 234)
	)
	(arc
		(start 196.486503 132.318933)
		(mid 196.910144 132.143454)
		(end 197.333786 132.318932)
		(width 0.13)
		(layer "In4.Cu")
		(net 234)
	)
	(arc
		(start 198.118677 131.534042)
		(mid 197.943199 131.1104)
		(end 198.118677 130.686758)
		(width 0.13)
		(layer "In4.Cu")
		(net 234)
	)
	(arc
		(start 194.577204 134.228014)
		(mid 195.000901 134.052512)
		(end 195.424597 134.228013)
		(width 0.13)
		(layer "In4.Cu")
		(net 234)
	)
	(arc
		(start 206.539852 107.931987)
		(mid 206.583788 108.038052)
		(end 206.539853 108.14412)
		(width 0.13)
		(layer "In4.Cu")
		(net 234)
	)
	(arc
		(start 211.381723 107.708277)
		(mid 211.521926 107.650203)
		(end 211.58 107.51)
		(width 0.13)
		(layer "In4.Cu")
		(net 234)
	)
	(arc
		(start 197.41864 132.403786)
		(mid 197.672576 132.50897)
		(end 197.926513 132.403787)
		(width 0.13)
		(layer "In4.Cu")
		(net 234)
	)
	(arc
		(start 206.539853 107.719853)
		(mid 206.495918 107.825921)
		(end 206.539853 107.931987)
		(width 0.13)
		(layer "In4.Cu")
		(net 234)
	)
	(arc
		(start 195.509451 134.312866)
		(mid 195.76344 134.418074)
		(end 196.017432 134.312867)
		(width 0.13)
		(layer "In4.Cu")
		(net 234)
	)
	(arc
		(start 199.32783 130.494596)
		(mid 199.581766 130.59978)
		(end 199.835703 130.494597)
		(width 0.13)
		(layer "In4.Cu")
		(net 234)
	)
	(arc
		(start 194.300296 135.352314)
		(mid 194.124796 134.928617)
		(end 194.300295 134.504921)
		(width 0.13)
		(layer "In4.Cu")
		(net 234)
	)
	(arc
		(start 211.091723 107.906554)
		(mid 211.149797 107.766351)
		(end 211.29 107.708277)
		(width 0.13)
		(layer "In4.Cu")
		(net 234)
	)
	(arc
		(start 198.203528 132.126768)
		(mid 198.308713 131.87283)
		(end 198.203528 131.618894)
		(width 0.13)
		(layer "In4.Cu")
		(net 234)
	)
	(arc
		(start 193.752003 142.865)
		(mid 193.663615 142.901612)
		(end 193.627003 142.99)
		(width 0.1)
		(layer "In4.Cu")
		(net 234)
	)
	(arc
		(start 200.112718 130.217578)
		(mid 200.217903 129.96364)
		(end 200.112718 129.709704)
		(width 0.13)
		(layer "In4.Cu")
		(net 234)
	)
	(segment
		(start 204.05 110.598)
		(end 204.05 111.75)
		(width 0.38)
		(layer "F.Cu")
		(net 235)
	)
	(segment
		(start 193.0005 144.9995)
		(end 193.5 144.5)
		(width 0.256)
		(layer "F.Cu")
		(net 235)
	)
	(via
		(at 204.05 111.75)
		(size 0.45)
		(drill 0.1)
		(layers "F.Cu" "B.Cu")
		(remove_unused_layers yes)
		(keep_end_layers yes)
		(zone_layer_connections)
		(net 235)
	)
	(via
		(at 193.5 144.5)
		(size 0.45)
		(drill 0.1)
		(layers "F.Cu" "B.Cu")
		(remove_unused_layers yes)
		(keep_end_layers yes)
		(zone_layer_connections)
		(net 235)
	)
	(segment
		(start 195.254891 134.397718)
		(end 195.254892 134.397719)
		(width 0.13)
		(layer "In4.Cu")
		(net 235)
	)
	(segment
		(start 194.554853 135.267461)
		(end 194.470001 135.182609)
		(width 0.13)
		(layer "In4.Cu")
		(net 235)
	)
	(segment
		(start 198.373233 131.449189)
		(end 198.373234 131.449189)
		(width 0.13)
		(layer "In4.Cu")
		(net 235)
	)
	(segment
		(start 194.1 143.791422)
		(end 194.1 138.02)
		(width 0.1)
		(layer "In4.Cu")
		(net 235)
	)
	(segment
		(start 212.62 118.049706)
		(end 212.62 110.425294)
		(width 0.13)
		(layer "In4.Cu")
		(net 235)
	)
	(segment
		(start 194.47 134.674628)
		(end 194.470001 134.674627)
		(width 0.13)
		(layer "In4.Cu")
		(net 235)
	)
	(segment
		(start 200.197571 128.947274)
		(end 200.197571 128.947275)
		(width 0.13)
		(layer "In4.Cu")
		(net 235)
	)
	(segment
		(start 196.187137 134.482573)
		(end 196.464043 134.205663)
		(width 0.13)
		(layer "In4.Cu")
		(net 235)
	)
	(segment
		(start 197.164082 132.488637)
		(end 197.164081 132.488639)
		(width 0.13)
		(layer "In4.Cu")
		(net 235)
	)
	(segment
		(start 196.464043 133.358379)
		(end 196.464044 133.358379)
		(width 0.13)
		(layer "In4.Cu")
		(net 235)
	)
	(segment
		(start 200.282423 130.387284)
		(end 200.282423 130.387283)
		(width 0.13)
		(layer "In4.Cu")
		(net 235)
	)
	(segment
		(start 199.073272 130.579447)
		(end 199.073271 130.579449)
		(width 0.13)
		(layer "In4.Cu")
		(net 235)
	)
	(segment
		(start 200.982461 128.670259)
		(end 201.067314 128.755112)
		(width 0.13)
		(layer "In4.Cu")
		(net 235)
	)
	(segment
		(start 200.282423 129.539999)
		(end 200.282424 129.539999)
		(width 0.13)
		(layer "In4.Cu")
		(net 235)
	)
	(segment
		(start 204.355 109.565294)
		(end 204.355 111.445)
		(width 0.13)
		(layer "In4.Cu")
		(net 235)
	)
	(segment
		(start 212.62 110.425294)
		(end 211.82 109.625294)
		(width 0.13)
		(layer "In4.Cu")
		(net 235)
	)
	(segment
		(start 194.12 138)
		(end 194.12 136.549706)
		(width 0.13)
		(layer "In4.Cu")
		(net 235)
	)
	(segment
		(start 211.82 106.650294)
		(end 211.349706 106.18)
		(width 0.13)
		(layer "In4.Cu")
		(net 235)
	)
	(segment
		(start 194.470001 134.674627)
		(end 194.74691 134.397719)
		(width 0.13)
		(layer "In4.Cu")
		(net 235)
	)
	(segment
		(start 195.254892 134.397719)
		(end 195.339745 134.482572)
		(width 0.13)
		(layer "In4.Cu")
		(net 235)
	)
	(segment
		(start 196.379191 132.765655)
		(end 196.656209 132.488638)
		(width 0.13)
		(layer "In4.Cu")
		(net 235)
	)
	(segment
		(start 198.288381 130.856465)
		(end 198.565399 130.579448)
		(width 0.13)
		(layer "In4.Cu")
		(net 235)
	)
	(segment
		(start 198.373234 131.449189)
		(end 198.288382 131.364337)
		(width 0.13)
		(layer "In4.Cu")
		(net 235)
	)
	(segment
		(start 211.349706 106.18)
		(end 206.850294 106.18)
		(width 0.13)
		(layer "In4.Cu")
		(net 235)
	)
	(segment
		(start 198.373233 132.296474)
		(end 198.373233 132.296473)
		(width 0.13)
		(layer "In4.Cu")
		(net 235)
	)
	(segment
		(start 196.379191 132.765654)
		(end 196.379191 132.765655)
		(width 0.13)
		(layer "In4.Cu")
		(net 235)
	)
	(segment
		(start 200.197571 128.947275)
		(end 200.474589 128.670258)
		(width 0.13)
		(layer "In4.Cu")
		(net 235)
	)
	(segment
		(start 200.282424 129.539999)
		(end 200.197572 129.455147)
		(width 0.13)
		(layer "In4.Cu")
		(net 235)
	)
	(segment
		(start 206.48 107.440294)
		(end 204.355 109.565294)
		(width 0.13)
		(layer "In4.Cu")
		(net 235)
	)
	(segment
		(start 204.355 111.445)
		(end 204.05 111.75)
		(width 0.13)
		(layer "In4.Cu")
		(net 235)
	)
	(segment
		(start 193.791422 144.1)
		(end 194.1 143.791422)
		(width 0.1)
		(layer "In4.Cu")
		(net 235)
	)
	(segment
		(start 196.187138 134.482573)
		(end 196.187137 134.482573)
		(width 0.13)
		(layer "In4.Cu")
		(net 235)
	)
	(segment
		(start 202.191613 128.478094)
		(end 212.62 118.049706)
		(width 0.13)
		(layer "In4.Cu")
		(net 235)
	)
	(segment
		(start 199.073271 130.579449)
		(end 199.158124 130.664302)
		(width 0.13)
		(layer "In4.Cu")
		(net 235)
	)
	(segment
		(start 200.982462 128.670257)
		(end 200.982461 128.670259)
		(width 0.13)
		(layer "In4.Cu")
		(net 235)
	)
	(segment
		(start 197.164081 132.488639)
		(end 197.248934 132.573492)
		(width 0.13)
		(layer "In4.Cu")
		(net 235)
	)
	(segment
		(start 194.12 136.549706)
		(end 194.554853 136.114853)
		(width 0.13)
		(layer "In4.Cu")
		(net 235)
	)
	(segment
		(start 196.464044 133.358379)
		(end 196.379192 133.273527)
		(width 0.13)
		(layer "In4.Cu")
		(net 235)
	)
	(segment
		(start 193.5 144.5)
		(end 193.5 144.15)
		(width 0.1)
		(layer "In4.Cu")
		(net 235)
	)
	(segment
		(start 201.914598 128.755112)
		(end 202.191613 128.478094)
		(width 0.13)
		(layer "In4.Cu")
		(net 235)
	)
	(segment
		(start 200.005408 130.664302)
		(end 200.282423 130.387284)
		(width 0.13)
		(layer "In4.Cu")
		(net 235)
	)
	(segment
		(start 198.096218 132.573492)
		(end 198.373233 132.296474)
		(width 0.13)
		(layer "In4.Cu")
		(net 235)
	)
	(segment
		(start 211.82 109.625294)
		(end 211.82 106.650294)
		(width 0.13)
		(layer "In4.Cu")
		(net 235)
	)
	(segment
		(start 198.288381 130.856464)
		(end 198.288381 130.856465)
		(width 0.13)
		(layer "In4.Cu")
		(net 235)
	)
	(segment
		(start 206.48 106.550294)
		(end 206.48 107.440294)
		(width 0.13)
		(layer "In4.Cu")
		(net 235)
	)
	(segment
		(start 193.55 144.1)
		(end 193.791422 144.1)
		(width 0.1)
		(layer "In4.Cu")
		(net 235)
	)
	(segment
		(start 194.1 138.02)
		(end 194.12 138)
		(width 0.1)
		(layer "In4.Cu")
		(net 235)
	)
	(segment
		(start 193.5 144.15)
		(end 193.55 144.1)
		(width 0.1)
		(layer "In4.Cu")
		(net 235)
	)
	(segment
		(start 206.850294 106.18)
		(end 206.48 106.550294)
		(width 0.13)
		(layer "In4.Cu")
		(net 235)
	)
	(arc
		(start 196.656209 132.488638)
		(mid 196.910145 132.383454)
		(end 197.164082 132.488637)
		(width 0.13)
		(layer "In4.Cu")
		(net 235)
	)
	(arc
		(start 194.554853 136.114853)
		(mid 194.730355 135.691156)
		(end 194.554853 135.267461)
		(width 0.13)
		(layer "In4.Cu")
		(net 235)
	)
	(arc
		(start 200.474589 128.670258)
		(mid 200.728525 128.565074)
		(end 200.982462 128.670257)
		(width 0.13)
		(layer "In4.Cu")
		(net 235)
	)
	(arc
		(start 198.288382 131.364337)
		(mid 198.183198 131.110401)
		(end 198.288381 130.856464)
		(width 0.13)
		(layer "In4.Cu")
		(net 235)
	)
	(arc
		(start 198.565399 130.579448)
		(mid 198.819335 130.474264)
		(end 199.073272 130.579447)
		(width 0.13)
		(layer "In4.Cu")
		(net 235)
	)
	(arc
		(start 201.067314 128.755112)
		(mid 201.490956 128.93059)
		(end 201.914598 128.755112)
		(width 0.13)
		(layer "In4.Cu")
		(net 235)
	)
	(arc
		(start 195.339745 134.482572)
		(mid 195.76344 134.658074)
		(end 196.187138 134.482573)
		(width 0.13)
		(layer "In4.Cu")
		(net 235)
	)
	(arc
		(start 194.470001 135.182609)
		(mid 194.364795 134.928618)
		(end 194.47 134.674628)
		(width 0.13)
		(layer "In4.Cu")
		(net 235)
	)
	(arc
		(start 196.379192 133.273527)
		(mid 196.274008 133.019591)
		(end 196.379191 132.765654)
		(width 0.13)
		(layer "In4.Cu")
		(net 235)
	)
	(arc
		(start 198.373233 132.296473)
		(mid 198.548711 131.872831)
		(end 198.373233 131.449189)
		(width 0.13)
		(layer "In4.Cu")
		(net 235)
	)
	(arc
		(start 200.197572 129.455147)
		(mid 200.092388 129.201211)
		(end 200.197571 128.947274)
		(width 0.13)
		(layer "In4.Cu")
		(net 235)
	)
	(arc
		(start 200.282423 130.387283)
		(mid 200.457901 129.963641)
		(end 200.282423 129.539999)
		(width 0.13)
		(layer "In4.Cu")
		(net 235)
	)
	(arc
		(start 199.158124 130.664302)
		(mid 199.581766 130.83978)
		(end 200.005408 130.664302)
		(width 0.13)
		(layer "In4.Cu")
		(net 235)
	)
	(arc
		(start 194.74691 134.397719)
		(mid 195.000899 134.292513)
		(end 195.254891 134.397718)
		(width 0.13)
		(layer "In4.Cu")
		(net 235)
	)
	(arc
		(start 196.464043 134.205663)
		(mid 196.639521 133.782021)
		(end 196.464043 133.358379)
		(width 0.13)
		(layer "In4.Cu")
		(net 235)
	)
	(arc
		(start 197.248934 132.573492)
		(mid 197.672576 132.74897)
		(end 198.096218 132.573492)
		(width 0.13)
		(layer "In4.Cu")
		(net 235)
	)
	(segment
		(start 255.75 145)
		(end 255.202 145.548)
		(width 0.201)
		(layer "F.Cu")
		(net 236)
	)
	(segment
		(start 255.75 144)
		(end 255.75 145)
		(width 0.201)
		(layer "F.Cu")
		(net 236)
	)
	(segment
		(start 253.27 142.4)
		(end 254.15 142.4)
		(width 0.201)
		(layer "F.Cu")
		(net 236)
	)
	(segment
		(start 254.15 142.4)
		(end 255.75 144)
		(width 0.201)
		(layer "F.Cu")
		(net 236)
	)
	(segment
		(start 255.202 145.548)
		(end 254.974 145.548)
		(width 0.201)
		(layer "F.Cu")
		(net 236)
	)
	(segment
		(start 253.27 146.65)
		(end 253.27 145.592)
		(width 0.201)
		(layer "F.Cu")
		(net 237)
	)
	(segment
		(start 253.27 145.592)
		(end 253.226 145.548)
		(width 0.201)
		(layer "F.Cu")
		(net 237)
	)
	(segment
		(start 221.382 149.098)
		(end 221.522 149.237999)
		(width 0.201)
		(layer "F.Cu")
		(net 238)
	)
	(segment
		(start 138.699499 173.534)
		(end 138.699499 174.224)
		(width 0.15)
		(layer "F.Cu")
		(net 238)
	)
	(segment
		(start 221.522 149.95)
		(end 222.422 150.85)
		(width 0.201)
		(layer "F.Cu")
		(net 238)
	)
	(segment
		(start 220.472001 149.098)
		(end 219.922 149.098)
		(width 0.15)
		(layer "F.Cu")
		(net 238)
	)
	(segment
		(start 221.244001 149.098)
		(end 220.472001 149.098)
		(width 0.15)
		(layer "F.Cu")
		(net 238)
	)
	(segment
		(start 197.5 156.5)
		(end 197.0005 156.0005)
		(width 0.256)
		(layer "F.Cu")
		(net 238)
	)
	(segment
		(start 222.422 150.85)
		(end 223.342 150.85)
		(width 0.201)
		(layer "F.Cu")
		(net 238)
	)
	(segment
		(start 221.522 149.237999)
		(end 221.522 149.95)
		(width 0.201)
		(layer "F.Cu")
		(net 238)
	)
	(segment
		(start 221.244001 149.098)
		(end 221.382 149.098)
		(width 0.201)
		(layer "F.Cu")
		(net 238)
	)
	(via
		(at 197.5 156.5)
		(size 0.45)
		(drill 0.1)
		(layers "F.Cu" "B.Cu")
		(remove_unused_layers yes)
		(keep_end_layers yes)
		(zone_layer_connections)
		(net 238)
	)
	(via
		(at 219.922 149.098)
		(size 0.45)
		(drill 0.1)
		(layers "F.Cu" "B.Cu")
		(remove_unused_layers yes)
		(keep_end_layers yes)
		(zone_layer_connections)
		(net 238)
	)
	(via
		(at 138.699499 174.224)
		(size 0.45)
		(drill 0.1)
		(layers "F.Cu" "B.Cu")
		(remove_unused_layers yes)
		(keep_end_layers yes)
		(zone_layer_connections)
		(net 238)
	)
	(segment
		(start 215.3 124.4)
		(end 205.3 124.4)
		(width 0.15)
		(layer "B.Cu")
		(net 238)
	)
	(segment
		(start 221.65 147.85)
		(end 221.65 130.75)
		(width 0.15)
		(layer "B.Cu")
		(net 238)
	)
	(segment
		(start 150.426 174.224)
		(end 138.699499 174.224)
		(width 0.15)
		(layer "B.Cu")
		(net 238)
	)
	(segment
		(start 221.65 130.75)
		(end 215.3 124.4)
		(width 0.15)
		(layer "B.Cu")
		(net 238)
	)
	(segment
		(start 199.35 130.35)
		(end 177.7 130.35)
		(width 0.15)
		(layer "B.Cu")
		(net 238)
	)
	(segment
		(start 205.3 124.4)
		(end 199.35 130.35)
		(width 0.15)
		(layer "B.Cu")
		(net 238)
	)
	(segment
		(start 151.6 156.45)
		(end 151.6 173.05)
		(width 0.15)
		(layer "B.Cu")
		(net 238)
	)
	(segment
		(start 220.402 149.098)
		(end 221.65 147.85)
		(width 0.15)
		(layer "B.Cu")
		(net 238)
	)
	(segment
		(start 219.922 149.098)
		(end 220.402 149.098)
		(width 0.15)
		(layer "B.Cu")
		(net 238)
	)
	(segment
		(start 177.7 130.35)
		(end 151.6 156.45)
		(width 0.15)
		(layer "B.Cu")
		(net 238)
	)
	(segment
		(start 151.6 173.05)
		(end 150.426 174.224)
		(width 0.15)
		(layer "B.Cu")
		(net 238)
	)
	(segment
		(start 197.875 156.875)
		(end 197.5 156.5)
		(width 0.1)
		(layer "In2.Cu")
		(net 238)
	)
	(segment
		(start 203.2 157.05)
		(end 203.025 156.875)
		(width 0.1)
		(layer "In2.Cu")
		(net 238)
	)
	(segment
		(start 217.5 154.972334)
		(end 214.072334 154.972334)
		(width 0.1)
		(layer "In2.Cu")
		(net 238)
	)
	(segment
		(start 211.544668 157.5)
		(end 205.55 157.5)
		(width 0.1)
		(layer "In2.Cu")
		(net 238)
	)
	(segment
		(start 205.55 157.5)
		(end 205.1 157.05)
		(width 0.1)
		(layer "In2.Cu")
		(net 238)
	)
	(segment
		(start 218.972 151.25)
		(end 218.65 151.25)
		(width 0.1)
		(layer "In2.Cu")
		(net 238)
	)
	(segment
		(start 218.35 151.55)
		(end 218.35 154.122334)
		(width 0.1)
		(layer "In2.Cu")
		(net 238)
	)
	(segment
		(start 205.1 157.05)
		(end 203.2 157.05)
		(width 0.1)
		(layer "In2.Cu")
		(net 238)
	)
	(segment
		(start 219.922 149.098)
		(end 219.922 150.3)
		(width 0.1)
		(layer "In2.Cu")
		(net 238)
	)
	(segment
		(start 219.922 150.3)
		(end 218.972 151.25)
		(width 0.1)
		(layer "In2.Cu")
		(net 238)
	)
	(segment
		(start 218.35 154.122334)
		(end 217.5 154.972334)
		(width 0.1)
		(layer "In2.Cu")
		(net 238)
	)
	(segment
		(start 203.025 156.875)
		(end 197.875 156.875)
		(width 0.1)
		(layer "In2.Cu")
		(net 238)
	)
	(segment
		(start 214.072334 154.972334)
		(end 211.544668 157.5)
		(width 0.1)
		(layer "In2.Cu")
		(net 238)
	)
	(segment
		(start 218.65 151.25)
		(end 218.35 151.55)
		(width 0.1)
		(layer "In2.Cu")
		(net 238)
	)
	(segment
		(start 218.902 148.598)
		(end 221.244001 148.598)
		(width 0.15)
		(layer "F.Cu")
		(net 239)
	)
	(segment
		(start 218.9 148.6)
		(end 218.902 148.598)
		(width 0.15)
		(layer "F.Cu")
		(net 239)
	)
	(segment
		(start 223.090001 148.598)
		(end 223.342 148.849999)
		(width 0.201)
		(layer "F.Cu")
		(net 239)
	)
	(segment
		(start 221.244001 148.598)
		(end 223.090001 148.598)
		(width 0.201)
		(layer "F.Cu")
		(net 239)
	)
	(segment
		(start 137.649499 173.534)
		(end 137.649499 174.224)
		(width 0.15)
		(layer "F.Cu")
		(net 239)
	)
	(segment
		(start 200.500001 154.5)
		(end 200.0005 154.0005)
		(width 0.256)
		(layer "F.Cu")
		(net 239)
	)
	(via
		(at 200.500001 154.5)
		(size 0.45)
		(drill 0.1)
		(layers "F.Cu" "B.Cu")
		(remove_unused_layers yes)
		(keep_end_layers yes)
		(zone_layer_connections)
		(net 239)
	)
	(via
		(at 218.9 148.6)
		(size 0.45)
		(drill 0.1)
		(layers "F.Cu" "B.Cu")
		(remove_unused_layers yes)
		(keep_end_layers yes)
		(zone_layer_connections)
		(net 239)
	)
	(via
		(at 137.649499 174.224)
		(size 0.45)
		(drill 0.1)
		(layers "F.Cu" "B.Cu")
		(remove_unused_layers yes)
		(keep_end_layers yes)
		(zone_layer_connections)
		(net 239)
	)
	(segment
		(start 138.150499 174.725)
		(end 150.525 174.725)
		(width 0.15)
		(layer "B.Cu")
		(net 239)
	)
	(segment
		(start 219.985686 148.6)
		(end 218.9 148.6)
		(width 0.15)
		(layer "B.Cu")
		(net 239)
	)
	(segment
		(start 150.525 174.725)
		(end 152 173.25)
		(width 0.15)
		(layer "B.Cu")
		(net 239)
	)
	(segment
		(start 221.2 147.385686)
		(end 219.985686 148.6)
		(width 0.15)
		(layer "B.Cu")
		(net 239)
	)
	(segment
		(start 205.486397 124.849999)
		(end 215.113605 124.849999)
		(width 0.15)
		(layer "B.Cu")
		(net 239)
	)
	(segment
		(start 199.536396 130.8)
		(end 205.486397 124.849999)
		(width 0.15)
		(layer "B.Cu")
		(net 239)
	)
	(segment
		(start 152 173.25)
		(end 152 156.9)
		(width 0.15)
		(layer "B.Cu")
		(net 239)
	)
	(segment
		(start 215.113605 124.849999)
		(end 221.2 130.936394)
		(width 0.15)
		(layer "B.Cu")
		(net 239)
	)
	(segment
		(start 152 156.9)
		(end 178.1 130.8)
		(width 0.15)
		(layer "B.Cu")
		(net 239)
	)
	(segment
		(start 221.2 130.936394)
		(end 221.2 147.385686)
		(width 0.15)
		(layer "B.Cu")
		(net 239)
	)
	(segment
		(start 137.649499 174.224)
		(end 138.150499 174.725)
		(width 0.15)
		(layer "B.Cu")
		(net 239)
	)
	(segment
		(start 178.1 130.8)
		(end 199.536396 130.8)
		(width 0.15)
		(layer "B.Cu")
		(net 239)
	)
	(segment
		(start 212.004501 154.045499)
		(end 212.85 153.2)
		(width 0.1)
		(layer "In2.Cu")
		(net 239)
	)
	(segment
		(start 210.554501 154.045499)
		(end 212.004501 154.045499)
		(width 0.1)
		(layer "In2.Cu")
		(net 239)
	)
	(segment
		(start 208.4 155.6)
		(end 209 155.6)
		(width 0.1)
		(layer "In2.Cu")
		(net 239)
	)
	(segment
		(start 212.85 153.2)
		(end 214.95 153.2)
		(width 0.1)
		(layer "In2.Cu")
		(net 239)
	)
	(segment
		(start 209 155.6)
		(end 210.554501 154.045499)
		(width 0.1)
		(layer "In2.Cu")
		(net 239)
	)
	(segment
		(start 204.325 155.875)
		(end 206.125 155.875)
		(width 0.1)
		(layer "In2.Cu")
		(net 239)
	)
	(segment
		(start 217.1 149.75)
		(end 217.75 149.75)
		(width 0.1)
		(layer "In2.Cu")
		(net 239)
	)
	(segment
		(start 200.500001 154.5)
		(end 201.0625 155.0625)
		(width 0.1)
		(layer "In2.Cu")
		(net 239)
	)
	(segment
		(start 214.95 153.2)
		(end 216.35 151.8)
		(width 0.1)
		(layer "In2.Cu")
		(net 239)
	)
	(segment
		(start 216.35 150.5)
		(end 217.1 149.75)
		(width 0.1)
		(layer "In2.Cu")
		(net 239)
	)
	(segment
		(start 207.6 156.4)
		(end 208.4 155.6)
		(width 0.1)
		(layer "In2.Cu")
		(net 239)
	)
	(segment
		(start 201.0625 155.0625)
		(end 203.5125 155.0625)
		(width 0.1)
		(layer "In2.Cu")
		(net 239)
	)
	(segment
		(start 217.75 149.75)
		(end 218.9 148.6)
		(width 0.1)
		(layer "In2.Cu")
		(net 239)
	)
	(segment
		(start 206.65 156.4)
		(end 207.6 156.4)
		(width 0.1)
		(layer "In2.Cu")
		(net 239)
	)
	(segment
		(start 216.35 151.8)
		(end 216.35 150.5)
		(width 0.1)
		(layer "In2.Cu")
		(net 239)
	)
	(segment
		(start 203.5125 155.0625)
		(end 204.325 155.875)
		(width 0.1)
		(layer "In2.Cu")
		(net 239)
	)
	(segment
		(start 206.125 155.875)
		(end 206.65 156.4)
		(width 0.1)
		(layer "In2.Cu")
		(net 239)
	)
	(segment
		(start 195.0005 156.0005)
		(end 195.5 156.5)
		(width 0.256)
		(layer "F.Cu")
		(net 242)
	)
	(segment
		(start 218.85 147.625)
		(end 218.875 147.6)
		(width 0.15)
		(layer "F.Cu")
		(net 242)
	)
	(segment
		(start 222.472 146.85)
		(end 223.342 146.85)
		(width 0.201)
		(layer "F.Cu")
		(net 242)
	)
	(segment
		(start 221.244001 147.6)
		(end 221.722 147.6)
		(width 0.201)
		(layer "F.Cu")
		(net 242)
	)
	(segment
		(start 221.722 147.6)
		(end 222.472 146.85)
		(width 0.201)
		(layer "F.Cu")
		(net 242)
	)
	(segment
		(start 135.424499 173.534)
		(end 135.424499 174.224)
		(width 0.15)
		(layer "F.Cu")
		(net 242)
	)
	(segment
		(start 218.875 147.6)
		(end 221.244001 147.6)
		(width 0.15)
		(layer "F.Cu")
		(net 242)
	)
	(via
		(at 135.424499 174.224)
		(size 0.45)
		(drill 0.1)
		(layers "F.Cu" "B.Cu")
		(remove_unused_layers yes)
		(keep_end_layers yes)
		(zone_layer_connections)
		(net 242)
	)
	(via
		(at 218.85 147.625)
		(size 0.45)
		(drill 0.1)
		(layers "F.Cu" "B.Cu")
		(remove_unused_layers yes)
		(keep_end_layers yes)
		(zone_layer_connections)
		(net 242)
	)
	(via
		(at 195.5 156.5)
		(size 0.45)
		(drill 0.1)
		(layers "F.Cu" "B.Cu")
		(remove_unused_layers yes)
		(keep_end_layers yes)
		(zone_layer_connections)
		(net 242)
	)
	(segment
		(start 136.752672 173.725)
		(end 135.923499 173.725)
		(width 0.15)
		(layer "B.Cu")
		(net 242)
	)
	(segment
		(start 220.75 131.12279)
		(end 214.927209 125.299999)
		(width 0.15)
		(layer "B.Cu")
		(net 242)
	)
	(segment
		(start 137.175 174.575)
		(end 137.175 174.147328)
		(width 0.15)
		(layer "B.Cu")
		(net 242)
	)
	(segment
		(start 220.275 147.625)
		(end 220.75 147.15)
		(width 0.15)
		(layer "B.Cu")
		(net 242)
	)
	(segment
		(start 150.8 175.175)
		(end 137.775 175.175)
		(width 0.15)
		(layer "B.Cu")
		(net 242)
	)
	(segment
		(start 220.75 147.15)
		(end 220.75 131.12279)
		(width 0.15)
		(layer "B.Cu")
		(net 242)
	)
	(segment
		(start 199.722792 131.25)
		(end 178.55 131.25)
		(width 0.15)
		(layer "B.Cu")
		(net 242)
	)
	(segment
		(start 137.175 174.147328)
		(end 136.752672 173.725)
		(width 0.15)
		(layer "B.Cu")
		(net 242)
	)
	(segment
		(start 152.4 157.4)
		(end 152.4 173.575)
		(width 0.15)
		(layer "B.Cu")
		(net 242)
	)
	(segment
		(start 178.55 131.25)
		(end 152.4 157.4)
		(width 0.15)
		(layer "B.Cu")
		(net 242)
	)
	(segment
		(start 152.4 173.575)
		(end 150.8 175.175)
		(width 0.15)
		(layer "B.Cu")
		(net 242)
	)
	(segment
		(start 135.923499 173.725)
		(end 135.424499 174.224)
		(width 0.15)
		(layer "B.Cu")
		(net 242)
	)
	(segment
		(start 137.775 175.175)
		(end 137.175 174.575)
		(width 0.15)
		(layer "B.Cu")
		(net 242)
	)
	(segment
		(start 205.672793 125.299999)
		(end 199.722792 131.25)
		(width 0.15)
		(layer "B.Cu")
		(net 242)
	)
	(segment
		(start 218.85 147.625)
		(end 220.275 147.625)
		(width 0.15)
		(layer "B.Cu")
		(net 242)
	)
	(segment
		(start 214.927209 125.299999)
		(end 205.672793 125.299999)
		(width 0.15)
		(layer "B.Cu")
		(net 242)
	)
	(segment
		(start 203.7 156.125)
		(end 204.0875 156.5125)
		(width 0.1)
		(layer "In2.Cu")
		(net 242)
	)
	(segment
		(start 219.547 150.153)
		(end 219.547 148.803)
		(width 0.1)
		(layer "In2.Cu")
		(net 242)
	)
	(segment
		(start 205.3125 156.5125)
		(end 205.9 157.1)
		(width 0.1)
		(layer "In2.Cu")
		(net 242)
	)
	(segment
		(start 218.5 150.7)
		(end 219 150.7)
		(width 0.1)
		(layer "In2.Cu")
		(net 242)
	)
	(segment
		(start 211.530331 156.65)
		(end 213.840165 154.340165)
		(width 0.1)
		(layer "In2.Cu")
		(net 242)
	)
	(segment
		(start 220.5 147)
		(end 220.189768 146.689768)
		(width 0.1)
		(layer "In2.Cu")
		(net 242)
	)
	(segment
		(start 208.45 156.65)
		(end 211.530331 156.65)
		(width 0.1)
		(layer "In2.Cu")
		(net 242)
	)
	(segment
		(start 217.209835 154.340165)
		(end 217.9 153.65)
		(width 0.1)
		(layer "In2.Cu")
		(net 242)
	)
	(segment
		(start 208 157.1)
		(end 208.45 156.65)
		(width 0.1)
		(layer "In2.Cu")
		(net 242)
	)
	(segment
		(start 219 150.7)
		(end 219.547 150.153)
		(width 0.1)
		(layer "In2.Cu")
		(net 242)
	)
	(segment
		(start 204.0875 156.5125)
		(end 205.3125 156.5125)
		(width 0.1)
		(layer "In2.Cu")
		(net 242)
	)
	(segment
		(start 219.397 146.882537)
		(end 219.397 147.078)
		(width 0.1)
		(layer "In2.Cu")
		(net 242)
	)
	(segment
		(start 220.5 148.25)
		(end 220.5 147)
		(width 0.1)
		(layer "In2.Cu")
		(net 242)
	)
	(segment
		(start 220.15 148.6)
		(end 220.5 148.25)
		(width 0.1)
		(layer "In2.Cu")
		(net 242)
	)
	(segment
		(start 195.5 156.5)
		(end 195.875 156.125)
		(width 0.1)
		(layer "In2.Cu")
		(net 242)
	)
	(segment
		(start 219.75 148.6)
		(end 220.15 148.6)
		(width 0.1)
		(layer "In2.Cu")
		(net 242)
	)
	(segment
		(start 219.397 147.078)
		(end 218.85 147.625)
		(width 0.1)
		(layer "In2.Cu")
		(net 242)
	)
	(segment
		(start 220.189768 146.689768)
		(end 219.589769 146.689768)
		(width 0.1)
		(layer "In2.Cu")
		(net 242)
	)
	(segment
		(start 217.9 153.65)
		(end 217.9 151.3)
		(width 0.1)
		(layer "In2.Cu")
		(net 242)
	)
	(segment
		(start 217.9 151.3)
		(end 218.5 150.7)
		(width 0.1)
		(layer "In2.Cu")
		(net 242)
	)
	(segment
		(start 195.875 156.125)
		(end 203.7 156.125)
		(width 0.1)
		(layer "In2.Cu")
		(net 242)
	)
	(segment
		(start 213.840165 154.340165)
		(end 217.209835 154.340165)
		(width 0.1)
		(layer "In2.Cu")
		(net 242)
	)
	(segment
		(start 205.9 157.1)
		(end 208 157.1)
		(width 0.1)
		(layer "In2.Cu")
		(net 242)
	)
	(segment
		(start 219.547 148.803)
		(end 219.75 148.6)
		(width 0.1)
		(layer "In2.Cu")
		(net 242)
	)
	(segment
		(start 219.589769 146.689768)
		(end 219.397 146.882537)
		(width 0.1)
		(layer "In2.Cu")
		(net 242)
	)
	(segment
		(start 221.472 147.1)
		(end 221.672 146.9)
		(width 0.201)
		(layer "F.Cu")
		(net 244)
	)
	(segment
		(start 136.547342 173.532328)
		(end 136.547342 174.222328)
		(width 0.15)
		(layer "F.Cu")
		(net 244)
	)
	(segment
		(start 220.472001 147.1)
		(end 219.922 147.1)
		(width 0.15)
		(layer "F.Cu")
		(net 244)
	)
	(segment
		(start 222.471 144.850999)
		(end 223.342 144.850999)
		(width 0.201)
		(layer "F.Cu")
		(net 244)
	)
	(segment
		(start 221.672 145.65)
		(end 222.471 144.850999)
		(width 0.201)
		(layer "F.Cu")
		(net 244)
	)
	(segment
		(start 221.244001 147.1)
		(end 221.472 147.1)
		(width 0.201)
		(layer "F.Cu")
		(net 244)
	)
	(segment
		(start 221.672 146.9)
		(end 221.672 145.65)
		(width 0.201)
		(layer "F.Cu")
		(net 244)
	)
	(segment
		(start 221.244001 147.1)
		(end 220.472001 147.1)
		(width 0.15)
		(layer "F.Cu")
		(net 244)
	)
	(segment
		(start 197.0005 154.000499)
		(end 197.5 154.5)
		(width 0.256)
		(layer "F.Cu")
		(net 244)
	)
	(via
		(at 136.547342 174.222328)
		(size 0.45)
		(drill 0.1)
		(layers "F.Cu" "B.Cu")
		(remove_unused_layers yes)
		(keep_end_layers yes)
		(zone_layer_connections)
		(net 244)
	)
	(via
		(at 219.922 147.1)
		(size 0.45)
		(drill 0.1)
		(layers "F.Cu" "B.Cu")
		(remove_unused_layers yes)
		(keep_end_layers yes)
		(zone_layer_connections)
		(net 244)
	)
	(via
		(at 197.5 154.5)
		(size 0.45)
		(drill 0.1)
		(layers "F.Cu" "B.Cu")
		(remove_unused_layers yes)
		(keep_end_layers yes)
		(zone_layer_connections)
		(net 244)
	)
	(segment
		(start 152.8 174.05)
		(end 152.8 157.95)
		(width 0.15)
		(layer "B.Cu")
		(net 244)
	)
	(segment
		(start 152.8 157.95)
		(end 179.05 131.7)
		(width 0.15)
		(layer "B.Cu")
		(net 244)
	)
	(segment
		(start 179.05 131.7)
		(end 199.909188 131.7)
		(width 0.15)
		(layer "B.Cu")
		(net 244)
	)
	(segment
		(start 199.909188 131.7)
		(end 205.859189 125.749999)
		(width 0.15)
		(layer "B.Cu")
		(net 244)
	)
	(segment
		(start 205.859189 125.749999)
		(end 214.740813 125.749999)
		(width 0.15)
		(layer "B.Cu")
		(net 244)
	)
	(segment
		(start 137.5 175.675)
		(end 151.175 175.675)
		(width 0.15)
		(layer "B.Cu")
		(net 244)
	)
	(segment
		(start 136.547342 174.222328)
		(end 136.547342 174.722342)
		(width 0.15)
		(layer "B.Cu")
		(net 244)
	)
	(segment
		(start 220.35 131.359186)
		(end 220.35 146.672)
		(width 0.15)
		(layer "B.Cu")
		(net 244)
	)
	(segment
		(start 214.740813 125.749999)
		(end 220.35 131.359186)
		(width 0.15)
		(layer "B.Cu")
		(net 244)
	)
	(segment
		(start 151.175 175.675)
		(end 152.8 174.05)
		(width 0.15)
		(layer "B.Cu")
		(net 244)
	)
	(segment
		(start 220.35 146.672)
		(end 219.922 147.1)
		(width 0.15)
		(layer "B.Cu")
		(net 244)
	)
	(segment
		(start 136.547342 174.722342)
		(end 137.5 175.675)
		(width 0.15)
		(layer "B.Cu")
		(net 244)
	)
	(segment
		(start 217.4 151.034501)
		(end 218.2 150.234501)
		(width 0.1)
		(layer "In2.Cu")
		(net 244)
	)
	(segment
		(start 217.090165 153.709835)
		(end 217.4 153.4)
		(width 0.1)
		(layer "In2.Cu")
		(net 244)
	)
	(segment
		(start 197.5 154.5)
		(end 198.05 155.05)
		(width 0.1)
		(layer "In2.Cu")
		(net 244)
	)
	(segment
		(start 219.275 149.525)
		(end 219.275 147.747)
		(width 0.1)
		(layer "In2.Cu")
		(net 244)
	)
	(segment
		(start 199.95 155.65)
		(end 200.175 155.875)
		(width 0.1)
		(layer "In2.Cu")
		(net 244)
	)
	(segment
		(start 205.725 156.175)
		(end 206.3 156.75)
		(width 0.1)
		(layer "In2.Cu")
		(net 244)
	)
	(segment
		(start 199.95 155.2625)
		(end 199.95 155.65)
		(width 0.1)
		(layer "In2.Cu")
		(net 244)
	)
	(segment
		(start 200.175 155.875)
		(end 202.825 155.875)
		(width 0.1)
		(layer "In2.Cu")
		(net 244)
	)
	(segment
		(start 219.275 147.747)
		(end 219.922 147.1)
		(width 0.1)
		(layer "In2.Cu")
		(net 244)
	)
	(segment
		(start 206.3 156.75)
		(end 207.85 156.75)
		(width 0.1)
		(layer "In2.Cu")
		(net 244)
	)
	(segment
		(start 203.7 155.7)
		(end 204.175 156.175)
		(width 0.1)
		(layer "In2.Cu")
		(net 244)
	)
	(segment
		(start 210.694669 156.425)
		(end 213.409835 153.709835)
		(width 0.1)
		(layer "In2.Cu")
		(net 244)
	)
	(segment
		(start 217.4 153.4)
		(end 217.4 151.034501)
		(width 0.1)
		(layer "In2.Cu")
		(net 244)
	)
	(segment
		(start 207.85 156.75)
		(end 208.175 156.425)
		(width 0.1)
		(layer "In2.Cu")
		(net 244)
	)
	(segment
		(start 218.565499 150.234501)
		(end 219.275 149.525)
		(width 0.1)
		(layer "In2.Cu")
		(net 244)
	)
	(segment
		(start 199.7375 155.05)
		(end 199.95 155.2625)
		(width 0.1)
		(layer "In2.Cu")
		(net 244)
	)
	(segment
		(start 208.175 156.425)
		(end 210.694669 156.425)
		(width 0.1)
		(layer "In2.Cu")
		(net 244)
	)
	(segment
		(start 204.175 156.175)
		(end 205.725 156.175)
		(width 0.1)
		(layer "In2.Cu")
		(net 244)
	)
	(segment
		(start 218.2 150.234501)
		(end 218.565499 150.234501)
		(width 0.1)
		(layer "In2.Cu")
		(net 244)
	)
	(segment
		(start 202.825 155.875)
		(end 203 155.7)
		(width 0.1)
		(layer "In2.Cu")
		(net 244)
	)
	(segment
		(start 198.05 155.05)
		(end 199.7375 155.05)
		(width 0.1)
		(layer "In2.Cu")
		(net 244)
	)
	(segment
		(start 213.409835 153.709835)
		(end 217.090165 153.709835)
		(width 0.1)
		(layer "In2.Cu")
		(net 244)
	)
	(segment
		(start 203 155.7)
		(end 203.7 155.7)
		(width 0.1)
		(layer "In2.Cu")
		(net 244)
	)
	(segment
		(start 128.600676 180.458)
		(end 129.505678 180.458)
		(width 0.16)
		(layer "F.Cu")
		(net 246)
	)
	(segment
		(start 130.577576 179.860127)
		(end 130.31489 180.122813)
		(width 0.16)
		(layer "F.Cu")
		(net 246)
	)
	(segment
		(start 130.855139 179.787627)
		(end 130.752608 179.787627)
		(width 0.16)
		(layer "F.Cu")
		(net 246)
	)
	(segment
		(start 128.371325 180.553)
		(end 127.801 180.553)
		(width 0.16)
		(layer "F.Cu")
		(net 246)
	)
	(via
		(at 130.855139 179.787627)
		(size 0.45)
		(drill 0.1)
		(layers "F.Cu" "B.Cu")
		(remove_unused_layers yes)
		(keep_end_layers yes)
		(zone_layer_connections)
		(net 246)
	)
	(arc
		(start 130.752608 179.787627)
		(mid 130.657881 179.806469)
		(end 130.577576 179.860127)
		(width 0.16)
		(layer "F.Cu")
		(net 246)
	)
	(arc
		(start 129.505678 180.458)
		(mid 129.94362 180.370887)
		(end 130.31489 180.122813)
		(width 0.16)
		(layer "F.Cu")
		(net 246)
	)
	(arc
		(start 128.600676 180.458)
		(mid 128.538614 180.470344)
		(end 128.486001 180.5055)
		(width 0.16)
		(layer "F.Cu")
		(net 246)
	)
	(arc
		(start 128.371325 180.553)
		(mid 128.433387 180.540655)
		(end 128.486001 180.5055)
		(width 0.16)
		(layer "F.Cu")
		(net 246)
	)
	(segment
		(start 135.242374 187.152625)
		(end 135.242374 187.152626)
		(width 0.16)
		(layer "B.Cu")
		(net 246)
	)
	(segment
		(start 175.076679 180.994116)
		(end 186.54881 169.521985)
		(width 0.16)
		(layer "B.Cu")
		(net 246)
	)
	(segment
		(start 186.677501 168.0975)
		(end 186.510001 167.93)
		(width 0.16)
		(layer "B.Cu")
		(net 246)
	)
	(segment
		(start 130.855139 179.787627)
		(end 130.752608 179.787627)
		(width 0.16)
		(layer "B.Cu")
		(net 246)
	)
	(segment
		(start 135.642374 187.152626)
		(end 135.642374 187.152625)
		(width 0.16)
		(layer "B.Cu")
		(net 246)
	)
	(segment
		(start 136.842425 187.152574)
		(end 136.842425 187.152575)
		(width 0.16)
		(layer "B.Cu")
		(net 246)
	)
	(segment
		(start 136.58485 187.010149)
		(end 136.7 187.010149)
		(width 0.16)
		(layer "B.Cu")
		(net 246)
	)
	(segment
		(start 134.984748 187.010251)
		(end 135.1 187.010251)
		(width 0.16)
		(layer "B.Cu")
		(net 246)
	)
	(segment
		(start 137.1 187.295)
		(end 141.85023 187.295)
		(width 0.16)
		(layer "B.Cu")
		(net 246)
	)
	(segment
		(start 130.577576 179.860127)
		(end 130.39675 180.040953)
		(width 0.16)
		(layer "B.Cu")
		(net 246)
	)
	(segment
		(start 136.442425 187.152575)
		(end 136.442425 187.152574)
		(width 0.16)
		(layer "B.Cu")
		(net 246)
	)
	(segment
		(start 130.235 180.431452)
		(end 130.235 183.387084)
		(width 0.16)
		(layer "B.Cu")
		(net 246)
	)
	(segment
		(start 136.98485 187.295)
		(end 137.1 187.295)
		(width 0.16)
		(layer "B.Cu")
		(net 246)
	)
	(segment
		(start 134.842374 187.152626)
		(end 134.842374 187.152625)
		(width 0.16)
		(layer "B.Cu")
		(net 246)
	)
	(segment
		(start 186.845001 168.806916)
		(end 186.845001 168.50188)
		(width 0.16)
		(layer "B.Cu")
		(net 246)
	)
	(segment
		(start 135.784748 187.010251)
		(end 135.9 187.010251)
		(width 0.16)
		(layer "B.Cu")
		(net 246)
	)
	(segment
		(start 134.142915 187.295)
		(end 134.7 187.295)
		(width 0.16)
		(layer "B.Cu")
		(net 246)
	)
	(segment
		(start 135.384748 187.295)
		(end 135.5 187.295)
		(width 0.16)
		(layer "B.Cu")
		(net 246)
	)
	(segment
		(start 145.495865 185.784929)
		(end 147.192003 184.088792)
		(width 0.16)
		(layer "B.Cu")
		(net 246)
	)
	(segment
		(start 151.039759 182.495)
		(end 171.453224 182.495)
		(width 0.16)
		(layer "B.Cu")
		(net 246)
	)
	(segment
		(start 136.184748 187.295)
		(end 136.3 187.295)
		(width 0.16)
		(layer "B.Cu")
		(net 246)
	)
	(segment
		(start 136.042374 187.152625)
		(end 136.042374 187.152626)
		(width 0.16)
		(layer "B.Cu")
		(net 246)
	)
	(arc
		(start 135.5 187.295)
		(mid 135.600674 187.2533)
		(end 135.642374 187.152626)
		(width 0.16)
		(layer "B.Cu")
		(net 246)
	)
	(arc
		(start 147.192003 184.088792)
		(mid 148.957368 182.909213)
		(end 151.039759 182.495)
		(width 0.16)
		(layer "B.Cu")
		(net 246)
	)
	(arc
		(start 135.242374 187.152626)
		(mid 135.284074 187.2533)
		(end 135.384748 187.295)
		(width 0.16)
		(layer "B.Cu")
		(net 246)
	)
	(arc
		(start 135.1 187.010251)
		(mid 135.200674 187.051951)
		(end 135.242374 187.152625)
		(width 0.16)
		(layer "B.Cu")
		(net 246)
	)
	(arc
		(start 186.845001 168.50188)
		(mid 186.801469 168.283031)
		(end 186.677501 168.0975)
		(width 0.16)
		(layer "B.Cu")
		(net 246)
	)
	(arc
		(start 136.7 187.010149)
		(mid 136.80071 187.051864)
		(end 136.842425 187.152574)
		(width 0.16)
		(layer "B.Cu")
		(net 246)
	)
	(arc
		(start 186.54881 169.521985)
		(mid 186.768023 169.193908)
		(end 186.845001 168.806916)
		(width 0.16)
		(layer "B.Cu")
		(net 246)
	)
	(arc
		(start 135.9 187.010251)
		(mid 136.000674 187.051951)
		(end 136.042374 187.152625)
		(width 0.16)
		(layer "B.Cu")
		(net 246)
	)
	(arc
		(start 134.842374 187.152625)
		(mid 134.884074 187.051951)
		(end 134.984748 187.010251)
		(width 0.16)
		(layer "B.Cu")
		(net 246)
	)
	(arc
		(start 134.7 187.295)
		(mid 134.800674 187.2533)
		(end 134.842374 187.152626)
		(width 0.16)
		(layer "B.Cu")
		(net 246)
	)
	(arc
		(start 136.842425 187.152575)
		(mid 136.88414 187.253285)
		(end 136.98485 187.295)
		(width 0.16)
		(layer "B.Cu")
		(net 246)
	)
	(arc
		(start 130.235 183.387084)
		(mid 130.532472 184.882578)
		(end 131.379602 186.150398)
		(width 0.16)
		(layer "B.Cu")
		(net 246)
	)
	(arc
		(start 131.379602 186.150398)
		(mid 132.64742 186.997527)
		(end 134.142915 187.295)
		(width 0.16)
		(layer "B.Cu")
		(net 246)
	)
	(arc
		(start 136.042374 187.152626)
		(mid 136.084074 187.2533)
		(end 136.184748 187.295)
		(width 0.16)
		(layer "B.Cu")
		(net 246)
	)
	(arc
		(start 136.442425 187.152574)
		(mid 136.48414 187.051864)
		(end 136.58485 187.010149)
		(width 0.16)
		(layer "B.Cu")
		(net 246)
	)
	(arc
		(start 130.39675 180.040953)
		(mid 130.277037 180.220115)
		(end 130.235 180.431452)
		(width 0.16)
		(layer "B.Cu")
		(net 246)
	)
	(arc
		(start 130.752608 179.787627)
		(mid 130.657881 179.806469)
		(end 130.577576 179.860127)
		(width 0.16)
		(layer "B.Cu")
		(net 246)
	)
	(arc
		(start 136.3 187.295)
		(mid 136.40071 187.253285)
		(end 136.442425 187.152575)
		(width 0.16)
		(layer "B.Cu")
		(net 246)
	)
	(arc
		(start 171.453224 182.495)
		(mid 173.414224 182.104933)
		(end 175.076679 180.994116)
		(width 0.16)
		(layer "B.Cu")
		(net 246)
	)
	(arc
		(start 135.642374 187.152625)
		(mid 135.684074 187.051951)
		(end 135.784748 187.010251)
		(width 0.16)
		(layer "B.Cu")
		(net 246)
	)
	(arc
		(start 141.85023 187.295)
		(mid 143.823233 186.902545)
		(end 145.495865 185.784929)
		(width 0.16)
		(layer "B.Cu")
		(net 246)
	)
	(segment
		(start 128.371325 180.053)
		(end 127.801 180.053)
		(width 0.16)
		(layer "F.Cu")
		(net 248)
	)
	(segment
		(start 130.358372 179.640923)
		(end 130.094481 179.904814)
		(width 0.16)
		(layer "F.Cu")
		(net 248)
	)
	(segment
		(start 129.507377 180.148)
		(end 128.600676 180.148)
		(width 0.16)
		(layer "F.Cu")
		(net 248)
	)
	(segment
		(start 130.430873 179.363361)
		(end 130.430873 179.465892)
		(width 0.16)
		(layer "F.Cu")
		(net 248)
	)
	(via
		(at 130.430873 179.363361)
		(size 0.45)
		(drill 0.1)
		(layers "F.Cu" "B.Cu")
		(remove_unused_layers yes)
		(keep_end_layers yes)
		(zone_layer_connections)
		(net 248)
	)
	(arc
		(start 129.507377 180.148)
		(mid 129.825115 180.084798)
		(end 130.094481 179.904814)
		(width 0.16)
		(layer "F.Cu")
		(net 248)
	)
	(arc
		(start 128.486001 180.1005)
		(mid 128.538614 180.135655)
		(end 128.600676 180.148)
		(width 0.16)
		(layer "F.Cu")
		(net 248)
	)
	(arc
		(start 128.486001 180.1005)
		(mid 128.433387 180.065344)
		(end 128.371325 180.053)
		(width 0.16)
		(layer "F.Cu")
		(net 248)
	)
	(arc
		(start 130.430873 179.465892)
		(mid 130.41203 179.560618)
		(end 130.358372 179.640923)
		(width 0.16)
		(layer "F.Cu")
		(net 248)
	)
	(segment
		(start 186.769909 169.739294)
		(end 175.297996 181.211207)
		(width 0.16)
		(layer "B.Cu")
		(net 248)
	)
	(segment
		(start 187.3225 168.097499)
		(end 187.49 167.93)
		(width 0.16)
		(layer "B.Cu")
		(net 248)
	)
	(segment
		(start 171.45024 182.805)
		(end 151.037884 182.805)
		(width 0.16)
		(layer "B.Cu")
		(net 248)
	)
	(segment
		(start 187.155001 168.501879)
		(end 187.155001 168.809601)
		(width 0.16)
		(layer "B.Cu")
		(net 248)
	)
	(segment
		(start 145.707996 186.011206)
		(end 147.412536 184.306667)
		(width 0.16)
		(layer "B.Cu")
		(net 248)
	)
	(segment
		(start 130.358372 179.640923)
		(end 130.177936 179.821359)
		(width 0.16)
		(layer "B.Cu")
		(net 248)
	)
	(segment
		(start 129.925 183.387087)
		(end 129.925 180.432002)
		(width 0.16)
		(layer "B.Cu")
		(net 248)
	)
	(segment
		(start 141.86024 187.605)
		(end 134.142912 187.605)
		(width 0.16)
		(layer "B.Cu")
		(net 248)
	)
	(segment
		(start 130.430873 179.363361)
		(end 130.430873 179.465892)
		(width 0.16)
		(layer "B.Cu")
		(net 248)
	)
	(arc
		(start 131.160398 186.369602)
		(mid 132.528787 187.28393)
		(end 134.142912 187.605)
		(width 0.16)
		(layer "B.Cu")
		(net 248)
	)
	(arc
		(start 130.430873 179.465892)
		(mid 130.41203 179.560618)
		(end 130.358372 179.640923)
		(width 0.16)
		(layer "B.Cu")
		(net 248)
	)
	(arc
		(start 141.86024 187.605)
		(mid 143.94263 187.190786)
		(end 145.707996 186.011206)
		(width 0.16)
		(layer "B.Cu")
		(net 248)
	)
	(arc
		(start 129.925 183.387087)
		(mid 130.246069 185.001212)
		(end 131.160398 186.369602)
		(width 0.16)
		(layer "B.Cu")
		(net 248)
	)
	(arc
		(start 151.037884 182.805)
		(mid 149.07586 183.195271)
		(end 147.412536 184.306667)
		(width 0.16)
		(layer "B.Cu")
		(net 248)
	)
	(arc
		(start 171.45024 182.805)
		(mid 173.53263 182.390786)
		(end 175.297996 181.211207)
		(width 0.16)
		(layer "B.Cu")
		(net 248)
	)
	(arc
		(start 187.155001 168.501879)
		(mid 187.198532 168.28303)
		(end 187.3225 168.097499)
		(width 0.16)
		(layer "B.Cu")
		(net 248)
	)
	(arc
		(start 186.769909 169.739294)
		(mid 187.054918 169.312747)
		(end 187.155001 168.809601)
		(width 0.16)
		(layer "B.Cu")
		(net 248)
	)
	(arc
		(start 129.925 180.432002)
		(mid 129.990735 180.101524)
		(end 130.177936 179.821359)
		(width 0.16)
		(layer "B.Cu")
		(net 248)
	)
	(segment
		(start 113.154 154.315)
		(end 113.775 154.315)
		(width 0.2)
		(layer "F.Cu")
		(net 249)
	)
	(segment
		(start 113.775 154.315)
		(end 114.44 153.65)
		(width 0.2)
		(layer "F.Cu")
		(net 249)
	)
	(segment
		(start 114.44 153.65)
		(end 115.265 153.65)
		(width 0.2)
		(layer "F.Cu")
		(net 249)
	)
	(segment
		(start 230.941501 158.841501)
		(end 234.35 162.25)
		(width 0.182)
		(layer "F.Cu")
		(net 250)
	)
	(segment
		(start 228.5265 158.841501)
		(end 230.941501 158.841501)
		(width 0.182)
		(layer "F.Cu")
		(net 250)
	)
	(segment
		(start 234.35 162.25)
		(end 234.35 165.15)
		(width 0.182)
		(layer "F.Cu")
		(net 250)
	)
	(segment
		(start 186.34 194.276111)
		(end 186.34 196.473296)
		(width 0.22)
		(layer "B.Cu")
		(net 252)
	)
	(segment
		(start 186.34 196.473296)
		(end 186.34 197.14)
		(width 0.22)
		(layer "B.Cu")
		(net 252)
	)
	(segment
		(start 186.506249 193.874749)
		(end 186.672499 193.7085)
		(width 0.22)
		(layer "B.Cu")
		(net 252)
	)
	(segment
		(start 186.34 197.14)
		(end 186.65 197.45)
		(width 0.22)
		(layer "B.Cu")
		(net 252)
	)
	(segment
		(start 186.65 197.45)
		(end 186.65 199.25)
		(width 0.22)
		(layer "B.Cu")
		(net 252)
	)
	(arc
		(start 186.506249 193.874749)
		(mid 186.383206 194.058895)
		(end 186.34 194.276111)
		(width 0.22)
		(layer "B.Cu")
		(net 252)
	)
	(segment
		(start 193.65 197.45)
		(end 193.65 199.25)
		(width 0.22)
		(layer "B.Cu")
		(net 253)
	)
	(segment
		(start 193.96 194.28465)
		(end 193.96 196.469296)
		(width 0.22)
		(layer "B.Cu")
		(net 253)
	)
	(segment
		(start 193.791249 193.87725)
		(end 193.622499 193.7085)
		(width 0.22)
		(layer "B.Cu")
		(net 253)
	)
	(segment
		(start 193.96 196.469296)
		(end 193.96 197.14)
		(width 0.22)
		(layer "B.Cu")
		(net 253)
	)
	(segment
		(start 193.96 197.14)
		(end 193.65 197.45)
		(width 0.22)
		(layer "B.Cu")
		(net 253)
	)
	(arc
		(start 193.96 194.28465)
		(mid 193.916143 194.064166)
		(end 193.791249 193.87725)
		(width 0.22)
		(layer "B.Cu")
		(net 253)
	)
	(segment
		(start 194.65 197.45)
		(end 194.65 199.25)
		(width 0.22)
		(layer "B.Cu")
		(net 254)
	)
	(segment
		(start 194.506249 193.874749)
		(end 194.672499 193.7085)
		(width 0.22)
		(layer "B.Cu")
		(net 254)
	)
	(segment
		(start 194.34 196.473296)
		(end 194.34 194.276111)
		(width 0.22)
		(layer "B.Cu")
		(net 254)
	)
	(segment
		(start 194.34 197.14)
		(end 194.65 197.45)
		(width 0.22)
		(layer "B.Cu")
		(net 254)
	)
	(segment
		(start 194.34 196.473296)
		(end 194.34 197.14)
		(width 0.22)
		(layer "B.Cu")
		(net 254)
	)
	(arc
		(start 194.34 194.276111)
		(mid 194.383206 194.058895)
		(end 194.506249 193.874749)
		(width 0.22)
		(layer "B.Cu")
		(net 254)
	)
	(segment
		(start 189.65 197.45)
		(end 189.65 199.25)
		(width 0.22)
		(layer "B.Cu")
		(net 255)
	)
	(segment
		(start 189.96 197.14)
		(end 189.65 197.45)
		(width 0.22)
		(layer "B.Cu")
		(net 255)
	)
	(segment
		(start 189.96 196.469296)
		(end 189.96 194.28465)
		(width 0.22)
		(layer "B.Cu")
		(net 255)
	)
	(segment
		(start 189.96 196.469296)
		(end 189.96 197.14)
		(width 0.22)
		(layer "B.Cu")
		(net 255)
	)
	(segment
		(start 189.791249 193.87725)
		(end 189.622499 193.7085)
		(width 0.22)
		(layer "B.Cu")
		(net 255)
	)
	(arc
		(start 189.791249 193.87725)
		(mid 189.916143 194.064166)
		(end 189.96 194.28465)
		(width 0.22)
		(layer "B.Cu")
		(net 255)
	)
	(segment
		(start 190.34 196.473296)
		(end 190.34 197.14)
		(width 0.22)
		(layer "B.Cu")
		(net 256)
	)
	(segment
		(start 190.506249 193.874749)
		(end 190.672499 193.7085)
		(width 0.22)
		(layer "B.Cu")
		(net 256)
	)
	(segment
		(start 190.65 197.45)
		(end 190.65 199.25)
		(width 0.22)
		(layer "B.Cu")
		(net 256)
	)
	(segment
		(start 190.34 194.276111)
		(end 190.34 196.473296)
		(width 0.22)
		(layer "B.Cu")
		(net 256)
	)
	(segment
		(start 190.34 197.14)
		(end 190.65 197.45)
		(width 0.22)
		(layer "B.Cu")
		(net 256)
	)
	(arc
		(start 190.506249 193.874749)
		(mid 190.383206 194.058895)
		(end 190.34 194.276111)
		(width 0.22)
		(layer "B.Cu")
		(net 256)
	)
	(segment
		(start 185.96 196.469296)
		(end 185.96 197.14)
		(width 0.22)
		(layer "B.Cu")
		(net 257)
	)
	(segment
		(start 185.96 196.469296)
		(end 185.96 194.28465)
		(width 0.22)
		(layer "B.Cu")
		(net 257)
	)
	(segment
		(start 185.65 197.45)
		(end 185.65 199.25)
		(width 0.22)
		(layer "B.Cu")
		(net 257)
	)
	(segment
		(start 185.791249 193.87725)
		(end 185.622499 193.7085)
		(width 0.22)
		(layer "B.Cu")
		(net 257)
	)
	(segment
		(start 185.96 197.14)
		(end 185.65 197.45)
		(width 0.22)
		(layer "B.Cu")
		(net 257)
	)
	(arc
		(start 185.791249 193.87725)
		(mid 185.916143 194.064166)
		(end 185.96 194.28465)
		(width 0.22)
		(layer "B.Cu")
		(net 257)
	)
	(segment
		(start 181.791249 193.87725)
		(end 181.622499 193.7085)
		(width 0.22)
		(layer "B.Cu")
		(net 258)
	)
	(segment
		(start 181.65 197.45)
		(end 181.65 199.25)
		(width 0.22)
		(layer "B.Cu")
		(net 258)
	)
	(segment
		(start 181.96 196.469296)
		(end 181.96 194.28465)
		(width 0.22)
		(layer "B.Cu")
		(net 258)
	)
	(segment
		(start 181.96 196.469296)
		(end 181.96 197.14)
		(width 0.22)
		(layer "B.Cu")
		(net 258)
	)
	(segment
		(start 181.96 197.14)
		(end 181.65 197.45)
		(width 0.22)
		(layer "B.Cu")
		(net 258)
	)
	(arc
		(start 181.96 194.28465)
		(mid 181.916143 194.064166)
		(end 181.791249 193.87725)
		(width 0.22)
		(layer "B.Cu")
		(net 258)
	)
	(segment
		(start 182.65 197.45)
		(end 182.65 199.25)
		(width 0.22)
		(layer "B.Cu")
		(net 259)
	)
	(segment
		(start 182.34 196.473296)
		(end 182.34 197.14)
		(width 0.22)
		(layer "B.Cu")
		(net 259)
	)
	(segment
		(start 182.34 196.473296)
		(end 182.34 194.276111)
		(width 0.22)
		(layer "B.Cu")
		(net 259)
	)
	(segment
		(start 182.506249 193.874749)
		(end 182.672499 193.7085)
		(width 0.22)
		(layer "B.Cu")
		(net 259)
	)
	(segment
		(start 182.34 197.14)
		(end 182.65 197.45)
		(width 0.22)
		(layer "B.Cu")
		(net 259)
	)
	(arc
		(start 182.34 194.276111)
		(mid 182.383206 194.058895)
		(end 182.506249 193.874749)
		(width 0.22)
		(layer "B.Cu")
		(net 259)
	)
	(segment
		(start 121.05 113.216461)
		(end 121.05 114.08269)
		(width 0.114)
		(layer "F.Cu")
		(net 266)
	)
	(segment
		(start 132.319602 180.440633)
		(end 132.422133 180.440633)
		(width 0.16)
		(layer "F.Cu")
		(net 267)
	)
	(segment
		(start 132.14457 180.513133)
		(end 131.458387 181.199316)
		(width 0.16)
		(layer "F.Cu")
		(net 267)
	)
	(segment
		(start 128.371325 182.053)
		(end 127.801 182.053)
		(width 0.16)
		(layer "F.Cu")
		(net 267)
	)
	(segment
		(start 129.626763 181.958)
		(end 128.600676 181.958)
		(width 0.16)
		(layer "F.Cu")
		(net 267)
	)
	(via
		(at 132.422133 180.440633)
		(size 0.45)
		(drill 0.1)
		(layers "F.Cu" "B.Cu")
		(remove_unused_layers yes)
		(keep_end_layers yes)
		(zone_layer_connections)
		(net 267)
	)
	(arc
		(start 128.486001 182.0055)
		(mid 128.433387 182.040655)
		(end 128.371325 182.053)
		(width 0.16)
		(layer "F.Cu")
		(net 267)
	)
	(arc
		(start 128.486001 182.0055)
		(mid 128.538614 181.970344)
		(end 128.600676 181.958)
		(width 0.16)
		(layer "F.Cu")
		(net 267)
	)
	(arc
		(start 132.319602 180.440633)
		(mid 132.224875 180.459475)
		(end 132.14457 180.513133)
		(width 0.16)
		(layer "F.Cu")
		(net 267)
	)
	(arc
		(start 129.626763 181.958)
		(mid 130.618031 181.760824)
		(end 131.458387 181.199316)
		(width 0.16)
		(layer "F.Cu")
		(net 267)
	)
	(segment
		(start 176.268378 178.724318)
		(end 176.091969 178.900728)
		(width 0.16)
		(layer "B.Cu")
		(net 267)
	)
	(segment
		(start 180.824397 173.156399)
		(end 177.880398 176.100398)
		(width 0.16)
		(layer "B.Cu")
		(net 267)
	)
	(segment
		(start 136.302175 185.222825)
		(end 136.302175 185.222824)
		(width 0.16)
		(layer "B.Cu")
		(net 267)
	)
	(segment
		(start 175.914824 178.900729)
		(end 175.914825 178.900727)
		(width 0.16)
		(layer "B.Cu")
		(net 267)
	)
	(segment
		(start 184.510001 167.93)
		(end 184.677501 168.0975)
		(width 0.16)
		(layer "B.Cu")
		(net 267)
	)
	(segment
		(start 177.703318 176.100398)
		(end 177.703319 176.100398)
		(width 0.16)
		(layer "B.Cu")
		(net 267)
	)
	(segment
		(start 136.662175 185.222824)
		(end 136.662175 185.222825)
		(width 0.16)
		(layer "B.Cu")
		(net 267)
	)
	(segment
		(start 177.060756 177.75563)
		(end 176.444358 177.139232)
		(width 0.16)
		(layer "B.Cu")
		(net 267)
	)
	(segment
		(start 136.52 185.365)
		(end 136.44435 185.365)
		(width 0.16)
		(layer "B.Cu")
		(net 267)
	)
	(segment
		(start 176.798372 176.786138)
		(end 177.106115 177.093881)
		(width 0.16)
		(layer "B.Cu")
		(net 267)
	)
	(segment
		(start 177.703319 176.100398)
		(end 177.593716 175.990795)
		(width 0.16)
		(layer "B.Cu")
		(net 267)
	)
	(segment
		(start 135.942175 185.222824)
		(end 135.942175 185.222825)
		(width 0.16)
		(layer "B.Cu")
		(net 267)
	)
	(segment
		(start 184.845001 168.50188)
		(end 184.845001 168.756276)
		(width 0.16)
		(layer "B.Cu")
		(net 267)
	)
	(segment
		(start 137.96 185.365)
		(end 137.884408 185.365)
		(width 0.16)
		(layer "B.Cu")
		(net 267)
	)
	(segment
		(start 175.960602 178.239399)
		(end 176.268377 178.547174)
		(width 0.16)
		(layer "B.Cu")
		(net 267)
	)
	(segment
		(start 170.607491 181.245)
		(end 149.839759 181.245)
		(width 0.16)
		(layer "B.Cu")
		(net 267)
	)
	(segment
		(start 175.189674 178.791126)
		(end 175.189672 178.791127)
		(width 0.16)
		(layer "B.Cu")
		(net 267)
	)
	(segment
		(start 175.827949 177.139232)
		(end 175.652398 177.314782)
		(width 0.16)
		(layer "B.Cu")
		(net 267)
	)
	(segment
		(start 137.022175 185.222825)
		(end 137.022175 185.222824)
		(width 0.16)
		(layer "B.Cu")
		(net 267)
	)
	(segment
		(start 175.960602 178.239395)
		(end 175.960602 178.239399)
		(width 0.16)
		(layer "B.Cu")
		(net 267)
	)
	(segment
		(start 141.339295 185.365)
		(end 137.96 185.365)
		(width 0.16)
		(layer "B.Cu")
		(net 267)
	)
	(segment
		(start 137.6 185.080592)
		(end 137.524408 185.080592)
		(width 0.16)
		(layer "B.Cu")
		(net 267)
	)
	(segment
		(start 176.978231 175.990795)
		(end 176.798372 176.170653)
		(width 0.16)
		(layer "B.Cu")
		(net 267)
	)
	(segment
		(start 131.805 182.09425)
		(end 131.805 181.071437)
		(width 0.16)
		(layer "B.Cu")
		(net 267)
	)
	(segment
		(start 132.819602 184.350398)
		(end 132.682905 184.213701)
		(width 0.16)
		(layer "B.Cu")
		(net 267)
	)
	(segment
		(start 177.414309 177.580053)
		(end 177.238732 177.755631)
		(width 0.16)
		(layer "B.Cu")
		(net 267)
	)
	(segment
		(start 175.652398 177.931191)
		(end 175.960602 178.239395)
		(width 0.16)
		(layer "B.Cu")
		(net 267)
	)
	(segment
		(start 177.106116 177.093885)
		(end 177.414308 177.402077)
		(width 0.16)
		(layer "B.Cu")
		(net 267)
	)
	(segment
		(start 131.959668 180.698035)
		(end 132.14457 180.513133)
		(width 0.16)
		(layer "B.Cu")
		(net 267)
	)
	(segment
		(start 177.414308 177.580055)
		(end 177.414309 177.580053)
		(width 0.16)
		(layer "B.Cu")
		(net 267)
	)
	(segment
		(start 176.798372 176.786139)
		(end 176.798372 176.786138)
		(width 0.16)
		(layer "B.Cu")
		(net 267)
	)
	(segment
		(start 136.88 185.080649)
		(end 136.80435 185.080649)
		(width 0.16)
		(layer "B.Cu")
		(net 267)
	)
	(segment
		(start 132.319602 180.440633)
		(end 132.422133 180.440633)
		(width 0.16)
		(layer "B.Cu")
		(net 267)
	)
	(segment
		(start 175.827948 177.139232)
		(end 175.827949 177.139232)
		(width 0.16)
		(layer "B.Cu")
		(net 267)
	)
	(segment
		(start 176.268378 178.724319)
		(end 176.268378 178.724318)
		(width 0.16)
		(layer "B.Cu")
		(net 267)
	)
	(segment
		(start 184.576642 169.404153)
		(end 180.824397 173.156399)
		(width 0.16)
		(layer "B.Cu")
		(net 267)
	)
	(segment
		(start 175.914825 178.900727)
		(end 175.805224 178.791126)
		(width 0.16)
		(layer "B.Cu")
		(net 267)
	)
	(segment
		(start 177.060755 177.75563)
		(end 177.060756 177.75563)
		(width 0.16)
		(layer "B.Cu")
		(net 267)
	)
	(segment
		(start 136.16 185.080649)
		(end 136.08435 185.080649)
		(width 0.16)
		(layer "B.Cu")
		(net 267)
	)
	(segment
		(start 175.652397 177.931191)
		(end 175.652398 177.931191)
		(width 0.16)
		(layer "B.Cu")
		(net 267)
	)
	(segment
		(start 137.24 185.365)
		(end 137.16435 185.365)
		(width 0.16)
		(layer "B.Cu")
		(net 267)
	)
	(segment
		(start 175.189672 178.791127)
		(end 174.240734 179.740062)
		(width 0.16)
		(layer "B.Cu")
		(net 267)
	)
	(segment
		(start 145.992002 182.838792)
		(end 144.96946 183.861335)
		(width 0.16)
		(layer "B.Cu")
		(net 267)
	)
	(segment
		(start 177.106115 177.093881)
		(end 177.106116 177.093885)
		(width 0.16)
		(layer "B.Cu")
		(net 267)
	)
	(segment
		(start 135.8 185.365)
		(end 135.269067 185.365)
		(width 0.16)
		(layer "B.Cu")
		(net 267)
	)
	(segment
		(start 176.97823 175.990795)
		(end 176.978231 175.990795)
		(width 0.16)
		(layer "B.Cu")
		(net 267)
	)
	(arc
		(start 137.022175 185.222824)
		(mid 136.980533 185.122291)
		(end 136.88 185.080649)
		(width 0.16)
		(layer "B.Cu")
		(net 267)
	)
	(arc
		(start 144.96946 183.861335)
		(mid 143.303926 184.97421)
		(end 141.339295 185.365)
		(width 0.16)
		(layer "B.Cu")
		(net 267)
	)
	(arc
		(start 177.238732 177.755631)
		(mid 177.149744 177.79249)
		(end 177.060755 177.75563)
		(width 0.16)
		(layer "B.Cu")
		(net 267)
	)
	(arc
		(start 137.382204 185.222796)
		(mid 137.340553 185.323349)
		(end 137.24 185.365)
		(width 0.16)
		(layer "B.Cu")
		(net 267)
	)
	(arc
		(start 132.682905 184.213701)
		(mid 132.03316 183.241288)
		(end 131.805 182.09425)
		(width 0.16)
		(layer "B.Cu")
		(net 267)
	)
	(arc
		(start 136.80435 185.080649)
		(mid 136.703817 185.122291)
		(end 136.662175 185.222824)
		(width 0.16)
		(layer "B.Cu")
		(net 267)
	)
	(arc
		(start 132.14457 180.513133)
		(mid 132.224875 180.459475)
		(end 132.319602 180.440633)
		(width 0.16)
		(layer "B.Cu")
		(net 267)
	)
	(arc
		(start 176.798372 176.170653)
		(mid 176.670901 176.478396)
		(end 176.798372 176.786139)
		(width 0.16)
		(layer "B.Cu")
		(net 267)
	)
	(arc
		(start 136.302175 185.222824)
		(mid 136.260533 185.122291)
		(end 136.16 185.080649)
		(width 0.16)
		(layer "B.Cu")
		(net 267)
	)
	(arc
		(start 177.593716 175.990795)
		(mid 177.285973 175.863324)
		(end 176.97823 175.990795)
		(width 0.16)
		(layer "B.Cu")
		(net 267)
	)
	(arc
		(start 149.839759 181.245)
		(mid 147.757368 181.659213)
		(end 145.992002 182.838792)
		(width 0.16)
		(layer "B.Cu")
		(net 267)
	)
	(arc
		(start 136.44435 185.365)
		(mid 136.343817 185.323358)
		(end 136.302175 185.222825)
		(width 0.16)
		(layer "B.Cu")
		(net 267)
	)
	(arc
		(start 136.662175 185.222825)
		(mid 136.620533 185.323358)
		(end 136.52 185.365)
		(width 0.16)
		(layer "B.Cu")
		(net 267)
	)
	(arc
		(start 184.677501 168.0975)
		(mid 184.801469 168.283031)
		(end 184.845001 168.50188)
		(width 0.16)
		(layer "B.Cu")
		(net 267)
	)
	(arc
		(start 174.240734 179.740062)
		(mid 172.573788 180.85388)
		(end 170.607491 181.245)
		(width 0.16)
		(layer "B.Cu")
		(net 267)
	)
	(arc
		(start 177.880398 176.100398)
		(mid 177.791858 176.137072)
		(end 177.703318 176.100398)
		(width 0.16)
		(layer "B.Cu")
		(net 267)
	)
	(arc
		(start 137.16435 185.365)
		(mid 137.063817 185.323358)
		(end 137.022175 185.222825)
		(width 0.16)
		(layer "B.Cu")
		(net 267)
	)
	(arc
		(start 137.742204 185.222796)
		(mid 137.700553 185.122243)
		(end 137.6 185.080592)
		(width 0.16)
		(layer "B.Cu")
		(net 267)
	)
	(arc
		(start 135.942175 185.222825)
		(mid 135.900533 185.323358)
		(end 135.8 185.365)
		(width 0.16)
		(layer "B.Cu")
		(net 267)
	)
	(arc
		(start 135.269067 185.365)
		(mid 133.943426 185.101313)
		(end 132.819602 184.350398)
		(width 0.16)
		(layer "B.Cu")
		(net 267)
	)
	(arc
		(start 177.414308 177.402077)
		(mid 177.451169 177.491065)
		(end 177.414308 177.580055)
		(width 0.16)
		(layer "B.Cu")
		(net 267)
	)
	(arc
		(start 137.524408 185.080592)
		(mid 137.423855 185.122243)
		(end 137.382204 185.222796)
		(width 0.16)
		(layer "B.Cu")
		(net 267)
	)
	(arc
		(start 175.805224 178.791126)
		(mid 175.497449 178.663641)
		(end 175.189674 178.791126)
		(width 0.16)
		(layer "B.Cu")
		(net 267)
	)
	(arc
		(start 131.805 181.071437)
		(mid 131.845197 180.869353)
		(end 131.959668 180.698035)
		(width 0.16)
		(layer "B.Cu")
		(net 267)
	)
	(arc
		(start 176.091969 178.900728)
		(mid 176.003397 178.937416)
		(end 175.914824 178.900729)
		(width 0.16)
		(layer "B.Cu")
		(net 267)
	)
	(arc
		(start 184.845001 168.756276)
		(mid 184.775257 169.106904)
		(end 184.576642 169.404153)
		(width 0.16)
		(layer "B.Cu")
		(net 267)
	)
	(arc
		(start 136.08435 185.080649)
		(mid 135.983817 185.122291)
		(end 135.942175 185.222824)
		(width 0.16)
		(layer "B.Cu")
		(net 267)
	)
	(arc
		(start 137.884408 185.365)
		(mid 137.783855 185.323349)
		(end 137.742204 185.222796)
		(width 0.16)
		(layer "B.Cu")
		(net 267)
	)
	(arc
		(start 176.268377 178.547174)
		(mid 176.305065 178.635746)
		(end 176.268378 178.724319)
		(width 0.16)
		(layer "B.Cu")
		(net 267)
	)
	(arc
		(start 176.444358 177.139232)
		(mid 176.136153 177.011569)
		(end 175.827948 177.139232)
		(width 0.16)
		(layer "B.Cu")
		(net 267)
	)
	(arc
		(start 175.652398 177.314782)
		(mid 175.524735 177.622986)
		(end 175.652397 177.931191)
		(width 0.16)
		(layer "B.Cu")
		(net 267)
	)
	(segment
		(start 186.5005 159.4995)
		(end 187 159)
		(width 0.256)
		(layer "F.Cu")
		(net 268)
	)
	(via
		(at 186.5005 159.4995)
		(size 0.45)
		(drill 0.1)
		(layers "F.Cu" "B.Cu")
		(remove_unused_layers yes)
		(keep_end_layers yes)
		(zone_layer_connections)
		(net 268)
	)
	(via
		(at 125.01 153.81)
		(size 0.45)
		(drill 0.1)
		(layers "F.Cu" "B.Cu")
		(remove_unused_layers yes)
		(keep_end_layers yes)
		(zone_layer_connections)
		(net 268)
	)
	(segment
		(start 123.602499 153.782499)
		(end 123.43 153.61)
		(width 0.16)
		(layer "B.Cu")
		(net 268)
	)
	(segment
		(start 124.762471 153.954999)
		(end 124.01895 153.954999)
		(width 0.16)
		(layer "B.Cu")
		(net 268)
	)
	(segment
		(start 125.01 153.81)
		(end 124.9375 153.882499)
		(width 0.16)
		(layer "B.Cu")
		(net 268)
	)
	(arc
		(start 124.762471 153.954999)
		(mid 124.857196 153.936156)
		(end 124.9375 153.882499)
		(width 0.16)
		(layer "B.Cu")
		(net 268)
	)
	(arc
		(start 123.602499 153.782499)
		(mid 123.793568 153.910167)
		(end 124.01895 153.954999)
		(width 0.16)
		(layer "B.Cu")
		(net 268)
	)
	(segment
		(start 186.689485 161.161173)
		(end 186.764657 161.236344)
		(width 0.1)
		(layer "In4.Cu")
		(net 268)
	)
	(segment
		(start 125.222409 153.971785)
		(end 125.167885 153.949206)
		(width 0.1)
		(layer "In4.Cu")
		(net 268)
	)
	(segment
		(start 186.876 166.798045)
		(end 186.876 162.547024)
		(width 0.1)
		(layer "In4.Cu")
		(net 268)
	)
	(segment
		(start 169.434681 171.656352)
		(end 169.404188 171.626587)
		(width 0.1)
		(layer "In4.Cu")
		(net 268)
	)
	(segment
		(start 185.996301 160.876169)
		(end 186.060566 160.940435)
		(width 0.1)
		(layer "In4.Cu")
		(net 268)
	)
	(segment
		(start 186.5005 159.788792)
		(end 186.5005 159.4995)
		(width 0.1)
		(layer "In4.Cu")
		(net 268)
	)
	(segment
		(start 186.171346 159.947786)
		(end 186.059565 160.059566)
		(width 0.1)
		(layer "In4.Cu")
		(net 268)
	)
	(segment
		(start 171.620126 172.655028)
		(end 171.710371 172.663916)
		(width 0.1)
		(layer "In4.Cu")
		(net 268)
	)
	(segment
		(start 141.763575 153.99792)
		(end 141.881852 154.008268)
		(width 0.1)
		(layer "In4.Cu")
		(net 268)
	)
	(segment
		(start 169.639792 171.834768)
		(end 169.569692 171.77724)
		(width 0.1)
		(layer "In4.Cu")
		(net 268)
	)
	(segment
		(start 169.267382 171.491399)
		(end 169.232823 171.457639)
		(width 0.1)
		(layer "In4.Cu")
		(net 268)
	)
	(segment
		(start 186.602155 161.125)
		(end 186.602156 161.125001)
		(width 0.1)
		(layer "In4.Cu")
		(net 268)
	)
	(segment
		(start 158.787922 169.093915)
		(end 158.874148 169.166268)
		(width 0.1)
		(layer "In4.Cu")
		(net 268)
	)
	(segment
		(start 185.875 160.505148)
		(end 185.875 160.584)
		(width 0.1)
		(layer "In4.Cu")
		(net 268)
	)
	(segment
		(start 186.414291 159.875001)
		(end 186.347066 159.875001)
		(width 0.1)
		(layer "In4.Cu")
		(net 268)
	)
	(segment
		(start 186.602155 161.125)
		(end 186.506148 161.125)
		(width 0.1)
		(layer "In4.Cu")
		(net 268)
	)
	(segment
		(start 141.289071 153.985)
		(end 125.33828 153.985)
		(width 0.1)
		(layer "In4.Cu")
		(net 268)
	)
	(segment
		(start 172.072706 172.675)
		(end 181.006582 172.675)
		(width 0.1)
		(layer "In4.Cu")
		(net 268)
	)
	(segment
		(start 162.30117 170.375)
		(end 166.429036 170.375)
		(width 0.1)
		(layer "In4.Cu")
		(net 268)
	)
	(segment
		(start 169.014849 171.26798)
		(end 169.089353 171.329126)
		(width 0.1)
		(layer "In4.Cu")
		(net 268)
	)
	(segment
		(start 186.876 161.852443)
		(end 186.876 161.505153)
		(width 0.1)
		(layer "In4.Cu")
		(net 268)
	)
	(segment
		(start 166.814142 170.386673)
		(end 166.910061 170.39612)
		(width 0.1)
		(layer "In4.Cu")
		(net 268)
	)
	(segment
		(start 185.8755 160.585208)
		(end 185.876001 160.585709)
		(width 0.1)
		(layer "In4.Cu")
		(net 268)
	)
	(segment
		(start 158.461217 168.784439)
		(end 145.339533 155.662755)
		(width 0.1)
		(layer "In4.Cu")
		(net 268)
	)
	(segment
		(start 125.076613 153.876613)
		(end 125.01 153.81)
		(width 0.1)
		(layer "In4.Cu")
		(net 268)
	)
	(segment
		(start 186.876 161.852443)
		(end 186.876 162.547024)
		(width 0.1)
		(layer "In4.Cu")
		(net 268)
	)
	(segment
		(start 161.73919 170.353017)
		(end 161.851322 170.362827)
		(width 0.1)
		(layer "In4.Cu")
		(net 268)
	)
	(segment
		(start 185.356306 170.466914)
		(end 184.662593 171.160628)
		(width 0.1)
		(layer "In4.Cu")
		(net 268)
	)
	(segment
		(start 144.903923 155.260047)
		(end 144.994874 155.336364)
		(width 0.1)
		(layer "In4.Cu")
		(net 268)
	)
	(arc
		(start 143.268053 154.315582)
		(mid 143.48922 154.401589)
		(end 143.706425 154.497161)
		(width 0.1)
		(layer "In4.Cu")
		(net 268)
	)
	(arc
		(start 186.060566 160.940435)
		(mid 186.265001 161.077034)
		(end 186.506148 161.125)
		(width 0.1)
		(layer "In4.Cu")
		(net 268)
	)
	(arc
		(start 141.763575 153.99792)
		(mid 141.645173 153.989837)
		(end 141.526549 153.986285)
		(width 0.1)
		(layer "In4.Cu")
		(net 268)
	)
	(arc
		(start 169.930813 172.050598)
		(mid 170.083914 172.147545)
		(end 170.241588 172.236864)
		(width 0.1)
		(layer "In4.Cu")
		(net 268)
	)
	(arc
		(start 158.787922 169.093915)
		(mid 158.703138 169.019954)
		(end 158.621253 168.942797)
		(width 0.1)
		(layer "In4.Cu")
		(net 268)
	)
	(arc
		(start 186.689485 161.161173)
		(mid 186.649419 161.134401)
		(end 186.602156 161.125001)
		(width 0.1)
		(layer "In4.Cu")
		(net 268)
	)
	(arc
		(start 144.994874 155.336364)
		(mid 145.084312 155.414371)
		(end 145.170703 155.495741)
		(width 0.1)
		(layer "In4.Cu")
		(net 268)
	)
	(arc
		(start 169.014849 171.26798)
		(mid 168.863011 171.14948)
		(end 168.705541 171.038574)
		(width 0.1)
		(layer "In4.Cu")
		(net 268)
	)
	(arc
		(start 141.289071 153.985)
		(mid 141.407811 153.985321)
		(end 141.526549 153.986285)
		(width 0.1)
		(layer "In4.Cu")
		(net 268)
	)
	(arc
		(start 167.290986 170.452629)
		(mid 167.47891 170.494831)
		(end 167.664538 170.546203)
		(width 0.1)
		(layer "In4.Cu")
		(net 268)
	)
	(arc
		(start 125.33828 153.985)
		(mid 125.308746 153.98476)
		(end 125.279221 153.984043)
		(width 0.1)
		(layer "In4.Cu")
		(net 268)
	)
	(arc
		(start 143.706425 154.497161)
		(mid 143.919254 154.602116)
		(end 144.127303 154.716256)
		(width 0.1)
		(layer "In4.Cu")
		(net 268)
	)
	(arc
		(start 171.261727 172.601867)
		(mid 171.440274 172.632846)
		(end 171.620126 172.655028)
		(width 0.1)
		(layer "In4.Cu")
		(net 268)
	)
	(arc
		(start 160.425015 170.061669)
		(mid 160.638046 170.133984)
		(end 160.85403 170.196938)
		(width 0.1)
		(layer "In4.Cu")
		(net 268)
	)
	(arc
		(start 186.764657 161.236344)
		(mid 186.847063 161.359674)
		(end 186.876 161.505153)
		(width 0.1)
		(layer "In4.Cu")
		(net 268)
	)
	(arc
		(start 125.076613 153.876613)
		(mid 125.097665 153.897328)
		(end 125.119048 153.917702)
		(width 0.1)
		(layer "In4.Cu")
		(net 268)
	)
	(arc
		(start 186.414291 159.875001)
		(mid 186.447281 159.868438)
		(end 186.47525 159.849751)
		(width 0.1)
		(layer "In4.Cu")
		(net 268)
	)
	(arc
		(start 169.335779 171.559)
		(mid 169.369881 171.592896)
		(end 169.404188 171.626587)
		(width 0.1)
		(layer "In4.Cu")
		(net 268)
	)
	(arc
		(start 144.527484 154.971197)
		(mid 144.330174 154.83936)
		(end 144.127303 154.716256)
		(width 0.1)
		(layer "In4.Cu")
		(net 268)
	)
	(arc
		(start 125.222409 153.971785)
		(mid 125.250261 153.980479)
		(end 125.279221 153.984043)
		(width 0.1)
		(layer "In4.Cu")
		(net 268)
	)
	(arc
		(start 168.375238 170.840594)
		(mid 168.542819 170.935529)
		(end 168.705541 171.038574)
		(width 0.1)
		(layer "In4.Cu")
		(net 268)
	)
	(arc
		(start 142.815525 154.172901)
		(mid 143.043345 154.239304)
		(end 143.268053 154.315582)
		(width 0.1)
		(layer "In4.Cu")
		(net 268)
	)
	(arc
		(start 168.375238 170.840594)
		(mid 168.2032 170.753994)
		(end 168.027119 170.675941)
		(width 0.1)
		(layer "In4.Cu")
		(net 268)
	)
	(arc
		(start 186.171346 159.947786)
		(mid 186.251967 159.893917)
		(end 186.347066 159.875001)
		(width 0.1)
		(layer "In4.Cu")
		(net 268)
	)
	(arc
		(start 142.815525 154.172901)
		(mid 142.585023 154.116497)
		(end 142.352281 154.070202)
		(width 0.1)
		(layer "In4.Cu")
		(net 268)
	)
	(arc
		(start 171.89132 172.673903)
		(mid 171.982011 172.674725)
		(end 172.072706 172.675)
		(width 0.1)
		(layer "In4.Cu")
		(net 268)
	)
	(arc
		(start 184.662593 171.160628)
		(mid 182.985201 172.281427)
		(end 181.006582 172.675)
		(width 0.1)
		(layer "In4.Cu")
		(net 268)
	)
	(arc
		(start 166.814142 170.386673)
		(mid 166.718096 170.379309)
		(end 166.621821 170.376112)
		(width 0.1)
		(layer "In4.Cu")
		(net 268)
	)
	(arc
		(start 158.874148 169.166268)
		(mid 159.049599 169.307083)
		(end 159.231026 169.440112)
		(width 0.1)
		(layer "In4.Cu")
		(net 268)
	)
	(arc
		(start 158.461217 168.784439)
		(mid 158.541026 168.863828)
		(end 158.621253 168.942797)
		(width 0.1)
		(layer "In4.Cu")
		(net 268)
	)
	(arc
		(start 160.425015 170.061669)
		(mid 160.215339 169.98013)
		(end 160.00942 169.889522)
		(width 0.1)
		(layer "In4.Cu")
		(net 268)
	)
	(arc
		(start 167.664538 170.546203)
		(mid 167.847421 170.606621)
		(end 168.027119 170.675941)
		(width 0.1)
		(layer "In4.Cu")
		(net 268)
	)
	(arc
		(start 159.610412 169.68181)
		(mid 159.80765 169.790019)
		(end 160.00942 169.889522)
		(width 0.1)
		(layer "In4.Cu")
		(net 268)
	)
	(arc
		(start 144.903923 155.260047)
		(mid 144.718855 155.111515)
		(end 144.527484 154.971197)
		(width 0.1)
		(layer "In4.Cu")
		(net 268)
	)
	(arc
		(start 170.910264 172.513832)
		(mid 170.738195 172.456989)
		(end 170.569123 172.391773)
		(width 0.1)
		(layer "In4.Cu")
		(net 268)
	)
	(arc
		(start 159.610412 169.68181)
		(mid 159.418082 169.5651)
		(end 159.231026 169.440112)
		(width 0.1)
		(layer "In4.Cu")
		(net 268)
	)
	(arc
		(start 185.996301 160.876169)
		(mid 185.907267 160.742919)
		(end 185.876001 160.585709)
		(width 0.1)
		(layer "In4.Cu")
		(net 268)
	)
	(arc
		(start 186.5005 159.788792)
		(mid 186.493937 159.821782)
		(end 186.47525 159.849751)
		(width 0.1)
		(layer "In4.Cu")
		(net 268)
	)
	(arc
		(start 186.876 166.798045)
		(mid 186.481045 168.783622)
		(end 185.356306 170.466914)
		(width 0.1)
		(layer "In4.Cu")
		(net 268)
	)
	(arc
		(start 167.290986 170.452629)
		(mid 167.101217 170.419699)
		(end 166.910061 170.39612)
		(width 0.1)
		(layer "In4.Cu")
		(net 268)
	)
	(arc
		(start 145.170703 155.495741)
		(mid 145.255343 155.57902)
		(end 145.339533 155.662755)
		(width 0.1)
		(layer "In4.Cu")
		(net 268)
	)
	(arc
		(start 170.910264 172.513832)
		(mid 171.084915 172.562163)
		(end 171.261727 172.601867)
		(width 0.1)
		(layer "In4.Cu")
		(net 268)
	)
	(arc
		(start 169.089353 171.329126)
		(mid 169.162477 171.391831)
		(end 169.232823 171.457639)
		(width 0.1)
		(layer "In4.Cu")
		(net 268)
	)
	(arc
		(start 162.076032 170.373819)
		(mid 161.963571 170.37048)
		(end 161.851322 170.362827)
		(width 0.1)
		(layer "In4.Cu")
		(net 268)
	)
	(arc
		(start 169.930813 172.050598)
		(mid 169.782653 171.946255)
		(end 169.639792 171.834768)
		(width 0.1)
		(layer "In4.Cu")
		(net 268)
	)
	(arc
		(start 161.293202 170.2943)
		(mid 161.072554 170.25041)
		(end 160.85403 170.196938)
		(width 0.1)
		(layer "In4.Cu")
		(net 268)
	)
	(arc
		(start 125.119048 153.917702)
		(mid 125.142042 153.935661)
		(end 125.167885 153.949206)
		(width 0.1)
		(layer "In4.Cu")
		(net 268)
	)
	(arc
		(start 166.621821 170.376112)
		(mid 166.52543 170.375278)
		(end 166.429036 170.375)
		(width 0.1)
		(layer "In4.Cu")
		(net 268)
	)
	(arc
		(start 185.875 160.584)
		(mid 185.875129 160.584653)
		(end 185.8755 160.585208)
		(width 0.1)
		(layer "In4.Cu")
		(net 268)
	)
	(arc
		(start 170.241588 172.236864)
		(mid 170.403454 172.318338)
		(end 170.569123 172.391773)
		(width 0.1)
		(layer "In4.Cu")
		(net 268)
	)
	(arc
		(start 142.352281 154.070202)
		(mid 142.117742 154.034102)
		(end 141.881852 154.008268)
		(width 0.1)
		(layer "In4.Cu")
		(net 268)
	)
	(arc
		(start 171.89132 172.673903)
		(mid 171.800738 172.670856)
		(end 171.710371 172.663916)
		(width 0.1)
		(layer "In4.Cu")
		(net 268)
	)
	(arc
		(start 169.335779 171.559)
		(mid 169.301679 171.525099)
		(end 169.267382 171.491399)
		(width 0.1)
		(layer "In4.Cu")
		(net 268)
	)
	(arc
		(start 161.293202 170.2943)
		(mid 161.515555 170.328524)
		(end 161.73919 170.353017)
		(width 0.1)
		(layer "In4.Cu")
		(net 268)
	)
	(arc
		(start 169.569692 171.77724)
		(mid 169.500885 171.718249)
		(end 169.434681 171.656352)
		(width 0.1)
		(layer "In4.Cu")
		(net 268)
	)
	(arc
		(start 185.875 160.505148)
		(mid 185.922966 160.264001)
		(end 186.059565 160.059566)
		(width 0.1)
		(layer "In4.Cu")
		(net 268)
	)
	(arc
		(start 162.076032 170.373819)
		(mid 162.188599 170.374704)
		(end 162.30117 170.375)
		(width 0.1)
		(layer "In4.Cu")
		(net 268)
	)
	(segment
		(start 121.975 153.61)
		(end 121.505 153.61)
		(width 0.4)
		(layer "F.Cu")
		(net 269)
	)
	(via
		(at 121.975 153.61)
		(size 0.45)
		(drill 0.1)
		(layers "F.Cu" "B.Cu")
		(remove_unused_layers yes)
		(keep_end_layers yes)
		(zone_layer_connections)
		(net 269)
	)
	(segment
		(start 105.685805 160.379)
		(end 105.17 160.379)
		(width 0.16)
		(layer "B.Cu")
		(net 269)
	)
	(segment
		(start 116.003096 154.287698)
		(end 115.337698 154.953096)
		(width 0.16)
		(layer "B.Cu")
		(net 269)
	)
	(segment
		(start 121.8025 153.782499)
		(end 121.975 153.61)
		(width 0.16)
		(layer "B.Cu")
		(net 269)
	)
	(segment
		(start 106.842323 160.724)
		(end 106.518708 160.724)
		(width 0.16)
		(layer "B.Cu")
		(net 269)
	)
	(segment
		(start 107.071674 160.629)
		(end 108.534325 160.629)
		(width 0.16)
		(layer "B.Cu")
		(net 269)
	)
	(segment
		(start 121.975 153.61)
		(end 122.47 153.61)
		(width 0.16)
		(layer "B.Cu")
		(net 269)
	)
	(segment
		(start 121.386049 153.954999)
		(end 116.806302 153.954999)
		(width 0.16)
		(layer "B.Cu")
		(net 269)
	)
	(segment
		(start 109.823576 160.467219)
		(end 115.337698 154.953096)
		(width 0.16)
		(layer "B.Cu")
		(net 269)
	)
	(segment
		(start 108.763676 160.724)
		(end 109.203651 160.724)
		(width 0.16)
		(layer "B.Cu")
		(net 269)
	)
	(arc
		(start 121.8025 153.782499)
		(mid 121.61143 153.910167)
		(end 121.386049 153.954999)
		(width 0.16)
		(layer "B.Cu")
		(net 269)
	)
	(arc
		(start 116.806302 153.954999)
		(mid 116.37161 154.041464)
		(end 116.003096 154.287698)
		(width 0.16)
		(layer "B.Cu")
		(net 269)
	)
	(arc
		(start 107.071674 160.629)
		(mid 107.009612 160.641344)
		(end 106.956999 160.6765)
		(width 0.16)
		(layer "B.Cu")
		(net 269)
	)
	(arc
		(start 108.763676 160.724)
		(mid 108.701614 160.711655)
		(end 108.649001 160.6765)
		(width 0.16)
		(layer "B.Cu")
		(net 269)
	)
	(arc
		(start 106.956999 160.6765)
		(mid 106.904385 160.711655)
		(end 106.842323 160.724)
		(width 0.16)
		(layer "B.Cu")
		(net 269)
	)
	(arc
		(start 106.102257 160.5515)
		(mid 106.293326 160.679168)
		(end 106.518708 160.724)
		(width 0.16)
		(layer "B.Cu")
		(net 269)
	)
	(arc
		(start 108.649001 160.6765)
		(mid 108.596387 160.641344)
		(end 108.534325 160.629)
		(width 0.16)
		(layer "B.Cu")
		(net 269)
	)
	(arc
		(start 109.823576 160.467219)
		(mid 109.539152 160.657265)
		(end 109.203651 160.724)
		(width 0.16)
		(layer "B.Cu")
		(net 269)
	)
	(arc
		(start 105.685805 160.379)
		(mid 105.911187 160.423831)
		(end 106.102257 160.5515)
		(width 0.16)
		(layer "B.Cu")
		(net 269)
	)
	(segment
		(start 115.1 113.402)
		(end 115.098 113.4)
		(width 0.1)
		(layer "F.Cu")
		(net 270)
	)
	(segment
		(start 115.1 113.407)
		(end 115.098 113.405)
		(width 0.15)
		(layer "F.Cu")
		(net 270)
	)
	(segment
		(start 115.1 114.2)
		(end 115.1 113.402)
		(width 0.114)
		(layer "F.Cu")
		(net 270)
	)
	(segment
		(start 118.1 114.2)
		(end 118.1 113.402)
		(width 0.114)
		(layer "F.Cu")
		(net 271)
	)
	(segment
		(start 118.1 113.407)
		(end 118.098 113.405)
		(width 0.15)
		(layer "F.Cu")
		(net 271)
	)
	(segment
		(start 118.1 113.402)
		(end 118.098 113.4)
		(width 0.1)
		(layer "F.Cu")
		(net 271)
	)
	(segment
		(start 113.405 102.785)
		(end 113.405 104.55)
		(width 0.1)
		(layer "B.Cu")
		(net 272)
	)
	(segment
		(start 113.405 104.55)
		(end 113.705 104.85)
		(width 0.1)
		(layer "B.Cu")
		(net 272)
	)
	(segment
		(start 113.35 107.195)
		(end 113.35 106.1)
		(width 0.1)
		(layer "B.Cu")
		(net 273)
	)
	(segment
		(start 110.706 103.456)
		(end 110.706 102.684)
		(width 0.1)
		(layer "B.Cu")
		(net 273)
	)
	(segment
		(start 113.35 106.1)
		(end 110.706 103.456)
		(width 0.1)
		(layer "B.Cu")
		(net 273)
	)
	(segment
		(start 113.705 107.55)
		(end 113.35 107.195)
		(width 0.1)
		(layer "B.Cu")
		(net 273)
	)
	(segment
		(start 112.005 108.55)
		(end 112.005 106)
		(width 0.1)
		(layer "B.Cu")
		(net 274)
	)
	(segment
		(start 113.705 110.25)
		(end 112.005 108.55)
		(width 0.1)
		(layer "B.Cu")
		(net 274)
	)
	(segment
		(start 112.005 106)
		(end 109.505 103.5)
		(width 0.1)
		(layer "B.Cu")
		(net 274)
	)
	(segment
		(start 109.505 103.5)
		(end 108.505 103.5)
		(width 0.1)
		(layer "B.Cu")
		(net 274)
	)
	(segment
		(start 108.505 103.5)
		(end 108.005 103)
		(width 0.1)
		(layer "B.Cu")
		(net 274)
	)
	(segment
		(start 108.005 103)
		(end 108.005 102.685)
		(width 0.1)
		(layer "B.Cu")
		(net 274)
	)
	(segment
		(start 113.705 112.95)
		(end 113.548357 112.793357)
		(width 0.1)
		(layer "B.Cu")
		(net 275)
	)
	(segment
		(start 111.505 106)
		(end 109.555 104.05)
		(width 0.1)
		(layer "B.Cu")
		(net 275)
	)
	(segment
		(start 113.518794 112.822921)
		(end 113.208132 112.822921)
		(width 0.1)
		(layer "B.Cu")
		(net 275)
	)
	(segment
		(start 111.505 110.75)
		(end 111.505 106)
		(width 0.1)
		(layer "B.Cu")
		(net 275)
	)
	(segment
		(start 105.305 103.45)
		(end 105.305 102.535)
		(width 0.1)
		(layer "B.Cu")
		(net 275)
	)
	(segment
		(start 109.555 104.05)
		(end 105.905 104.05)
		(width 0.1)
		(layer "B.Cu")
		(net 275)
	)
	(segment
		(start 112.675 112.29259)
		(end 112.675 111.92)
		(width 0.1)
		(layer "B.Cu")
		(net 275)
	)
	(segment
		(start 112.677801 112.29259)
		(end 112.675 112.29259)
		(width 0.1)
		(layer "B.Cu")
		(net 275)
	)
	(segment
		(start 112.675 111.92)
		(end 111.505 110.75)
		(width 0.1)
		(layer "B.Cu")
		(net 275)
	)
	(segment
		(start 105.905 104.05)
		(end 105.305 103.45)
		(width 0.1)
		(layer "B.Cu")
		(net 275)
	)
	(segment
		(start 113.548357 112.793357)
		(end 113.518794 112.822921)
		(width 0.1)
		(layer "B.Cu")
		(net 275)
	)
	(segment
		(start 113.208132 112.822921)
		(end 112.677801 112.29259)
		(width 0.1)
		(layer "B.Cu")
		(net 275)
	)
	(segment
		(start 109.505 104.5)
		(end 111.005 106)
		(width 0.1)
		(layer "B.Cu")
		(net 276)
	)
	(segment
		(start 111.005 106)
		(end 111.005 112.95)
		(width 0.1)
		(layer "B.Cu")
		(net 276)
	)
	(segment
		(start 103.505 104.5)
		(end 109.505 104.5)
		(width 0.1)
		(layer "B.Cu")
		(net 276)
	)
	(segment
		(start 102.605 102.535)
		(end 102.605 103.6)
		(width 0.1)
		(layer "B.Cu")
		(net 276)
	)
	(segment
		(start 102.605 103.6)
		(end 103.505 104.5)
		(width 0.1)
		(layer "B.Cu")
		(net 276)
	)
	(segment
		(start 111.005 112.95)
		(end 113.705 115.65)
		(width 0.1)
		(layer "B.Cu")
		(net 276)
	)
	(segment
		(start 251.65 146)
		(end 252.3 146.65)
		(width 0.201)
		(layer "F.Cu")
		(net 277)
	)
	(segment
		(start 251.324499 146)
		(end 251.65 146)
		(width 0.201)
		(layer "F.Cu")
		(net 277)
	)
	(segment
		(start 252.3 142.4)
		(end 252.165 142.4)
		(width 0.201)
		(layer "F.Cu")
		(net 278)
	)
	(segment
		(start 252.165 142.4)
		(end 251.324499 141.559499)
		(width 0.201)
		(layer "F.Cu")
		(net 278)
	)
	(segment
		(start 251.324499 140.6)
		(end 251.324499 141.559499)
		(width 0.201)
		(layer "F.Cu")
		(net 278)
	)
	(segment
		(start 209.9 153.165)
		(end 210.885499 153.165)
		(width 0.256)
		(layer "F.Cu")
		(net 279)
	)
	(segment
		(start 210.885499 153.165)
		(end 210.899999 153.1505)
		(width 0.256)
		(layer "F.Cu")
		(net 279)
	)
	(via
		(at 210.899999 153.1505)
		(size 0.45)
		(drill 0.1)
		(layers "F.Cu" "B.Cu")
		(remove_unused_layers yes)
		(keep_end_layers yes)
		(zone_layer_connections)
		(net 279)
	)
	(segment
		(start 210.375 153.1505)
		(end 211.4245 153.1505)
		(width 0.256)
		(layer "B.Cu")
		(net 279)
	)
	(segment
		(start 211.4245 153.1505)
		(end 211.425 153.15)
		(width 0.256)
		(layer "B.Cu")
		(net 279)
	)
	(segment
		(start 217.898501 151.8645)
		(end 218.884 151.8645)
		(width 0.256)
		(layer "F.Cu")
		(net 280)
	)
	(segment
		(start 218.884 151.8645)
		(end 218.8985 151.85)
		(width 0.256)
		(layer "F.Cu")
		(net 280)
	)
	(via
		(at 218.8985 151.85)
		(size 0.45)
		(drill 0.1)
		(layers "F.Cu" "B.Cu")
		(remove_unused_layers yes)
		(keep_end_layers yes)
		(zone_layer_connections)
		(net 280)
	)
	(segment
		(start 218.375 151.85)
		(end 219.425 151.85)
		(width 0.256)
		(layer "B.Cu")
		(net 280)
	)
	(segment
		(start 209.9 150.624)
		(end 210.885499 150.624)
		(width 0.256)
		(layer "F.Cu")
		(net 281)
	)
	(segment
		(start 210.885499 150.624)
		(end 210.899999 150.6095)
		(width 0.1)
		(layer "F.Cu")
		(net 281)
	)
	(via
		(at 210.899999 150.6095)
		(size 0.45)
		(drill 0.1)
		(layers "F.Cu" "B.Cu")
		(remove_unused_layers yes)
		(keep_end_layers yes)
		(zone_layer_connections)
		(net 281)
	)
	(segment
		(start 210.899999 150.6095)
		(end 210.375 150.6095)
		(width 0.256)
		(layer "B.Cu")
		(net 281)
	)
	(segment
		(start 218.884499 153.135)
		(end 218.898999 153.1205)
		(width 0.256)
		(layer "F.Cu")
		(net 282)
	)
	(segment
		(start 217.899 153.135)
		(end 218.884499 153.135)
		(width 0.256)
		(layer "F.Cu")
		(net 282)
	)
	(via
		(at 218.898999 153.1205)
		(size 0.45)
		(drill 0.1)
		(layers "F.Cu" "B.Cu")
		(remove_unused_layers yes)
		(keep_end_layers yes)
		(zone_layer_connections)
		(net 282)
	)
	(segment
		(start 218.375 153.1205)
		(end 218.898999 153.1205)
		(width 0.256)
		(layer "B.Cu")
		(net 282)
	)
	(segment
		(start 252.3 143.45)
		(end 251.474499 143.45)
		(width 0.201)
		(layer "F.Cu")
		(net 283)
	)
	(segment
		(start 251.474499 143.45)
		(end 251.324499 143.3)
		(width 0.201)
		(layer "F.Cu")
		(net 283)
	)
	(segment
		(start 247.9725 127.2)
		(end 244.15 127.2)
		(width 0.15)
		(layer "F.Cu")
		(net 284)
	)
	(segment
		(start 248.1135 127.341)
		(end 247.9725 127.2)
		(width 0.15)
		(layer "F.Cu")
		(net 284)
	)
	(segment
		(start 248.1135 127.986)
		(end 248.1135 127.341)
		(width 0.15)
		(layer "F.Cu")
		(net 284)
	)
	(segment
		(start 243.05 127.05)
		(end 242.45 127.65)
		(width 0.15)
		(layer "F.Cu")
		(net 284)
	)
	(segment
		(start 244 127.05)
		(end 243.05 127.05)
		(width 0.15)
		(layer "F.Cu")
		(net 284)
	)
	(segment
		(start 244.15 127.2)
		(end 244 127.05)
		(width 0.15)
		(layer "F.Cu")
		(net 284)
	)
	(segment
		(start 242.45 127.65)
		(end 242.45 127.8701)
		(width 0.15)
		(layer "F.Cu")
		(net 284)
	)
	(segment
		(start 149.02 190.345)
		(end 151.07 190.345)
		(width 0.201)
		(layer "F.Cu")
		(net 285)
	)
	(segment
		(start 148.792 189.519)
		(end 148.792 190.117)
		(width 0.201)
		(layer "F.Cu")
		(net 285)
	)
	(segment
		(start 152.71 190.785)
		(end 153.207 190.288)
		(width 0.201)
		(layer "F.Cu")
		(net 285)
	)
	(segment
		(start 153.207 190.288)
		(end 153.207 189.971)
		(width 0.201)
		(layer "F.Cu")
		(net 285)
	)
	(segment
		(start 151.51 190.785)
		(end 152.71 190.785)
		(width 0.201)
		(layer "F.Cu")
		(net 285)
	)
	(segment
		(start 148.792 190.117)
		(end 149.02 190.345)
		(width 0.201)
		(layer "F.Cu")
		(net 285)
	)
	(segment
		(start 151.07 190.345)
		(end 151.51 190.785)
		(width 0.201)
		(layer "F.Cu")
		(net 285)
	)
	(segment
		(start 251.874499 136.374)
		(end 251.324499 135.824)
		(width 0.15)
		(layer "F.Cu")
		(net 286)
	)
	(segment
		(start 254.771999 137.2215)
		(end 253.924499 136.374)
		(width 0.15)
		(layer "F.Cu")
		(net 286)
	)
	(segment
		(start 253.924499 136.374)
		(end 251.874499 136.374)
		(width 0.15)
		(layer "F.Cu")
		(net 286)
	)
	(segment
		(start 251.324499 135.824)
		(end 251.324499 135.149)
		(width 0.15)
		(layer "F.Cu")
		(net 286)
	)
	(segment
		(start 252.111999 135.1865)
		(end 252.074499 135.149)
		(width 0.15)
		(layer "F.Cu")
		(net 286)
	)
	(segment
		(start 252.074499 135.149)
		(end 251.324499 135.149)
		(width 0.15)
		(layer "F.Cu")
		(net 286)
	)
	(segment
		(start 255.173999 137.2215)
		(end 254.771999 137.2215)
		(width 0.15)
		(layer "F.Cu")
		(net 286)
	)
	(via
		(at 252.111999 135.1865)
		(size 0.45)
		(drill 0.1)
		(layers "F.Cu" "B.Cu")
		(remove_unused_layers yes)
		(keep_end_layers yes)
		(zone_layer_connections)
		(net 286)
	)
	(segment
		(start 252.674499 135.749)
		(end 253.714499 135.749)
		(width 0.256)
		(layer "B.Cu")
		(net 286)
	)
	(segment
		(start 252.111999 135.1865)
		(end 252.674499 135.749)
		(width 0.256)
		(layer "B.Cu")
		(net 286)
	)
	(segment
		(start 253.175999 137.2215)
		(end 251.846999 137.2215)
		(width 0.15)
		(layer "F.Cu")
		(net 287)
	)
	(segment
		(start 249.138499 137.284)
		(end 248.483499 137.284)
		(width 0.201)
		(layer "F.Cu")
		(net 287)
	)
	(segment
		(start 249.138499 137.284)
		(end 249.223499 137.199)
		(width 0.201)
		(layer "F.Cu")
		(net 287)
	)
	(segment
		(start 251.846999 137.2215)
		(end 251.124499 136.499)
		(width 0.15)
		(layer "F.Cu")
		(net 287)
	)
	(segment
		(start 249.973499 136.499)
		(end 249.223499 137.249)
		(width 0.15)
		(layer "F.Cu")
		(net 287)
	)
	(segment
		(start 251.124499 136.499)
		(end 249.973499 136.499)
		(width 0.15)
		(layer "F.Cu")
		(net 287)
	)
	(via
		(at 248.483499 137.284)
		(size 0.45)
		(drill 0.1)
		(layers "F.Cu" "B.Cu")
		(remove_unused_layers yes)
		(keep_end_layers yes)
		(zone_layer_connections)
		(net 287)
	)
	(segment
		(start 199.5 157.5)
		(end 199.0005 157.0005)
		(width 0.256)
		(layer "F.Cu")
		(net 288)
	)
	(via
		(at 199.5 157.5)
		(size 0.45)
		(drill 0.1)
		(layers "F.Cu" "B.Cu")
		(remove_unused_layers yes)
		(keep_end_layers yes)
		(zone_layer_connections)
		(net 288)
	)
	(segment
		(start 199.5 157.5)
		(end 199 157)
		(width 0.256)
		(layer "B.Cu")
		(net 288)
	)
	(segment
		(start 134.809499 166.449)
		(end 134.824499 166.449)
		(width 0.256)
		(layer "F.Cu")
		(net 289)
	)
	(segment
		(start 136.689499 164.584)
		(end 137.746 164.584)
		(width 0.256)
		(layer "F.Cu")
		(net 289)
	)
	(segment
		(start 134.824499 166.449)
		(end 136.689499 164.584)
		(width 0.256)
		(layer "F.Cu")
		(net 289)
	)
	(segment
		(start 128.600676 181.648)
		(end 129.625179 181.648)
		(width 0.16)
		(layer "F.Cu")
		(net 290)
	)
	(segment
		(start 131.925366 180.293929)
		(end 131.240301 180.978994)
		(width 0.16)
		(layer "F.Cu")
		(net 290)
	)
	(segment
		(start 128.371325 181.553)
		(end 127.801 181.553)
		(width 0.16)
		(layer "F.Cu")
		(net 290)
	)
	(segment
		(start 131.997867 180.118898)
		(end 131.997867 180.016367)
		(width 0.16)
		(layer "F.Cu")
		(net 290)
	)
	(via
		(at 131.997867 180.016367)
		(size 0.45)
		(drill 0.1)
		(layers "F.Cu" "B.Cu")
		(remove_unused_layers yes)
		(keep_end_layers yes)
		(zone_layer_connections)
		(net 290)
	)
	(arc
		(start 131.925366 180.293929)
		(mid 131.979024 180.213624)
		(end 131.997867 180.118898)
		(width 0.16)
		(layer "F.Cu")
		(net 290)
	)
	(arc
		(start 128.486001 181.6005)
		(mid 128.538614 181.635655)
		(end 128.600676 181.648)
		(width 0.16)
		(layer "F.Cu")
		(net 290)
	)
	(arc
		(start 128.486001 181.6005)
		(mid 128.433387 181.565344)
		(end 128.371325 181.553)
		(width 0.16)
		(layer "F.Cu")
		(net 290)
	)
	(arc
		(start 131.240301 180.978994)
		(mid 130.499277 181.474131)
		(end 129.625179 181.648)
		(width 0.16)
		(layer "F.Cu")
		(net 290)
	)
	(segment
		(start 131.746433 180.472862)
		(end 131.925366 180.293929)
		(width 0.16)
		(layer "B.Cu")
		(net 290)
	)
	(segment
		(start 177.633512 177.799256)
		(end 177.457935 177.974834)
		(width 0.16)
		(layer "B.Cu")
		(net 290)
	)
	(segment
		(start 176.047152 177.358436)
		(end 175.871601 177.533986)
		(width 0.16)
		(layer "B.Cu")
		(net 290)
	)
	(segment
		(start 185.49 167.93)
		(end 185.3225 168.097499)
		(width 0.16)
		(layer "B.Cu")
		(net 290)
	)
	(segment
		(start 132.600398 184.569602)
		(end 132.463703 184.432907)
		(width 0.16)
		(layer "B.Cu")
		(net 290)
	)
	(segment
		(start 183.548039 170.871164)
		(end 178.099601 176.319601)
		(width 0.16)
		(layer "B.Cu")
		(net 290)
	)
	(segment
		(start 176.841552 177.974833)
		(end 176.841553 177.974833)
		(width 0.16)
		(layer "B.Cu")
		(net 290)
	)
	(segment
		(start 141.34024 185.675)
		(end 135.269064 185.675)
		(width 0.16)
		(layer "B.Cu")
		(net 290)
	)
	(segment
		(start 131.495 182.09425)
		(end 131.495 181.079876)
		(width 0.16)
		(layer "B.Cu")
		(net 290)
	)
	(segment
		(start 175.408877 179.010329)
		(end 175.235818 179.183386)
		(width 0.16)
		(layer "B.Cu")
		(net 290)
	)
	(segment
		(start 176.487581 178.943521)
		(end 176.311172 179.119931)
		(width 0.16)
		(layer "B.Cu")
		(net 290)
	)
	(segment
		(start 131.997867 180.118898)
		(end 131.997867 180.016367)
		(width 0.16)
		(layer "B.Cu")
		(net 290)
	)
	(segment
		(start 177.197434 176.209998)
		(end 177.017575 176.389856)
		(width 0.16)
		(layer "B.Cu")
		(net 290)
	)
	(segment
		(start 175.871601 177.711989)
		(end 176.487582 178.327969)
		(width 0.16)
		(layer "B.Cu")
		(net 290)
	)
	(segment
		(start 175.235818 179.183386)
		(end 174.457996 179.961207)
		(width 0.16)
		(layer "B.Cu")
		(net 290)
	)
	(segment
		(start 177.197434 176.209999)
		(end 177.197434 176.209998)
		(width 0.16)
		(layer "B.Cu")
		(net 290)
	)
	(segment
		(start 177.484115 176.319601)
		(end 177.484116 176.319601)
		(width 0.16)
		(layer "B.Cu")
		(net 290)
	)
	(segment
		(start 177.633511 177.799258)
		(end 177.633512 177.799256)
		(width 0.16)
		(layer "B.Cu")
		(net 290)
	)
	(segment
		(start 175.871601 177.711988)
		(end 175.871601 177.711989)
		(width 0.16)
		(layer "B.Cu")
		(net 290)
	)
	(segment
		(start 175.695622 179.11993)
		(end 175.586021 179.010329)
		(width 0.16)
		(layer "B.Cu")
		(net 290)
	)
	(segment
		(start 146.211839 183.057363)
		(end 145.187996 184.081207)
		(width 0.16)
		(layer "B.Cu")
		(net 290)
	)
	(segment
		(start 175.695621 179.119932)
		(end 175.695622 179.11993)
		(width 0.16)
		(layer "B.Cu")
		(net 290)
	)
	(segment
		(start 177.017575 176.566935)
		(end 177.633513 177.182872)
		(width 0.16)
		(layer "B.Cu")
		(net 290)
	)
	(segment
		(start 176.841553 177.974833)
		(end 176.225154 177.358436)
		(width 0.16)
		(layer "B.Cu")
		(net 290)
	)
	(segment
		(start 177.484116 176.319601)
		(end 177.374513 176.209998)
		(width 0.16)
		(layer "B.Cu")
		(net 290)
	)
	(segment
		(start 185.155001 168.501879)
		(end 185.155001 168.764601)
		(width 0.16)
		(layer "B.Cu")
		(net 290)
	)
	(segment
		(start 176.487581 178.943522)
		(end 176.487581 178.943521)
		(width 0.16)
		(layer "B.Cu")
		(net 290)
	)
	(segment
		(start 184.801729 169.617474)
		(end 183.548039 170.871164)
		(width 0.16)
		(layer "B.Cu")
		(net 290)
	)
	(segment
		(start 170.61024 181.555)
		(end 149.838862 181.555)
		(width 0.16)
		(layer "B.Cu")
		(net 290)
	)
	(segment
		(start 177.017576 176.566935)
		(end 177.017575 176.566935)
		(width 0.16)
		(layer "B.Cu")
		(net 290)
	)
	(arc
		(start 176.225154 177.358436)
		(mid 176.136153 177.321571)
		(end 176.047152 177.358436)
		(width 0.16)
		(layer "B.Cu")
		(net 290)
	)
	(arc
		(start 176.311172 179.119931)
		(mid 176.003397 179.247416)
		(end 175.695621 179.119932)
		(width 0.16)
		(layer "B.Cu")
		(net 290)
	)
	(arc
		(start 185.155001 168.764601)
		(mid 185.063188 169.226172)
		(end 184.801729 169.617474)
		(width 0.16)
		(layer "B.Cu")
		(net 290)
	)
	(arc
		(start 135.269064 185.675)
		(mid 133.824792 185.387716)
		(end 132.600398 184.569602)
		(width 0.16)
		(layer "B.Cu")
		(net 290)
	)
	(arc
		(start 177.457935 177.974834)
		(mid 177.149744 178.10249)
		(end 176.841552 177.974833)
		(width 0.16)
		(layer "B.Cu")
		(net 290)
	)
	(arc
		(start 176.487582 178.327969)
		(mid 176.615067 178.635744)
		(end 176.487581 178.943522)
		(width 0.16)
		(layer "B.Cu")
		(net 290)
	)
	(arc
		(start 132.463703 184.432907)
		(mid 131.746757 183.359922)
		(end 131.495 182.09425)
		(width 0.16)
		(layer "B.Cu")
		(net 290)
	)
	(arc
		(start 177.017575 176.389856)
		(mid 176.980901 176.478396)
		(end 177.017576 176.566935)
		(width 0.16)
		(layer "B.Cu")
		(net 290)
	)
	(arc
		(start 177.633513 177.182872)
		(mid 177.761169 177.491065)
		(end 177.633511 177.799258)
		(width 0.16)
		(layer "B.Cu")
		(net 290)
	)
	(arc
		(start 185.3225 168.097499)
		(mid 185.198532 168.28303)
		(end 185.155001 168.501879)
		(width 0.16)
		(layer "B.Cu")
		(net 290)
	)
	(arc
		(start 177.374513 176.209998)
		(mid 177.285973 176.173324)
		(end 177.197434 176.209999)
		(width 0.16)
		(layer "B.Cu")
		(net 290)
	)
	(arc
		(start 145.187996 184.081207)
		(mid 143.42263 185.260786)
		(end 141.34024 185.675)
		(width 0.16)
		(layer "B.Cu")
		(net 290)
	)
	(arc
		(start 178.099601 176.319601)
		(mid 177.791858 176.447072)
		(end 177.484115 176.319601)
		(width 0.16)
		(layer "B.Cu")
		(net 290)
	)
	(arc
		(start 131.925366 180.293929)
		(mid 131.979024 180.213624)
		(end 131.997867 180.118898)
		(width 0.16)
		(layer "B.Cu")
		(net 290)
	)
	(arc
		(start 174.457996 179.961207)
		(mid 172.69263 181.140786)
		(end 170.61024 181.555)
		(width 0.16)
		(layer "B.Cu")
		(net 290)
	)
	(arc
		(start 131.495 181.079876)
		(mid 131.560345 180.751362)
		(end 131.746433 180.472862)
		(width 0.16)
		(layer "B.Cu")
		(net 290)
	)
	(arc
		(start 149.838862 181.555)
		(mid 147.875931 181.945451)
		(end 146.211839 183.057363)
		(width 0.16)
		(layer "B.Cu")
		(net 290)
	)
	(arc
		(start 175.586021 179.010329)
		(mid 175.497449 178.973641)
		(end 175.408877 179.010329)
		(width 0.16)
		(layer "B.Cu")
		(net 290)
	)
	(arc
		(start 175.871601 177.533986)
		(mid 175.834736 177.622987)
		(end 175.871601 177.711988)
		(width 0.16)
		(layer "B.Cu")
		(net 290)
	)
	(segment
		(start 186.5005 160.499499)
		(end 187 160)
		(width 0.256)
		(layer "F.Cu")
		(net 291)
	)
	(via
		(at 186.5005 160.499499)
		(size 0.45)
		(drill 0.1)
		(layers "F.Cu" "B.Cu")
		(remove_unused_layers yes)
		(keep_end_layers yes)
		(zone_layer_connections)
		(net 291)
	)
	(via
		(at 125.01 154.41)
		(size 0.45)
		(drill 0.1)
		(layers "F.Cu" "B.Cu")
		(remove_unused_layers yes)
		(keep_end_layers yes)
		(zone_layer_connections)
		(net 291)
	)
	(segment
		(start 124.762471 154.265001)
		(end 124.01895 154.265001)
		(width 0.16)
		(layer "B.Cu")
		(net 291)
	)
	(segment
		(start 123.602499 154.4375)
		(end 123.43 154.61)
		(width 0.16)
		(layer "B.Cu")
		(net 291)
	)
	(segment
		(start 124.9375 154.3375)
		(end 125.01 154.41)
		(width 0.16)
		(layer "B.Cu")
		(net 291)
	)
	(arc
		(start 123.602499 154.4375)
		(mid 123.793568 154.309832)
		(end 124.01895 154.265001)
		(width 0.16)
		(layer "B.Cu")
		(net 291)
	)
	(arc
		(start 124.762471 154.265001)
		(mid 124.857196 154.283842)
		(end 124.9375 154.3375)
		(width 0.16)
		(layer "B.Cu")
		(net 291)
	)
	(segment
		(start 186.829654 160.947786)
		(end 186.941435 161.059566)
		(width 0.1)
		(layer "In4.Cu")
		(net 291)
	)
	(segment
		(start 186.236343 160.236344)
		(end 186.311515 160.161173)
		(width 0.1)
		(layer "In4.Cu")
		(net 291)
	)
	(segment
		(start 145.166865 155.843643)
		(end 158.270465 168.947243)
		(width 0.1)
		(layer "In4.Cu")
		(net 291)
	)
	(segment
		(start 166.434712 170.625)
		(end 162.320927 170.625)
		(width 0.1)
		(layer "In4.Cu")
		(net 291)
	)
	(segment
		(start 144.836405 155.530697)
		(end 144.749199 155.457523)
		(width 0.1)
		(layer "In4.Cu")
		(net 291)
	)
	(segment
		(start 125.076614 154.343385)
		(end 125.01 154.41)
		(width 0.1)
		(layer "In4.Cu")
		(net 291)
	)
	(segment
		(start 180.997814 172.925)
		(end 172.070961 172.925)
		(width 0.1)
		(layer "In4.Cu")
		(net 291)
	)
	(segment
		(start 125.338279 154.235)
		(end 141.283255 154.235)
		(width 0.1)
		(layer "In4.Cu")
		(net 291)
	)
	(segment
		(start 186.500418 160.499417)
		(end 186.5005 160.499499)
		(width 0.1)
		(layer "In4.Cu")
		(net 291)
	)
	(segment
		(start 161.846423 170.612079)
		(end 161.728147 170.601731)
		(width 0.1)
		(layer "In4.Cu")
		(net 291)
	)
	(segment
		(start 166.795402 170.635962)
		(end 166.88524 170.64481)
		(width 0.1)
		(layer "In4.Cu")
		(net 291)
	)
	(segment
		(start 169.410699 171.970811)
		(end 169.485202 172.031954)
		(width 0.1)
		(layer "In4.Cu")
		(net 291)
	)
	(segment
		(start 168.856587 171.461372)
		(end 168.926368 171.51864)
		(width 0.1)
		(layer "In4.Cu")
		(net 291)
	)
	(segment
		(start 186.506153 160.875)
		(end 186.506154 160.875001)
		(width 0.1)
		(layer "In4.Cu")
		(net 291)
	)
	(segment
		(start 169.06074 171.639008)
		(end 169.088448 171.666076)
		(width 0.1)
		(layer "In4.Cu")
		(net 291)
	)
	(segment
		(start 186.398844 160.125001)
		(end 186.414291 160.125001)
		(width 0.1)
		(layer "In4.Cu")
		(net 291)
	)
	(segment
		(start 141.851618 154.257304)
		(end 141.738213 154.247382)
		(width 0.1)
		(layer "In4.Cu")
		(net 291)
	)
	(segment
		(start 186.162173 160.688485)
		(end 186.237344 160.763657)
		(width 0.1)
		(layer "In4.Cu")
		(net 291)
	)
	(segment
		(start 186.126001 160.586416)
		(end 186.126001 160.601156)
		(width 0.1)
		(layer "In4.Cu")
		(net 291)
	)
	(segment
		(start 187.126 166.796814)
		(end 187.126 161.505148)
		(width 0.1)
		(layer "In4.Cu")
		(net 291)
	)
	(segment
		(start 186.506154 160.875001)
		(end 186.653934 160.875001)
		(width 0.1)
		(layer "In4.Cu")
		(net 291)
	)
	(segment
		(start 125.222413 154.248232)
		(end 125.167895 154.270809)
		(width 0.1)
		(layer "In4.Cu")
		(net 291)
	)
	(segment
		(start 186.500337 160.49922)
		(end 186.500337 160.194093)
		(width 0.1)
		(layer "In4.Cu")
		(net 291)
	)
	(segment
		(start 184.84557 171.331206)
		(end 185.532207 170.64457)
		(width 0.1)
		(layer "In4.Cu")
		(net 291)
	)
	(segment
		(start 169.267204 171.84233)
		(end 169.235111 171.811005)
		(width 0.1)
		(layer "In4.Cu")
		(net 291)
	)
	(segment
		(start 158.615123 169.273634)
		(end 158.706075 169.349951)
		(width 0.1)
		(layer "In4.Cu")
		(net 291)
	)
	(segment
		(start 186.125 160.584)
		(end 186.125 160.505153)
		(width 0.1)
		(layer "In4.Cu")
		(net 291)
	)
	(segment
		(start 171.685863 172.913221)
		(end 171.589946 172.903773)
		(width 0.1)
		(layer "In4.Cu")
		(net 291)
	)
	(arc
		(start 161.846423 170.612079)
		(mid 161.964825 170.620161)
		(end 162.083449 170.623714)
		(width 0.1)
		(layer "In4.Cu")
		(net 291)
	)
	(arc
		(start 170.124802 172.45932)
		(mid 170.296837 172.545915)
		(end 170.472915 172.623966)
		(width 0.1)
		(layer "In4.Cu")
		(net 291)
	)
	(arc
		(start 145.00499 155.683509)
		(mid 144.922158 155.605492)
		(end 144.836405 155.530697)
		(width 0.1)
		(layer "In4.Cu")
		(net 291)
	)
	(arc
		(start 167.931477 170.90688)
		(mid 168.096393 170.979982)
		(end 168.257525 171.061089)
		(width 0.1)
		(layer "In4.Cu")
		(net 291)
	)
	(arc
		(start 158.706075 169.349951)
		(mid 158.891143 169.498483)
		(end 159.082514 169.638801)
		(width 0.1)
		(layer "In4.Cu")
		(net 291)
	)
	(arc
		(start 168.566889 171.246516)
		(mid 168.414483 171.150005)
		(end 168.257525 171.061089)
		(width 0.1)
		(layer "In4.Cu")
		(net 291)
	)
	(arc
		(start 144.388268 155.180571)
		(mid 144.571755 155.315109)
		(end 144.749199 155.457523)
		(width 0.1)
		(layer "In4.Cu")
		(net 291)
	)
	(arc
		(start 161.257717 170.539797)
		(mid 161.492256 170.575896)
		(end 161.728147 170.601731)
		(width 0.1)
		(layer "In4.Cu")
		(net 291)
	)
	(arc
		(start 167.242014 170.697733)
		(mid 167.064276 170.666892)
		(end 166.88524 170.64481)
		(width 0.1)
		(layer "In4.Cu")
		(net 291)
	)
	(arc
		(start 186.47525 160.150251)
		(mid 186.447281 160.131563)
		(end 186.414291 160.125001)
		(width 0.1)
		(layer "In4.Cu")
		(net 291)
	)
	(arc
		(start 186.398844 160.125001)
		(mid 186.351581 160.134401)
		(end 186.311515 160.161173)
		(width 0.1)
		(layer "In4.Cu")
		(net 291)
	)
	(arc
		(start 169.06074 171.639008)
		(mid 168.994855 171.577371)
		(end 168.926368 171.51864)
		(width 0.1)
		(layer "In4.Cu")
		(net 291)
	)
	(arc
		(start 167.931477 170.90688)
		(mid 167.763171 170.841957)
		(end 167.591883 170.785371)
		(width 0.1)
		(layer "In4.Cu")
		(net 291)
	)
	(arc
		(start 169.794504 172.261348)
		(mid 169.637037 172.150447)
		(end 169.485202 172.031954)
		(width 0.1)
		(layer "In4.Cu")
		(net 291)
	)
	(arc
		(start 184.84557 171.331206)
		(mid 183.080204 172.510786)
		(end 180.997814 172.925)
		(width 0.1)
		(layer "In4.Cu")
		(net 291)
	)
	(arc
		(start 186.47525 160.150251)
		(mid 186.490319 160.170571)
		(end 186.500337 160.194093)
		(width 0.1)
		(layer "In4.Cu")
		(net 291)
	)
	(arc
		(start 168.856587 171.461372)
		(mid 168.714375 171.350388)
		(end 168.566889 171.246516)
		(width 0.1)
		(layer "In4.Cu")
		(net 291)
	)
	(arc
		(start 159.903573 170.112838)
		(mid 159.690744 170.007882)
		(end 159.482696 169.893744)
		(width 0.1)
		(layer "In4.Cu")
		(net 291)
	)
	(arc
		(start 186.829654 160.947786)
		(mid 186.749033 160.893917)
		(end 186.653934 160.875001)
		(width 0.1)
		(layer "In4.Cu")
		(net 291)
	)
	(arc
		(start 186.500337 160.49922)
		(mid 186.500358 160.499326)
		(end 186.500418 160.499417)
		(width 0.1)
		(layer "In4.Cu")
		(net 291)
	)
	(arc
		(start 144.004572 154.936129)
		(mid 143.805093 154.826691)
		(end 143.601032 154.726059)
		(width 0.1)
		(layer "In4.Cu")
		(net 291)
	)
	(arc
		(start 170.835488 172.753698)
		(mid 170.652609 172.693282)
		(end 170.472915 172.623966)
		(width 0.1)
		(layer "In4.Cu")
		(net 291)
	)
	(arc
		(start 167.242014 170.697733)
		(mid 167.418024 170.737257)
		(end 167.591883 170.785371)
		(width 0.1)
		(layer "In4.Cu")
		(net 291)
	)
	(arc
		(start 125.279222 154.235966)
		(mid 125.250264 154.239536)
		(end 125.222413 154.248232)
		(width 0.1)
		(layer "In4.Cu")
		(net 291)
	)
	(arc
		(start 166.795402 170.635962)
		(mid 166.705445 170.629061)
		(end 166.615275 170.626056)
		(width 0.1)
		(layer "In4.Cu")
		(net 291)
	)
	(arc
		(start 171.685863 172.913221)
		(mid 171.781907 172.920598)
		(end 171.87818 172.923835)
		(width 0.1)
		(layer "In4.Cu")
		(net 291)
	)
	(arc
		(start 169.235111 171.811005)
		(mid 169.198331 171.774888)
		(end 169.161772 171.738549)
		(width 0.1)
		(layer "In4.Cu")
		(net 291)
	)
	(arc
		(start 161.257717 170.539797)
		(mid 161.024974 170.493502)
		(end 160.794474 170.437099)
		(width 0.1)
		(layer "In4.Cu")
		(net 291)
	)
	(arc
		(start 166.615275 170.626056)
		(mid 166.524995 170.625264)
		(end 166.434712 170.625)
		(width 0.1)
		(layer "In4.Cu")
		(net 291)
	)
	(arc
		(start 160.341944 170.294416)
		(mid 160.120777 170.208409)
		(end 159.903573 170.112838)
		(width 0.1)
		(layer "In4.Cu")
		(net 291)
	)
	(arc
		(start 143.180718 154.55196)
		(mid 143.392774 154.634423)
		(end 143.601032 154.726059)
		(width 0.1)
		(layer "In4.Cu")
		(net 291)
	)
	(arc
		(start 171.589946 172.903773)
		(mid 171.398795 172.880195)
		(end 171.209031 172.847267)
		(width 0.1)
		(layer "In4.Cu")
		(net 291)
	)
	(arc
		(start 158.439295 169.114258)
		(mid 158.354654 169.030978)
		(end 158.270465 168.947243)
		(width 0.1)
		(layer "In4.Cu")
		(net 291)
	)
	(arc
		(start 162.320927 170.625)
		(mid 162.202186 170.624678)
		(end 162.083449 170.623714)
		(width 0.1)
		(layer "In4.Cu")
		(net 291)
	)
	(arc
		(start 141.851618 154.257304)
		(mid 142.077792 154.282074)
		(end 142.30267 154.316687)
		(width 0.1)
		(layer "In4.Cu")
		(net 291)
	)
	(arc
		(start 143.180718 154.55196)
		(mid 142.965266 154.478824)
		(end 142.74683 154.415155)
		(width 0.1)
		(layer "In4.Cu")
		(net 291)
	)
	(arc
		(start 169.267204 171.84233)
		(mid 169.337569 171.908114)
		(end 169.410699 171.970811)
		(width 0.1)
		(layer "In4.Cu")
		(net 291)
	)
	(arc
		(start 158.615123 169.273634)
		(mid 158.525685 169.195626)
		(end 158.439295 169.114258)
		(width 0.1)
		(layer "In4.Cu")
		(net 291)
	)
	(arc
		(start 186.125 160.584)
		(mid 186.125129 160.584653)
		(end 186.1255 160.585208)
		(width 0.1)
		(layer "In4.Cu")
		(net 291)
	)
	(arc
		(start 142.30267 154.316687)
		(mid 142.525824 154.361075)
		(end 142.74683 154.415155)
		(width 0.1)
		(layer "In4.Cu")
		(net 291)
	)
	(arc
		(start 144.004572 154.936129)
		(mid 144.199087 155.054163)
		(end 144.388268 155.180571)
		(width 0.1)
		(layer "In4.Cu")
		(net 291)
	)
	(arc
		(start 186.1255 160.585208)
		(mid 186.12587 160.585762)
		(end 186.126001 160.586416)
		(width 0.1)
		(layer "In4.Cu")
		(net 291)
	)
	(arc
		(start 145.00499 155.683509)
		(mid 145.086144 155.763357)
		(end 145.166865 155.843643)
		(width 0.1)
		(layer "In4.Cu")
		(net 291)
	)
	(arc
		(start 186.126001 160.601156)
		(mid 186.135401 160.648419)
		(end 186.162173 160.688485)
		(width 0.1)
		(layer "In4.Cu")
		(net 291)
	)
	(arc
		(start 186.506153 160.875)
		(mid 186.360674 160.846063)
		(end 186.237344 160.763657)
		(width 0.1)
		(layer "In4.Cu")
		(net 291)
	)
	(arc
		(start 171.87818 172.923835)
		(mid 171.974568 172.924708)
		(end 172.070961 172.925)
		(width 0.1)
		(layer "In4.Cu")
		(net 291)
	)
	(arc
		(start 159.082514 169.638801)
		(mid 159.279823 169.770638)
		(end 159.482696 169.893744)
		(width 0.1)
		(layer "In4.Cu")
		(net 291)
	)
	(arc
		(start 170.835488 172.753698)
		(mid 171.02111 172.805067)
		(end 171.209031 172.847267)
		(width 0.1)
		(layer "In4.Cu")
		(net 291)
	)
	(arc
		(start 125.279222 154.235966)
		(mid 125.308746 154.235241)
		(end 125.338279 154.235)
		(width 0.1)
		(layer "In4.Cu")
		(net 291)
	)
	(arc
		(start 160.341944 170.294416)
		(mid 160.566652 170.370694)
		(end 160.794474 170.437099)
		(width 0.1)
		(layer "In4.Cu")
		(net 291)
	)
	(arc
		(start 170.124802 172.45932)
		(mid 169.957223 172.364388)
		(end 169.794504 172.261348)
		(width 0.1)
		(layer "In4.Cu")
		(net 291)
	)
	(arc
		(start 141.510951 154.236229)
		(mid 141.397104 154.235307)
		(end 141.283255 154.235)
		(width 0.1)
		(layer "In4.Cu")
		(net 291)
	)
	(arc
		(start 186.236343 160.236344)
		(mid 186.153937 160.359674)
		(end 186.125 160.505153)
		(width 0.1)
		(layer "In4.Cu")
		(net 291)
	)
	(arc
		(start 187.126 166.796814)
		(mid 186.711786 168.879204)
		(end 185.532207 170.64457)
		(width 0.1)
		(layer "In4.Cu")
		(net 291)
	)
	(arc
		(start 125.076614 154.343385)
		(mid 125.097666 154.322672)
		(end 125.119053 154.302305)
		(width 0.1)
		(layer "In4.Cu")
		(net 291)
	)
	(arc
		(start 186.941435 161.059566)
		(mid 187.078034 161.264001)
		(end 187.126 161.505148)
		(width 0.1)
		(layer "In4.Cu")
		(net 291)
	)
	(arc
		(start 169.088448 171.666076)
		(mid 169.125215 171.702205)
		(end 169.161772 171.738549)
		(width 0.1)
		(layer "In4.Cu")
		(net 291)
	)
	(arc
		(start 141.510951 154.236229)
		(mid 141.624688 154.239633)
		(end 141.738213 154.247382)
		(width 0.1)
		(layer "In4.Cu")
		(net 291)
	)
	(arc
		(start 125.167895 154.270809)
		(mid 125.142052 154.284352)
		(end 125.119053 154.302305)
		(width 0.1)
		(layer "In4.Cu")
		(net 291)
	)
	(segment
		(start 121.975 154.61)
		(end 121.505 154.61)
		(width 0.4)
		(layer "F.Cu")
		(net 292)
	)
	(via
		(at 121.975 154.61)
		(size 0.45)
		(drill 0.1)
		(layers "F.Cu" "B.Cu")
		(remove_unused_layers yes)
		(keep_end_layers yes)
		(zone_layer_connections)
		(net 292)
	)
	(segment
		(start 105.685805 161.379)
		(end 105.17 161.379)
		(width 0.16)
		(layer "B.Cu")
		(net 292)
	)
	(segment
		(start 116.221676 154.507527)
		(end 115.414801 155.314402)
		(width 0.16)
		(layer "B.Cu")
		(net 292)
	)
	(segment
		(start 106.518708 161.034)
		(end 106.842323 161.034)
		(width 0.16)
		(layer "B.Cu")
		(net 292)
	)
	(segment
		(start 116.807186 154.265001)
		(end 121.386049 154.265001)
		(width 0.16)
		(layer "B.Cu")
		(net 292)
	)
	(segment
		(start 121.975 154.61)
		(end 121.8025 154.4375)
		(width 0.16)
		(layer "B.Cu")
		(net 292)
	)
	(segment
		(start 110.048298 160.680905)
		(end 115.414801 155.314402)
		(width 0.16)
		(layer "B.Cu")
		(net 292)
	)
	(segment
		(start 108.534325 161.129)
		(end 107.071674 161.129)
		(width 0.16)
		(layer "B.Cu")
		(net 292)
	)
	(segment
		(start 108.763676 161.034)
		(end 109.195852 161.034)
		(width 0.16)
		(layer "B.Cu")
		(net 292)
	)
	(segment
		(start 121.975 154.61)
		(end 122.47 154.61)
		(width 0.16)
		(layer "B.Cu")
		(net 292)
	)
	(arc
		(start 106.842323 161.034)
		(mid 106.904385 161.046344)
		(end 106.956999 161.0815)
		(width 0.16)
		(layer "B.Cu")
		(net 292)
	)
	(arc
		(start 108.534325 161.129)
		(mid 108.596387 161.116655)
		(end 108.649001 161.0815)
		(width 0.16)
		(layer "B.Cu")
		(net 292)
	)
	(arc
		(start 116.807186 154.265001)
		(mid 116.49031 154.328031)
		(end 116.221676 154.507527)
		(width 0.16)
		(layer "B.Cu")
		(net 292)
	)
	(arc
		(start 110.048298 160.680905)
		(mid 109.657192 160.942233)
		(end 109.195852 161.034)
		(width 0.16)
		(layer "B.Cu")
		(net 292)
	)
	(arc
		(start 121.8025 154.4375)
		(mid 121.61143 154.309832)
		(end 121.386049 154.265001)
		(width 0.16)
		(layer "B.Cu")
		(net 292)
	)
	(arc
		(start 105.685805 161.379)
		(mid 105.911187 161.334168)
		(end 106.102257 161.2065)
		(width 0.16)
		(layer "B.Cu")
		(net 292)
	)
	(arc
		(start 106.518708 161.034)
		(mid 106.293326 161.078831)
		(end 106.102257 161.2065)
		(width 0.16)
		(layer "B.Cu")
		(net 292)
	)
	(arc
		(start 106.956999 161.0815)
		(mid 107.009612 161.116655)
		(end 107.071674 161.129)
		(width 0.16)
		(layer "B.Cu")
		(net 292)
	)
	(arc
		(start 108.763676 161.034)
		(mid 108.701614 161.046344)
		(end 108.649001 161.0815)
		(width 0.16)
		(layer "B.Cu")
		(net 292)
	)
	(segment
		(start 134.661843 161.831328)
		(end 135.256827 161.831328)
		(width 0.256)
		(layer "F.Cu")
		(net 293)
	)
	(segment
		(start 135.256827 161.831328)
		(end 135.480499 162.055)
		(width 0.256)
		(layer "F.Cu")
		(net 293)
	)
	(segment
		(start 135.480499 162.055)
		(end 137.7165 162.055)
		(width 0.256)
		(layer "F.Cu")
		(net 293)
	)
	(segment
		(start 137.7165 162.055)
		(end 137.7465 162.085)
		(width 0.15)
		(layer "F.Cu")
		(net 293)
	)
	(segment
		(start 134.182133 181.060633)
		(end 134.079602 181.060633)
		(width 0.16)
		(layer "F.Cu")
		(net 294)
	)
	(segment
		(start 132.656699 182.381004)
		(end 133.90457 181.133133)
		(width 0.16)
		(layer "F.Cu")
		(net 294)
	)
	(segment
		(start 128.600676 183.458)
		(end 130.056602 183.458)
		(width 0.16)
		(layer "F.Cu")
		(net 294)
	)
	(segment
		(start 128.371325 183.553)
		(end 127.801 183.553)
		(width 0.16)
		(layer "F.Cu")
		(net 294)
	)
	(via
		(at 134.182133 181.060633)
		(size 0.45)
		(drill 0.1)
		(layers "F.Cu" "B.Cu")
		(remove_unused_layers yes)
		(keep_end_layers yes)
		(zone_layer_connections)
		(net 294)
	)
	(arc
		(start 128.486001 183.5055)
		(mid 128.538614 183.470344)
		(end 128.600676 183.458)
		(width 0.16)
		(layer "F.Cu")
		(net 294)
	)
	(arc
		(start 133.90457 181.133133)
		(mid 133.984875 181.079475)
		(end 134.079602 181.060633)
		(width 0.16)
		(layer "F.Cu")
		(net 294)
	)
	(arc
		(start 132.656699 182.381004)
		(mid 131.463764 183.178097)
		(end 130.056602 183.458)
		(width 0.16)
		(layer "F.Cu")
		(net 294)
	)
	(arc
		(start 128.486001 183.5055)
		(mid 128.433387 183.540655)
		(end 128.371325 183.553)
		(width 0.16)
		(layer "F.Cu")
		(net 294)
	)
	(segment
		(start 182.845001 168.50188)
		(end 182.845001 168.677094)
		(width 0.16)
		(layer "B.Cu")
		(net 294)
	)
	(segment
		(start 178.877973 172.440409)
		(end 178.877974 172.440409)
		(width 0.16)
		(layer "B.Cu")
		(net 294)
	)
	(segment
		(start 180.12583 171.425522)
		(end 180.650956 171.95065)
		(width 0.16)
		(layer "B.Cu")
		(net 294)
	)
	(segment
		(start 180.016228 171.31592)
		(end 180.12583 171.425522)
		(width 0.16)
		(layer "B.Cu")
		(net 294)
	)
	(segment
		(start 180.650957 172.153848)
		(end 180.507673 172.297133)
		(width 0.16)
		(layer "B.Cu")
		(net 294)
	)
	(segment
		(start 136.56 183.521016)
		(end 136.433984 183.521016)
		(width 0.16)
		(layer "B.Cu")
		(net 294)
	)
	(segment
		(start 179.021248 171.65552)
		(end 179.021248 171.655521)
		(width 0.16)
		(layer "B.Cu")
		(net 294)
	)
	(segment
		(start 178.034859 174.553004)
		(end 178.034858 174.553006)
		(width 0.16)
		(layer "B.Cu")
		(net 294)
	)
	(segment
		(start 180.304474 172.297134)
		(end 180.304475 172.297132)
		(width 0.16)
		(layer "B.Cu")
		(net 294)
	)
	(segment
		(start 137.79 183.805)
		(end 137.66405 183.805)
		(width 0.16)
		(layer "B.Cu")
		(net 294)
	)
	(segment
		(start 137.932025 183.662974)
		(end 137.932025 183.662975)
		(width 0.16)
		(layer "B.Cu")
		(net 294)
	)
	(segment
		(start 180.960957 170.590398)
		(end 180.851354 170.480795)
		(width 0.16)
		(layer "B.Cu")
		(net 294)
	)
	(segment
		(start 177.746602 173.571781)
		(end 178.067409 173.892588)
		(width 0.16)
		(layer "B.Cu")
		(net 294)
	)
	(segment
		(start 140.381908 183.805)
		(end 138.48405 183.805)
		(width 0.16)
		(layer "B.Cu")
		(net 294)
	)
	(segment
		(start 177.889876 172.786893)
		(end 177.746602 172.930166)
		(width 0.16)
		(layer "B.Cu")
		(net 294)
	)
	(segment
		(start 182.510001 167.93)
		(end 182.677501 168.0975)
		(width 0.16)
		(layer "B.Cu")
		(net 294)
	)
	(segment
		(start 137.522025 183.662975)
		(end 137.522025 183.662974)
		(width 0.16)
		(layer "B.Cu")
		(net 294)
	)
	(segment
		(start 175.866026 175.874769)
		(end 173.004495 178.7363)
		(width 0.16)
		(layer "B.Cu")
		(net 294)
	)
	(segment
		(start 178.034858 174.553006)
		(end 177.925256 174.443404)
		(width 0.16)
		(layer "B.Cu")
		(net 294)
	)
	(segment
		(start 178.38134 174.395978)
		(end 178.224314 174.553005)
		(width 0.16)
		(layer "B.Cu")
		(net 294)
	)
	(segment
		(start 134.044602 183.105398)
		(end 133.597116 182.657912)
		(width 0.16)
		(layer "B.Cu")
		(net 294)
	)
	(segment
		(start 177.746601 173.571781)
		(end 177.746602 173.571781)
		(width 0.16)
		(layer "B.Cu")
		(net 294)
	)
	(segment
		(start 144.492002 181.838792)
		(end 144.041758 182.289037)
		(width 0.16)
		(layer "B.Cu")
		(net 294)
	)
	(segment
		(start 180.304475 172.297132)
		(end 179.662863 171.655521)
		(width 0.16)
		(layer "B.Cu")
		(net 294)
	)
	(segment
		(start 179.021248 171.655521)
		(end 178.877974 171.798794)
		(width 0.16)
		(layer "B.Cu")
		(net 294)
	)
	(segment
		(start 177.889876 172.786892)
		(end 177.889876 172.786893)
		(width 0.16)
		(layer "B.Cu")
		(net 294)
	)
	(segment
		(start 133.597116 181.440587)
		(end 133.90457 181.133133)
		(width 0.16)
		(layer "B.Cu")
		(net 294)
	)
	(segment
		(start 180.650956 172.153848)
		(end 180.650957 172.153848)
		(width 0.16)
		(layer "B.Cu")
		(net 294)
	)
	(segment
		(start 178.067409 173.892588)
		(end 178.067409 173.892591)
		(width 0.16)
		(layer "B.Cu")
		(net 294)
	)
	(segment
		(start 136.15 183.805)
		(end 135.73359 183.805)
		(width 0.16)
		(layer "B.Cu")
		(net 294)
	)
	(segment
		(start 169.362171 180.245)
		(end 148.339759 180.245)
		(width 0.16)
		(layer "B.Cu")
		(net 294)
	)
	(segment
		(start 179.173091 173.428492)
		(end 178.961902 173.217303)
		(width 0.16)
		(layer "B.Cu")
		(net 294)
	)
	(segment
		(start 178.961902 173.217303)
		(end 178.531491 172.786893)
		(width 0.16)
		(layer "B.Cu")
		(net 294)
	)
	(segment
		(start 178.381341 174.395977)
		(end 178.38134 174.395978)
		(width 0.16)
		(layer "B.Cu")
		(net 294)
	)
	(segment
		(start 177.297396 174.443403)
		(end 175.866026 175.874769)
		(width 0.16)
		(layer "B.Cu")
		(net 294)
	)
	(segment
		(start 177.297395 174.443405)
		(end 177.297396 174.443403)
		(width 0.16)
		(layer "B.Cu")
		(net 294)
	)
	(segment
		(start 180.223508 170.480795)
		(end 180.016228 170.688074)
		(width 0.16)
		(layer "B.Cu")
		(net 294)
	)
	(segment
		(start 178.067409 173.892591)
		(end 178.38134 174.206522)
		(width 0.16)
		(layer "B.Cu")
		(net 294)
	)
	(segment
		(start 137.112025 183.662974)
		(end 137.112025 183.662975)
		(width 0.16)
		(layer "B.Cu")
		(net 294)
	)
	(segment
		(start 179.198781 172.761216)
		(end 179.198781 172.761219)
		(width 0.16)
		(layer "B.Cu")
		(net 294)
	)
	(segment
		(start 137.38 183.520949)
		(end 137.25405 183.520949)
		(width 0.16)
		(layer "B.Cu")
		(net 294)
	)
	(segment
		(start 138.342025 183.662975)
		(end 138.342025 183.662974)
		(width 0.16)
		(layer "B.Cu")
		(net 294)
	)
	(segment
		(start 136.97 183.805)
		(end 136.843984 183.805)
		(width 0.16)
		(layer "B.Cu")
		(net 294)
	)
	(segment
		(start 179.198781 172.761219)
		(end 179.519572 173.08201)
		(width 0.16)
		(layer "B.Cu")
		(net 294)
	)
	(segment
		(start 179.519572 173.285186)
		(end 179.376267 173.428492)
		(width 0.16)
		(layer "B.Cu")
		(net 294)
	)
	(segment
		(start 182.690357 169.050438)
		(end 181.150397 170.590398)
		(width 0.16)
		(layer "B.Cu")
		(net 294)
	)
	(segment
		(start 138.2 183.520949)
		(end 138.07405 183.520949)
		(width 0.16)
		(layer "B.Cu")
		(net 294)
	)
	(segment
		(start 134.079602 181.060633)
		(end 134.182133 181.060633)
		(width 0.16)
		(layer "B.Cu")
		(net 294)
	)
	(segment
		(start 178.877974 172.440409)
		(end 179.198781 172.761216)
		(width 0.16)
		(layer "B.Cu")
		(net 294)
	)
	(arc
		(start 177.746602 172.930166)
		(mid 177.613719 173.250973)
		(end 177.746601 173.571781)
		(width 0.16)
		(layer "B.Cu")
		(net 294)
	)
	(arc
		(start 181.150397 170.590398)
		(mid 181.055677 170.629632)
		(end 180.960957 170.590398)
		(width 0.16)
		(layer "B.Cu")
		(net 294)
	)
	(arc
		(start 136.701992 183.663008)
		(mid 136.660404 183.562604)
		(end 136.56 183.521016)
		(width 0.16)
		(layer "B.Cu")
		(net 294)
	)
	(arc
		(start 133.345 182.04925)
		(mid 133.410522 181.719844)
		(end 133.597116 181.440587)
		(width 0.16)
		(layer "B.Cu")
		(net 294)
	)
	(arc
		(start 137.66405 183.805)
		(mid 137.563623 183.763402)
		(end 137.522025 183.662975)
		(width 0.16)
		(layer "B.Cu")
		(net 294)
	)
	(arc
		(start 180.851354 170.480795)
		(mid 180.537431 170.350764)
		(end 180.223508 170.480795)
		(width 0.16)
		(layer "B.Cu")
		(net 294)
	)
	(arc
		(start 133.90457 181.133133)
		(mid 133.984875 181.079475)
		(end 134.079602 181.060633)
		(width 0.16)
		(layer "B.Cu")
		(net 294)
	)
	(arc
		(start 178.224314 174.553005)
		(mid 178.129585 174.592243)
		(end 178.034859 174.553004)
		(width 0.16)
		(layer "B.Cu")
		(net 294)
	)
	(arc
		(start 137.522025 183.662974)
		(mid 137.480427 183.562547)
		(end 137.38 183.520949)
		(width 0.16)
		(layer "B.Cu")
		(net 294)
	)
	(arc
		(start 178.38134 174.206522)
		(mid 178.420579 174.301248)
		(end 178.381341 174.395977)
		(width 0.16)
		(layer "B.Cu")
		(net 294)
	)
	(arc
		(start 136.291992 183.663008)
		(mid 136.250404 183.763412)
		(end 136.15 183.805)
		(width 0.16)
		(layer "B.Cu")
		(net 294)
	)
	(arc
		(start 138.07405 183.520949)
		(mid 137.973623 183.562547)
		(end 137.932025 183.662974)
		(width 0.16)
		(layer "B.Cu")
		(net 294)
	)
	(arc
		(start 179.519572 173.08201)
		(mid 179.561652 173.183597)
		(end 179.519572 173.285186)
		(width 0.16)
		(layer "B.Cu")
		(net 294)
	)
	(arc
		(start 182.677501 168.0975)
		(mid 182.801469 168.283031)
		(end 182.845001 168.50188)
		(width 0.16)
		(layer "B.Cu")
		(net 294)
	)
	(arc
		(start 178.877974 171.798794)
		(mid 178.745091 172.119601)
		(end 178.877973 172.440409)
		(width 0.16)
		(layer "B.Cu")
		(net 294)
	)
	(arc
		(start 136.433984 183.521016)
		(mid 136.33358 183.562604)
		(end 136.291992 183.663008)
		(width 0.16)
		(layer "B.Cu")
		(net 294)
	)
	(arc
		(start 138.342025 183.662974)
		(mid 138.300427 183.562547)
		(end 138.2 183.520949)
		(width 0.16)
		(layer "B.Cu")
		(net 294)
	)
	(arc
		(start 135.73359 183.805)
		(mid 134.819516 183.623179)
		(end 134.044602 183.105398)
		(width 0.16)
		(layer "B.Cu")
		(net 294)
	)
	(arc
		(start 137.25405 183.520949)
		(mid 137.153623 183.562547)
		(end 137.112025 183.662974)
		(width 0.16)
		(layer "B.Cu")
		(net 294)
	)
	(arc
		(start 177.925256 174.443404)
		(mid 177.611326 174.313369)
		(end 177.297395 174.443405)
		(width 0.16)
		(layer "B.Cu")
		(net 294)
	)
	(arc
		(start 180.507673 172.297133)
		(mid 180.406075 172.339216)
		(end 180.304474 172.297134)
		(width 0.16)
		(layer "B.Cu")
		(net 294)
	)
	(arc
		(start 179.376267 173.428492)
		(mid 179.274678 173.470572)
		(end 179.173091 173.428492)
		(width 0.16)
		(layer "B.Cu")
		(net 294)
	)
	(arc
		(start 178.531491 172.786893)
		(mid 178.210684 172.65401)
		(end 177.889876 172.786892)
		(width 0.16)
		(layer "B.Cu")
		(net 294)
	)
	(arc
		(start 136.843984 183.805)
		(mid 136.74358 183.763412)
		(end 136.701992 183.663008)
		(width 0.16)
		(layer "B.Cu")
		(net 294)
	)
	(arc
		(start 180.650956 171.95065)
		(mid 180.693041 172.052248)
		(end 180.650956 172.153848)
		(width 0.16)
		(layer "B.Cu")
		(net 294)
	)
	(arc
		(start 182.845001 168.677094)
		(mid 182.80481 168.879146)
		(end 182.690357 169.050438)
		(width 0.16)
		(layer "B.Cu")
		(net 294)
	)
	(arc
		(start 180.016228 170.688074)
		(mid 179.886197 171.001997)
		(end 180.016228 171.31592)
		(width 0.16)
		(layer "B.Cu")
		(net 294)
	)
	(arc
		(start 144.041758 182.289037)
		(mid 142.362605 183.411014)
		(end 140.381908 183.805)
		(width 0.16)
		(layer "B.Cu")
		(net 294)
	)
	(arc
		(start 179.662863 171.655521)
		(mid 179.342056 171.522638)
		(end 179.021248 171.65552)
		(width 0.16)
		(layer "B.Cu")
		(net 294)
	)
	(arc
		(start 137.112025 183.662975)
		(mid 137.070427 183.763402)
		(end 136.97 183.805)
		(width 0.16)
		(layer "B.Cu")
		(net 294)
	)
	(arc
		(start 148.339759 180.245)
		(mid 146.257368 180.659213)
		(end 144.492002 181.838792)
		(width 0.16)
		(layer "B.Cu")
		(net 294)
	)
	(arc
		(start 137.932025 183.662975)
		(mid 137.890427 183.763402)
		(end 137.79 183.805)
		(width 0.16)
		(layer "B.Cu")
		(net 294)
	)
	(arc
		(start 138.48405 183.805)
		(mid 138.383623 183.763402)
		(end 138.342025 183.662975)
		(width 0.16)
		(layer "B.Cu")
		(net 294)
	)
	(arc
		(start 173.004495 178.7363)
		(mid 171.333383 179.852902)
		(end 169.362171 180.245)
		(width 0.16)
		(layer "B.Cu")
		(net 294)
	)
	(arc
		(start 133.597116 182.657912)
		(mid 133.410522 182.378655)
		(end 133.345 182.04925)
		(width 0.16)
		(layer "B.Cu")
		(net 294)
	)
	(segment
		(start 133.757867 180.636367)
		(end 133.757867 180.738898)
		(width 0.16)
		(layer "F.Cu")
		(net 295)
	)
	(segment
		(start 132.435717 182.163578)
		(end 133.685366 180.913929)
		(width 0.16)
		(layer "F.Cu")
		(net 295)
	)
	(segment
		(start 128.371325 183.053)
		(end 127.801 183.053)
		(width 0.16)
		(layer "F.Cu")
		(net 295)
	)
	(segment
		(start 128.600676 183.148)
		(end 130.059113 183.148)
		(width 0.16)
		(layer "F.Cu")
		(net 295)
	)
	(via
		(at 133.757867 180.636367)
		(size 0.45)
		(drill 0.1)
		(layers "F.Cu" "B.Cu")
		(remove_unused_layers yes)
		(keep_end_layers yes)
		(zone_layer_connections)
		(net 295)
	)
	(arc
		(start 132.435717 182.163578)
		(mid 131.345322 182.892157)
		(end 130.059113 183.148)
		(width 0.16)
		(layer "F.Cu")
		(net 295)
	)
	(arc
		(start 128.486001 183.1005)
		(mid 128.538614 183.135655)
		(end 128.600676 183.148)
		(width 0.16)
		(layer "F.Cu")
		(net 295)
	)
	(arc
		(start 128.486001 183.1005)
		(mid 128.433387 183.065344)
		(end 128.371325 183.053)
		(width 0.16)
		(layer "F.Cu")
		(net 295)
	)
	(arc
		(start 133.757867 180.738898)
		(mid 133.739024 180.833624)
		(end 133.685366 180.913929)
		(width 0.16)
		(layer "F.Cu")
		(net 295)
	)
	(segment
		(start 178.600543 174.615181)
		(end 178.443517 174.772208)
		(width 0.16)
		(layer "B.Cu")
		(net 295)
	)
	(segment
		(start 179.097176 172.221206)
		(end 179.097177 172.221206)
		(width 0.16)
		(layer "B.Cu")
		(net 295)
	)
	(segment
		(start 133.757867 180.738898)
		(end 133.757867 180.636367)
		(width 0.16)
		(layer "B.Cu")
		(net 295)
	)
	(segment
		(start 180.741754 170.809601)
		(end 180.632151 170.699998)
		(width 0.16)
		(layer "B.Cu")
		(net 295)
	)
	(segment
		(start 177.516599 174.662606)
		(end 173.217996 178.961207)
		(width 0.16)
		(layer "B.Cu")
		(net 295)
	)
	(segment
		(start 178.109079 173.006096)
		(end 177.965805 173.149369)
		(width 0.16)
		(layer "B.Cu")
		(net 295)
	)
	(segment
		(start 179.240451 171.874724)
		(end 179.097177 172.017997)
		(width 0.16)
		(layer "B.Cu")
		(net 295)
	)
	(segment
		(start 178.109079 173.006095)
		(end 178.109079 173.006096)
		(width 0.16)
		(layer "B.Cu")
		(net 295)
	)
	(segment
		(start 180.235431 171.096716)
		(end 180.235432 171.096717)
		(width 0.16)
		(layer "B.Cu")
		(net 295)
	)
	(segment
		(start 182.886581 169.292622)
		(end 181.369601 170.809602)
		(width 0.16)
		(layer "B.Cu")
		(net 295)
	)
	(segment
		(start 180.235432 171.096717)
		(end 180.870161 171.731445)
		(width 0.16)
		(layer "B.Cu")
		(net 295)
	)
	(segment
		(start 177.965804 173.352578)
		(end 177.965805 173.352578)
		(width 0.16)
		(layer "B.Cu")
		(net 295)
	)
	(segment
		(start 183.49 167.93)
		(end 183.3225 168.097499)
		(width 0.16)
		(layer "B.Cu")
		(net 295)
	)
	(segment
		(start 183.155001 168.501879)
		(end 183.155001 168.644601)
		(width 0.16)
		(layer "B.Cu")
		(net 295)
	)
	(segment
		(start 179.738775 173.504389)
		(end 179.59547 173.647695)
		(width 0.16)
		(layer "B.Cu")
		(net 295)
	)
	(segment
		(start 169.37024 180.555)
		(end 148.347987 180.555)
		(width 0.16)
		(layer "B.Cu")
		(net 295)
	)
	(segment
		(start 180.870159 172.373051)
		(end 180.87016 172.373051)
		(width 0.16)
		(layer "B.Cu")
		(net 295)
	)
	(segment
		(start 181.369601 170.809602)
		(end 181.3696 170.809601)
		(width 0.16)
		(layer "B.Cu")
		(net 295)
	)
	(segment
		(start 177.815656 174.772207)
		(end 177.815655 174.772209)
		(width 0.16)
		(layer "B.Cu")
		(net 295)
	)
	(segment
		(start 144.705383 182.063819)
		(end 144.247996 182.521207)
		(width 0.16)
		(layer "B.Cu")
		(net 295)
	)
	(segment
		(start 179.097177 172.221206)
		(end 179.738777 172.862805)
		(width 0.16)
		(layer "B.Cu")
		(net 295)
	)
	(segment
		(start 140.40024 184.115)
		(end 135.733587 184.115)
		(width 0.16)
		(layer "B.Cu")
		(net 295)
	)
	(segment
		(start 178.953888 173.647695)
		(end 178.742699 173.436506)
		(width 0.16)
		(layer "B.Cu")
		(net 295)
	)
	(segment
		(start 180.442712 170.699998)
		(end 180.235432 170.907277)
		(width 0.16)
		(layer "B.Cu")
		(net 295)
	)
	(segment
		(start 180.442711 170.699998)
		(end 180.442712 170.699998)
		(width 0.16)
		(layer "B.Cu")
		(net 295)
	)
	(segment
		(start 178.742699 173.436506)
		(end 178.312288 173.006096)
		(width 0.16)
		(layer "B.Cu")
		(net 295)
	)
	(segment
		(start 180.085272 172.516335)
		(end 179.44366 171.874724)
		(width 0.16)
		(layer "B.Cu")
		(net 295)
	)
	(segment
		(start 179.240451 171.874723)
		(end 179.240451 171.874724)
		(width 0.16)
		(layer "B.Cu")
		(net 295)
	)
	(segment
		(start 177.965805 173.352578)
		(end 178.600545 173.987317)
		(width 0.16)
		(layer "B.Cu")
		(net 295)
	)
	(segment
		(start 133.825398 183.324602)
		(end 133.377914 182.877118)
		(width 0.16)
		(layer "B.Cu")
		(net 295)
	)
	(segment
		(start 177.516598 174.662608)
		(end 177.516599 174.662606)
		(width 0.16)
		(layer "B.Cu")
		(net 295)
	)
	(segment
		(start 180.085271 172.516337)
		(end 180.085272 172.516335)
		(width 0.16)
		(layer "B.Cu")
		(net 295)
	)
	(segment
		(start 180.87016 172.373051)
		(end 180.726876 172.516336)
		(width 0.16)
		(layer "B.Cu")
		(net 295)
	)
	(segment
		(start 177.815655 174.772209)
		(end 177.706053 174.662607)
		(width 0.16)
		(layer "B.Cu")
		(net 295)
	)
	(segment
		(start 133.377914 181.221381)
		(end 133.685366 180.913929)
		(width 0.16)
		(layer "B.Cu")
		(net 295)
	)
	(segment
		(start 178.600544 174.61518)
		(end 178.600543 174.615181)
		(width 0.16)
		(layer "B.Cu")
		(net 295)
	)
	(arc
		(start 173.217996 178.961207)
		(mid 171.45263 180.140786)
		(end 169.37024 180.555)
		(width 0.16)
		(layer "B.Cu")
		(net 295)
	)
	(arc
		(start 179.738777 172.862805)
		(mid 179.871652 173.183597)
		(end 179.738775 173.504389)
		(width 0.16)
		(layer "B.Cu")
		(net 295)
	)
	(arc
		(start 179.44366 171.874724)
		(mid 179.342056 171.832638)
		(end 179.240451 171.874723)
		(width 0.16)
		(layer "B.Cu")
		(net 295)
	)
	(arc
		(start 180.235432 170.907277)
		(mid 180.196197 171.001996)
		(end 180.235431 171.096716)
		(width 0.16)
		(layer "B.Cu")
		(net 295)
	)
	(arc
		(start 144.247996 182.521207)
		(mid 142.48263 183.700786)
		(end 140.40024 184.115)
		(width 0.16)
		(layer "B.Cu")
		(net 295)
	)
	(arc
		(start 133.685366 180.913929)
		(mid 133.739024 180.833624)
		(end 133.757867 180.738898)
		(width 0.16)
		(layer "B.Cu")
		(net 295)
	)
	(arc
		(start 133.377914 182.877118)
		(mid 133.12412 182.497289)
		(end 133.035 182.04925)
		(width 0.16)
		(layer "B.Cu")
		(net 295)
	)
	(arc
		(start 177.706053 174.662607)
		(mid 177.611326 174.623369)
		(end 177.516598 174.662608)
		(width 0.16)
		(layer "B.Cu")
		(net 295)
	)
	(arc
		(start 181.3696 170.809601)
		(mid 181.055677 170.939632)
		(end 180.741754 170.809601)
		(width 0.16)
		(layer "B.Cu")
		(net 295)
	)
	(arc
		(start 177.965805 173.149369)
		(mid 177.923719 173.250973)
		(end 177.965804 173.352578)
		(width 0.16)
		(layer "B.Cu")
		(net 295)
	)
	(arc
		(start 135.733587 184.115)
		(mid 134.700882 183.909582)
		(end 133.825398 183.324602)
		(width 0.16)
		(layer "B.Cu")
		(net 295)
	)
	(arc
		(start 183.3225 168.097499)
		(mid 183.198532 168.28303)
		(end 183.155001 168.501879)
		(width 0.16)
		(layer "B.Cu")
		(net 295)
	)
	(arc
		(start 180.632151 170.699998)
		(mid 180.537431 170.660764)
		(end 180.442711 170.699998)
		(width 0.16)
		(layer "B.Cu")
		(net 295)
	)
	(arc
		(start 183.155001 168.644601)
		(mid 183.08524 168.995307)
		(end 182.886581 169.292622)
		(width 0.16)
		(layer "B.Cu")
		(net 295)
	)
	(arc
		(start 133.035 182.04925)
		(mid 133.12412 181.60121)
		(end 133.377914 181.221381)
		(width 0.16)
		(layer "B.Cu")
		(net 295)
	)
	(arc
		(start 148.347987 180.555)
		(mid 146.376623 180.947129)
		(end 144.705383 182.063819)
		(width 0.16)
		(layer "B.Cu")
		(net 295)
	)
	(arc
		(start 179.097177 172.017997)
		(mid 179.055091 172.119601)
		(end 179.097176 172.221206)
		(width 0.16)
		(layer "B.Cu")
		(net 295)
	)
	(arc
		(start 178.312288 173.006096)
		(mid 178.210684 172.96401)
		(end 178.109079 173.006095)
		(width 0.16)
		(layer "B.Cu")
		(net 295)
	)
	(arc
		(start 180.870161 171.731445)
		(mid 181.003041 172.052248)
		(end 180.870159 172.373051)
		(width 0.16)
		(layer "B.Cu")
		(net 295)
	)
	(arc
		(start 179.59547 173.647695)
		(mid 179.274678 173.780572)
		(end 178.953888 173.647695)
		(width 0.16)
		(layer "B.Cu")
		(net 295)
	)
	(arc
		(start 180.726876 172.516336)
		(mid 180.406075 172.649216)
		(end 180.085271 172.516337)
		(width 0.16)
		(layer "B.Cu")
		(net 295)
	)
	(arc
		(start 178.600545 173.987317)
		(mid 178.730579 174.301248)
		(end 178.600544 174.61518)
		(width 0.16)
		(layer "B.Cu")
		(net 295)
	)
	(arc
		(start 178.443517 174.772208)
		(mid 178.129585 174.902243)
		(end 177.815656 174.772207)
		(width 0.16)
		(layer "B.Cu")
		(net 295)
	)
	(segment
		(start 138.724499 172.564)
		(end 138.689499 172.564)
		(width 0.15)
		(layer "F.Cu")
		(net 296)
	)
	(segment
		(start 138.024499 171.899)
		(end 138.024499 171.398)
		(width 0.15)
		(layer "F.Cu")
		(net 296)
	)
	(segment
		(start 138.689499 172.564)
		(end 138.024499 171.899)
		(width 0.15)
		(layer "F.Cu")
		(net 296)
	)
	(segment
		(start 113.86 164.62)
		(end 115.57 166.33)
		(width 0.201)
		(layer "F.Cu")
		(net 297)
	)
	(segment
		(start 119.281 166.33)
		(end 119.931 165.68)
		(width 0.201)
		(layer "F.Cu")
		(net 297)
	)
	(segment
		(start 115.57 166.33)
		(end 119.281 166.33)
		(width 0.201)
		(layer "F.Cu")
		(net 297)
	)
	(via
		(at 119.931 165.68)
		(size 0.45)
		(drill 0.1)
		(layers "F.Cu" "B.Cu")
		(remove_unused_layers yes)
		(keep_end_layers yes)
		(zone_layer_connections)
		(net 297)
	)
	(via
		(at 113.86 164.62)
		(size 0.45)
		(drill 0.1)
		(layers "F.Cu" "B.Cu")
		(remove_unused_layers yes)
		(keep_end_layers yes)
		(zone_layer_connections)
		(net 297)
	)
	(segment
		(start 111.94 167.02)
		(end 111.5 167.46)
		(width 0.201)
		(layer "B.Cu")
		(net 297)
	)
	(segment
		(start 108.191 164.366)
		(end 110.046 164.366)
		(width 0.201)
		(layer "B.Cu")
		(net 297)
	)
	(segment
		(start 110.38 167.43)
		(end 110.38 167.9)
		(width 0.201)
		(layer "B.Cu")
		(net 297)
	)
	(segment
		(start 113.219 164.62)
		(end 113.86 164.62)
		(width 0.201)
		(layer "B.Cu")
		(net 297)
	)
	(segment
		(start 112.33 164.62)
		(end 112.33 165.29)
		(width 0.201)
		(layer "B.Cu")
		(net 297)
	)
	(segment
		(start 119.051 166.36)
		(end 119.941 166.36)
		(width 0.15)
		(layer "B.Cu")
		(net 297)
	)
	(segment
		(start 108.187 164.368)
		(end 108.189 164.366)
		(width 0.201)
		(layer "B.Cu")
		(net 297)
	)
	(segment
		(start 111.94 165.68)
		(end 111.94 167.02)
		(width 0.201)
		(layer "B.Cu")
		(net 297)
	)
	(segment
		(start 119.931 165.68)
		(end 119.931 166.36)
		(width 0.15)
		(layer "B.Cu")
		(net 297)
	)
	(segment
		(start 110.38 167.9)
		(end 110.85 168.37)
		(width 0.201)
		(layer "B.Cu")
		(net 297)
	)
	(segment
		(start 110.046 164.366)
		(end 110.3 164.62)
		(width 0.201)
		(layer "B.Cu")
		(net 297)
	)
	(segment
		(start 111.5 167.46)
		(end 111.5 168.37)
		(width 0.201)
		(layer "B.Cu")
		(net 297)
	)
	(segment
		(start 110.85 168.37)
		(end 111.5 168.37)
		(width 0.201)
		(layer "B.Cu")
		(net 297)
	)
	(segment
		(start 110.3 164.62)
		(end 112.33 164.62)
		(width 0.201)
		(layer "B.Cu")
		(net 297)
	)
	(segment
		(start 105.17 164.368)
		(end 108.187 164.368)
		(width 0.201)
		(layer "B.Cu")
		(net 297)
	)
	(segment
		(start 112.33 164.62)
		(end 113.219 164.62)
		(width 0.201)
		(layer "B.Cu")
		(net 297)
	)
	(segment
		(start 112.33 165.29)
		(end 111.94 165.68)
		(width 0.201)
		(layer "B.Cu")
		(net 297)
	)
	(segment
		(start 137.524499 171.398)
		(end 137.524499 172.464)
		(width 0.15)
		(layer "F.Cu")
		(net 298)
	)
	(segment
		(start 137.524499 172.464)
		(end 137.624499 172.564)
		(width 0.15)
		(layer "F.Cu")
		(net 298)
	)
	(segment
		(start 137.024499 172.085171)
		(end 136.547342 172.562328)
		(width 0.15)
		(layer "F.Cu")
		(net 299)
	)
	(segment
		(start 137.024499 171.398)
		(end 137.024499 172.085171)
		(width 0.15)
		(layer "F.Cu")
		(net 299)
	)
	(segment
		(start 135.951999 172.2265)
		(end 135.761999 172.2265)
		(width 0.15)
		(layer "F.Cu")
		(net 300)
	)
	(segment
		(start 136.530499 171.648)
		(end 135.951999 172.2265)
		(width 0.15)
		(layer "F.Cu")
		(net 300)
	)
	(segment
		(start 135.761999 172.2265)
		(end 135.424499 172.564)
		(width 0.15)
		(layer "F.Cu")
		(net 300)
	)
	(segment
		(start 136.530499 171.398)
		(end 136.530499 171.648)
		(width 0.15)
		(layer "F.Cu")
		(net 300)
	)
	(segment
		(start 143.730499 170.378)
		(end 143.724499 170.384)
		(width 0.15)
		(layer "F.Cu")
		(net 301)
	)
	(segment
		(start 146.276499 170.378)
		(end 143.730499 170.378)
		(width 0.15)
		(layer "F.Cu")
		(net 301)
	)
	(segment
		(start 138.102149 140.485)
		(end 141.332851 140.485)
		(width 0.15)
		(layer "F.Cu")
		(net 302)
	)
	(segment
		(start 101.843 139.445)
		(end 101.843 148.085)
		(width 0.4)
		(layer "F.Cu")
		(net 321)
	)
	(segment
		(start 109.344499 148.085)
		(end 109.349499 148.08)
		(width 0.4)
		(layer "F.Cu")
		(net 321)
	)
	(segment
		(start 106.023 139.445)
		(end 101.843 139.445)
		(width 0.4)
		(layer "F.Cu")
		(net 321)
	)
	(segment
		(start 101.843 148.085)
		(end 106.023 148.085)
		(width 0.4)
		(layer "F.Cu")
		(net 321)
	)
	(segment
		(start 105.751 148.085)
		(end 109.344499 148.085)
		(width 0.4)
		(layer "F.Cu")
		(net 321)
	)
	(segment
		(start 118.67 145.61)
		(end 118.67 147.61)
		(width 0.201)
		(layer "F.Cu")
		(net 322)
	)
	(segment
		(start 119.62 145.61)
		(end 118.67 145.61)
		(width 0.201)
		(layer "F.Cu")
		(net 322)
	)
	(segment
		(start 118.67 147.61)
		(end 118.67 154.61)
		(width 0.201)
		(layer "F.Cu")
		(net 322)
	)
	(via
		(at 254.65 126.15)
		(size 0.45)
		(drill 0.1)
		(layers "F.Cu" "B.Cu")
		(remove_unused_layers yes)
		(keep_end_layers yes)
		(zone_layer_connections)
		(net 325)
	)
	(via
		(at 263.4 126.1)
		(size 0.45)
		(drill 0.1)
		(layers "F.Cu" "B.Cu")
		(remove_unused_layers yes)
		(keep_end_layers yes)
		(zone_layer_connections)
		(net 325)
	)
	(via
		(at 260.63 125.56)
		(size 0.45)
		(drill 0.1)
		(layers "F.Cu" "B.Cu")
		(remove_unused_layers yes)
		(keep_end_layers yes)
		(zone_layer_connections)
		(net 325)
	)
	(via
		(at 257.37 124.87)
		(size 0.45)
		(drill 0.1)
		(layers "F.Cu" "B.Cu")
		(remove_unused_layers yes)
		(keep_end_layers yes)
		(zone_layer_connections)
		(net 325)
	)
	(via
		(at 263.52 125.56)
		(size 0.45)
		(drill 0.1)
		(layers "F.Cu" "B.Cu")
		(remove_unused_layers yes)
		(keep_end_layers yes)
		(zone_layer_connections)
		(net 325)
	)
	(via
		(at 255.94 123.43)
		(size 0.45)
		(drill 0.1)
		(layers "F.Cu" "B.Cu")
		(remove_unused_layers yes)
		(keep_end_layers yes)
		(zone_layer_connections)
		(net 325)
	)
	(via
		(at 255.26 123.43)
		(size 0.45)
		(drill 0.1)
		(layers "F.Cu" "B.Cu")
		(remove_unused_layers yes)
		(keep_end_layers yes)
		(zone_layer_connections)
		(net 325)
	)
	(via
		(at 257.37 124.16)
		(size 0.45)
		(drill 0.1)
		(layers "F.Cu" "B.Cu")
		(remove_unused_layers yes)
		(keep_end_layers yes)
		(zone_layer_connections)
		(net 325)
	)
	(via
		(at 256.65 126.29)
		(size 0.45)
		(drill 0.1)
		(layers "F.Cu" "B.Cu")
		(remove_unused_layers yes)
		(keep_end_layers yes)
		(zone_layer_connections)
		(net 325)
	)
	(via
		(at 263.52 124.88)
		(size 0.45)
		(drill 0.1)
		(layers "F.Cu" "B.Cu")
		(remove_unused_layers yes)
		(keep_end_layers yes)
		(zone_layer_connections)
		(net 325)
	)
	(via
		(at 260.63 124.17)
		(size 0.45)
		(drill 0.1)
		(layers "F.Cu" "B.Cu")
		(remove_unused_layers yes)
		(keep_end_layers yes)
		(zone_layer_connections)
		(net 325)
	)
	(via
		(at 262.09 126.3)
		(size 0.45)
		(drill 0.1)
		(layers "F.Cu" "B.Cu")
		(remove_unused_layers yes)
		(keep_end_layers yes)
		(zone_layer_connections)
		(net 325)
	)
	(via
		(at 261.41 123.44)
		(size 0.45)
		(drill 0.1)
		(layers "F.Cu" "B.Cu")
		(remove_unused_layers yes)
		(keep_end_layers yes)
		(zone_layer_connections)
		(net 325)
	)
	(via
		(at 257.25 126.09)
		(size 0.45)
		(drill 0.1)
		(layers "F.Cu" "B.Cu")
		(remove_unused_layers yes)
		(keep_end_layers yes)
		(zone_layer_connections)
		(net 325)
	)
	(via
		(at 260.63 124.88)
		(size 0.45)
		(drill 0.1)
		(layers "F.Cu" "B.Cu")
		(remove_unused_layers yes)
		(keep_end_layers yes)
		(zone_layer_connections)
		(net 325)
	)
	(via
		(at 262.8 123.44)
		(size 0.45)
		(drill 0.1)
		(layers "F.Cu" "B.Cu")
		(remove_unused_layers yes)
		(keep_end_layers yes)
		(zone_layer_connections)
		(net 325)
	)
	(via
		(at 262.8 126.3)
		(size 0.45)
		(drill 0.1)
		(layers "F.Cu" "B.Cu")
		(remove_unused_layers yes)
		(keep_end_layers yes)
		(zone_layer_connections)
		(net 325)
	)
	(via
		(at 254.67 123.56)
		(size 0.45)
		(drill 0.1)
		(layers "F.Cu" "B.Cu")
		(remove_unused_layers yes)
		(keep_end_layers yes)
		(zone_layer_connections)
		(net 325)
	)
	(via
		(at 263.52 124.17)
		(size 0.45)
		(drill 0.1)
		(layers "F.Cu" "B.Cu")
		(remove_unused_layers yes)
		(keep_end_layers yes)
		(zone_layer_connections)
		(net 325)
	)
	(via
		(at 262.09 123.44)
		(size 0.45)
		(drill 0.1)
		(layers "F.Cu" "B.Cu")
		(remove_unused_layers yes)
		(keep_end_layers yes)
		(zone_layer_connections)
		(net 325)
	)
	(via
		(at 256.65 123.43)
		(size 0.45)
		(drill 0.1)
		(layers "F.Cu" "B.Cu")
		(remove_unused_layers yes)
		(keep_end_layers yes)
		(zone_layer_connections)
		(net 325)
	)
	(via
		(at 260.82 123.57)
		(size 0.45)
		(drill 0.1)
		(layers "F.Cu" "B.Cu")
		(remove_unused_layers yes)
		(keep_end_layers yes)
		(zone_layer_connections)
		(net 325)
	)
	(via
		(at 257.37 125.55)
		(size 0.45)
		(drill 0.1)
		(layers "F.Cu" "B.Cu")
		(remove_unused_layers yes)
		(keep_end_layers yes)
		(zone_layer_connections)
		(net 325)
	)
	(via
		(at 260.8 126.16)
		(size 0.45)
		(drill 0.1)
		(layers "F.Cu" "B.Cu")
		(remove_unused_layers yes)
		(keep_end_layers yes)
		(zone_layer_connections)
		(net 325)
	)
	(via
		(at 257.22 123.57)
		(size 0.45)
		(drill 0.1)
		(layers "F.Cu" "B.Cu")
		(remove_unused_layers yes)
		(keep_end_layers yes)
		(zone_layer_connections)
		(net 325)
	)
	(via
		(at 255.26 126.29)
		(size 0.45)
		(drill 0.1)
		(layers "F.Cu" "B.Cu")
		(remove_unused_layers yes)
		(keep_end_layers yes)
		(zone_layer_connections)
		(net 325)
	)
	(via
		(at 254.48 125.55)
		(size 0.45)
		(drill 0.1)
		(layers "F.Cu" "B.Cu")
		(remove_unused_layers yes)
		(keep_end_layers yes)
		(zone_layer_connections)
		(net 325)
	)
	(via
		(at 254.48 124.16)
		(size 0.45)
		(drill 0.1)
		(layers "F.Cu" "B.Cu")
		(remove_unused_layers yes)
		(keep_end_layers yes)
		(zone_layer_connections)
		(net 325)
	)
	(via
		(at 263.37 123.58)
		(size 0.45)
		(drill 0.1)
		(layers "F.Cu" "B.Cu")
		(remove_unused_layers yes)
		(keep_end_layers yes)
		(zone_layer_connections)
		(net 325)
	)
	(via
		(at 255.94 126.29)
		(size 0.45)
		(drill 0.1)
		(layers "F.Cu" "B.Cu")
		(remove_unused_layers yes)
		(keep_end_layers yes)
		(zone_layer_connections)
		(net 325)
	)
	(via
		(at 254.48 124.87)
		(size 0.45)
		(drill 0.1)
		(layers "F.Cu" "B.Cu")
		(remove_unused_layers yes)
		(keep_end_layers yes)
		(zone_layer_connections)
		(net 325)
	)
	(via
		(at 261.41 126.3)
		(size 0.45)
		(drill 0.1)
		(layers "F.Cu" "B.Cu")
		(remove_unused_layers yes)
		(keep_end_layers yes)
		(zone_layer_connections)
		(net 325)
	)
	(segment
		(start 109.524499 135.449)
		(end 121.2758 135.449)
		(width 0.15)
		(layer "F.Cu")
		(net 330)
	)
	(segment
		(start 106.745 132.669501)
		(end 109.524499 135.449)
		(width 0.15)
		(layer "F.Cu")
		(net 330)
	)
	(segment
		(start 128.037648 141.462149)
		(end 130.197851 141.462149)
		(width 0.15)
		(layer "F.Cu")
		(net 330)
	)
	(segment
		(start 127.124499 140.549)
		(end 128.037648 141.462149)
		(width 0.15)
		(layer "F.Cu")
		(net 330)
	)
	(segment
		(start 130.435 141.485)
		(end 131.247851 141.485)
		(width 0.2)
		(layer "F.Cu")
		(net 330)
	)
	(segment
		(start 121.2758 135.449)
		(end 126.3758 140.549)
		(width 0.15)
		(layer "F.Cu")
		(net 330)
	)
	(segment
		(start 105.195 128.155)
		(end 106.745 129.705)
		(width 0.15)
		(layer "F.Cu")
		(net 330)
	)
	(segment
		(start 105.156999 121.861487)
		(end 105.195 121.899488)
		(width 0.15)
		(layer "F.Cu")
		(net 330)
	)
	(segment
		(start 126.3758 140.549)
		(end 127.124499 140.549)
		(width 0.15)
		(layer "F.Cu")
		(net 330)
	)
	(segment
		(start 106.745 129.705)
		(end 106.745 132.669501)
		(width 0.15)
		(layer "F.Cu")
		(net 330)
	)
	(segment
		(start 130.197851 141.462149)
		(end 130.305 141.355)
		(width 0.15)
		(layer "F.Cu")
		(net 330)
	)
	(segment
		(start 105.195 121.899488)
		(end 105.195 128.155)
		(width 0.15)
		(layer "F.Cu")
		(net 330)
	)
	(segment
		(start 130.305 141.355)
		(end 130.435 141.485)
		(width 0.2)
		(layer "F.Cu")
		(net 330)
	)
	(via
		(at 130.305 141.355)
		(size 0.45)
		(drill 0.1)
		(layers "F.Cu" "B.Cu")
		(remove_unused_layers yes)
		(keep_end_layers yes)
		(zone_layer_connections)
		(net 330)
	)
	(segment
		(start 126.805 140.287149)
		(end 126.805 141.257149)
		(width 0.2)
		(layer "B.Cu")
		(net 330)
	)
	(segment
		(start 130.305 141.355)
		(end 130.212149 141.262149)
		(width 0.2)
		(layer "B.Cu")
		(net 330)
	)
	(segment
		(start 130.212149 141.262149)
		(end 126.81 141.262149)
		(width 0.2)
		(layer "B.Cu")
		(net 330)
	)
	(segment
		(start 127.185499 142.51)
		(end 120.674499 135.999)
		(width 0.15)
		(layer "F.Cu")
		(net 331)
	)
	(segment
		(start 130.16 142.493851)
		(end 130.168851 142.485)
		(width 0.2)
		(layer "F.Cu")
		(net 331)
	)
	(segment
		(start 108.574499 135.999)
		(end 105.177986 132.602487)
		(width 0.15)
		(layer "F.Cu")
		(net 331)
	)
	(segment
		(start 130.143851 142.51)
		(end 127.185499 142.51)
		(width 0.15)
		(layer "F.Cu")
		(net 331)
	)
	(segment
		(start 120.674499 135.999)
		(end 108.574499 135.999)
		(width 0.15)
		(layer "F.Cu")
		(net 331)
	)
	(segment
		(start 105.177986 132.602487)
		(end 105.156999 132.602487)
		(width 0.15)
		(layer "F.Cu")
		(net 331)
	)
	(segment
		(start 130.16 142.493851)
		(end 130.143851 142.51)
		(width 0.15)
		(layer "F.Cu")
		(net 331)
	)
	(segment
		(start 130.168851 142.485)
		(end 131.247851 142.485)
		(width 0.2)
		(layer "F.Cu")
		(net 331)
	)
	(via
		(at 130.16 142.493851)
		(size 0.45)
		(drill 0.1)
		(layers "F.Cu" "B.Cu")
		(remove_unused_layers yes)
		(keep_end_layers yes)
		(zone_layer_connections)
		(net 331)
	)
	(segment
		(start 130.151149 142.485)
		(end 127.087149 142.485)
		(width 0.2)
		(layer "B.Cu")
		(net 331)
	)
	(segment
		(start 127.087149 142.485)
		(end 126.81 142.762149)
		(width 0.2)
		(layer "B.Cu")
		(net 331)
	)
	(segment
		(start 130.16 142.493851)
		(end 130.151149 142.485)
		(width 0.2)
		(layer "B.Cu")
		(net 331)
	)
	(segment
		(start 126.81 142.762149)
		(end 126.81 143.722149)
		(width 0.2)
		(layer "B.Cu")
		(net 331)
	)
	(segment
		(start 188.31 170.70759)
		(end 188.31 166.1)
		(width 0.22)
		(layer "F.Cu")
		(net 332)
	)
	(segment
		(start 160.96 196.99)
		(end 160.96 193.37134)
		(width 0.22)
		(layer "F.Cu")
		(net 332)
	)
	(segment
		(start 179.324978 183.00632)
		(end 185.966854 176.364444)
		(width 0.22)
		(layer "F.Cu")
		(net 332)
	)
	(segment
		(start 160.65 197.3)
		(end 160.96 196.99)
		(width 0.22)
		(layer "F.Cu")
		(net 332)
	)
	(segment
		(start 161.949979 190.981319)
		(end 168.056319 184.874979)
		(width 0.22)
		(layer "F.Cu")
		(net 332)
	)
	(segment
		(start 170.44634 183.885)
		(end 177.203657 183.885)
		(width 0.22)
		(layer "F.Cu")
		(net 332)
	)
	(segment
		(start 188.599999 164.458579)
		(end 188.458578 164.6)
		(width 0.1)
		(layer "F.Cu")
		(net 332)
	)
	(segment
		(start 188.37071 166.03929)
		(end 188.31 166.1)
		(width 0.1)
		(layer "F.Cu")
		(net 332)
	)
	(segment
		(start 160.65 199.25)
		(end 160.65 197.3)
		(width 0.22)
		(layer "F.Cu")
		(net 332)
	)
	(segment
		(start 188.858579 164.4)
		(end 188.741421 164.4)
		(width 0.1)
		(layer "F.Cu")
		(net 332)
	)
	(segment
		(start 189 164)
		(end 189 164.258579)
		(width 0.1)
		(layer "F.Cu")
		(net 332)
	)
	(segment
		(start 188.4 164.741421)
		(end 188.4 165.968579)
		(width 0.1)
		(layer "F.Cu")
		(net 332)
	)
	(segment
		(start 188.97071 164.32929)
		(end 188.929289 164.370711)
		(width 0.1)
		(layer "F.Cu")
		(net 332)
	)
	(arc
		(start 177.203657 183.885)
		(mid 178.351708 183.656639)
		(end 179.324978 183.00632)
		(width 0.22)
		(layer "F.Cu")
		(net 332)
	)
	(arc
		(start 168.056319 184.874979)
		(mid 169.15287 184.142287)
		(end 170.44634 183.885)
		(width 0.22)
		(layer "F.Cu")
		(net 332)
	)
	(arc
		(start 189 164.258579)
		(mid 188.992388 164.296848)
		(end 188.97071 164.32929)
		(width 0.1)
		(layer "F.Cu")
		(net 332)
	)
	(arc
		(start 188.741421 164.4)
		(mid 188.664884 164.415224)
		(end 188.599999 164.458579)
		(width 0.1)
		(layer "F.Cu")
		(net 332)
	)
	(arc
		(start 188.929289 164.370711)
		(mid 188.896847 164.392388)
		(end 188.858579 164.4)
		(width 0.1)
		(layer "F.Cu")
		(net 332)
	)
	(arc
		(start 185.966854 176.364444)
		(mid 187.701033 173.769057)
		(end 188.31 170.70759)
		(width 0.22)
		(layer "F.Cu")
		(net 332)
	)
	(arc
		(start 160.96 193.37134)
		(mid 161.217287 192.07787)
		(end 161.949979 190.981319)
		(width 0.22)
		(layer "F.Cu")
		(net 332)
	)
	(arc
		(start 188.458578 164.6)
		(mid 188.415224 164.664885)
		(end 188.4 164.741421)
		(width 0.1)
		(layer "F.Cu")
		(net 332)
	)
	(arc
		(start 188.37071 166.03929)
		(mid 188.392388 166.006848)
		(end 188.4 165.968579)
		(width 0.1)
		(layer "F.Cu")
		(net 332)
	)
	(segment
		(start 188.6 165.075)
		(end 188.6 164.782843)
		(width 0.1)
		(layer "F.Cu")
		(net 333)
	)
	(segment
		(start 179.593681 183.275021)
		(end 186.235555 176.633147)
		(width 0.22)
		(layer "F.Cu")
		(net 333)
	)
	(segment
		(start 161.34 196.99)
		(end 161.34 193.371343)
		(width 0.22)
		(layer "F.Cu")
		(net 333)
	)
	(segment
		(start 188.782843 164.6)
		(end 188.858579 164.6)
		(width 0.1)
		(layer "F.Cu")
		(net 333)
	)
	(segment
		(start 188.742674 165.5)
		(end 188.725 165.5)
		(width 0.1)
		(layer "F.Cu")
		(net 333)
	)
	(segment
		(start 188.6 165.375)
		(end 188.6 165.075)
		(width 0.1)
		(layer "F.Cu")
		(net 333)
	)
	(segment
		(start 188.69 166.1)
		(end 188.62929 166.03929)
		(width 0.1)
		(layer "F.Cu")
		(net 333)
	)
	(segment
		(start 188.69 170.707592)
		(end 188.69 166.1)
		(width 0.22)
		(layer "F.Cu")
		(net 333)
	)
	(segment
		(start 189 164.741421)
		(end 189 165)
		(width 0.1)
		(layer "F.Cu")
		(net 333)
	)
	(segment
		(start 188.725 165.75)
		(end 188.742674 165.75)
		(width 0.1)
		(layer "F.Cu")
		(net 333)
	)
	(segment
		(start 162.21868 191.250022)
		(end 168.325023 185.143679)
		(width 0.22)
		(layer "F.Cu")
		(net 333)
	)
	(segment
		(start 161.65 197.3)
		(end 161.34 196.99)
		(width 0.22)
		(layer "F.Cu")
		(net 333)
	)
	(segment
		(start 161.65 199.25)
		(end 161.65 197.3)
		(width 0.22)
		(layer "F.Cu")
		(net 333)
	)
	(segment
		(start 170.446343 184.265)
		(end 177.20366 184.265)
		(width 0.22)
		(layer "F.Cu")
		(net 333)
	)
	(segment
		(start 188.929289 164.629289)
		(end 188.97071 164.67071)
		(width 0.1)
		(layer "F.Cu")
		(net 333)
	)
	(segment
		(start 188.6 165.968579)
		(end 188.6 165.875)
		(width 0.1)
		(layer "F.Cu")
		(net 333)
	)
	(segment
		(start 188.629289 164.712133)
		(end 188.712132 164.62929)
		(width 0.1)
		(layer "F.Cu")
		(net 333)
	)
	(arc
		(start 188.6 164.782843)
		(mid 188.607612 164.744575)
		(end 188.629289 164.712133)
		(width 0.1)
		(layer "F.Cu")
		(net 333)
	)
	(arc
		(start 188.6 165.875)
		(mid 188.636612 165.786612)
		(end 188.725 165.75)
		(width 0.1)
		(layer "F.Cu")
		(net 333)
	)
	(arc
		(start 186.235555 176.633147)
		(mid 188.052108 173.914479)
		(end 188.69 170.707592)
		(width 0.22)
		(layer "F.Cu")
		(net 333)
	)
	(arc
		(start 177.20366 184.265)
		(mid 178.49713 184.007713)
		(end 179.593681 183.275021)
		(width 0.22)
		(layer "F.Cu")
		(net 333)
	)
	(arc
		(start 188.62929 166.03929)
		(mid 188.607612 166.006848)
		(end 188.6 165.968579)
		(width 0.1)
		(layer "F.Cu")
		(net 333)
	)
	(arc
		(start 188.712132 164.62929)
		(mid 188.744574 164.607612)
		(end 188.782843 164.6)
		(width 0.1)
		(layer "F.Cu")
		(net 333)
	)
	(arc
		(start 161.34 193.371343)
		(mid 161.568361 192.223292)
		(end 162.21868 191.250022)
		(width 0.22)
		(layer "F.Cu")
		(net 333)
	)
	(arc
		(start 188.97071 164.67071)
		(mid 188.992388 164.703152)
		(end 189 164.741421)
		(width 0.1)
		(layer "F.Cu")
		(net 333)
	)
	(arc
		(start 168.325023 185.143679)
		(mid 169.298293 184.493361)
		(end 170.446343 184.265)
		(width 0.22)
		(layer "F.Cu")
		(net 333)
	)
	(arc
		(start 188.742674 165.75)
		(mid 188.831062 165.713388)
		(end 188.867674 165.625)
		(width 0.1)
		(layer "F.Cu")
		(net 333)
	)
	(arc
		(start 188.725 165.5)
		(mid 188.636612 165.463388)
		(end 188.6 165.375)
		(width 0.1)
		(layer "F.Cu")
		(net 333)
	)
	(arc
		(start 188.858579 164.6)
		(mid 188.896847 164.607612)
		(end 188.929289 164.629289)
		(width 0.1)
		(layer "F.Cu")
		(net 333)
	)
	(arc
		(start 188.867674 165.625)
		(mid 188.831062 165.536612)
		(end 188.742674 165.5)
		(width 0.1)
		(layer "F.Cu")
		(net 333)
	)
	(segment
		(start 190.37071 166.03929)
		(end 190.31 166.1)
		(width 0.1)
		(layer "F.Cu")
		(net 334)
	)
	(segment
		(start 166.949979 190.181319)
		(end 169.831319 187.299979)
		(width 0.22)
		(layer "F.Cu")
		(net 334)
	)
	(segment
		(start 179.499978 185.43132)
		(end 187.966854 176.964444)
		(width 0.22)
		(layer "F.Cu")
		(net 334)
	)
	(segment
		(start 190.97071 164.32929)
		(end 190.929289 164.370711)
		(width 0.1)
		(layer "F.Cu")
		(net 334)
	)
	(segment
		(start 191 164)
		(end 191 164.258579)
		(width 0.1)
		(layer "F.Cu")
		(net 334)
	)
	(segment
		(start 172.22134 186.31)
		(end 177.378657 186.31)
		(width 0.22)
		(layer "F.Cu")
		(net 334)
	)
	(segment
		(start 165.65 197.3)
		(end 165.96 196.99)
		(width 0.22)
		(layer "F.Cu")
		(net 334)
	)
	(segment
		(start 190.4 164.741421)
		(end 190.4 165.968579)
		(width 0.1)
		(layer "F.Cu")
		(net 334)
	)
	(segment
		(start 165.65 199.25)
		(end 165.65 197.3)
		(width 0.22)
		(layer "F.Cu")
		(net 334)
	)
	(segment
		(start 190.858579 164.4)
		(end 190.741421 164.4)
		(width 0.1)
		(layer "F.Cu")
		(net 334)
	)
	(segment
		(start 190.599999 164.458579)
		(end 190.458578 164.6)
		(width 0.1)
		(layer "F.Cu")
		(net 334)
	)
	(segment
		(start 190.31 171.30759)
		(end 190.31 166.1)
		(width 0.22)
		(layer "F.Cu")
		(net 334)
	)
	(segment
		(start 165.96 196.99)
		(end 165.96 192.57134)
		(width 0.22)
		(layer "F.Cu")
		(net 334)
	)
	(arc
		(start 190.37071 166.03929)
		(mid 190.392388 166.006848)
		(end 190.4 165.968579)
		(width 0.1)
		(layer "F.Cu")
		(net 334)
	)
	(arc
		(start 190.741421 164.4)
		(mid 190.664884 164.415224)
		(end 190.599999 164.458579)
		(width 0.1)
		(layer "F.Cu")
		(net 334)
	)
	(arc
		(start 165.96 192.57134)
		(mid 166.217287 191.27787)
		(end 166.949979 190.181319)
		(width 0.22)
		(layer "F.Cu")
		(net 334)
	)
	(arc
		(start 191 164.258579)
		(mid 190.992388 164.296848)
		(end 190.97071 164.32929)
		(width 0.1)
		(layer "F.Cu")
		(net 334)
	)
	(arc
		(start 177.378657 186.31)
		(mid 178.526708 186.081638)
		(end 179.499978 185.43132)
		(width 0.22)
		(layer "F.Cu")
		(net 334)
	)
	(arc
		(start 187.966854 176.964444)
		(mid 189.701033 174.369057)
		(end 190.31 171.30759)
		(width 0.22)
		(layer "F.Cu")
		(net 334)
	)
	(arc
		(start 190.458578 164.6)
		(mid 190.415224 164.664885)
		(end 190.4 164.741421)
		(width 0.1)
		(layer "F.Cu")
		(net 334)
	)
	(arc
		(start 169.831319 187.299979)
		(mid 170.92787 186.567287)
		(end 172.22134 186.31)
		(width 0.22)
		(layer "F.Cu")
		(net 334)
	)
	(arc
		(start 190.929289 164.370711)
		(mid 190.896847 164.392388)
		(end 190.858579 164.4)
		(width 0.1)
		(layer "F.Cu")
		(net 334)
	)
	(segment
		(start 190.712132 164.62929)
		(end 190.629289 164.712133)
		(width 0.1)
		(layer "F.Cu")
		(net 335)
	)
	(segment
		(start 191 165)
		(end 191 164.741421)
		(width 0.1)
		(layer "F.Cu")
		(net 335)
	)
	(segment
		(start 166.34 196.99)
		(end 166.34 192.571343)
		(width 0.22)
		(layer "F.Cu")
		(net 335)
	)
	(segment
		(start 167.21868 190.450022)
		(end 170.100023 187.568679)
		(width 0.22)
		(layer "F.Cu")
		(net 335)
	)
	(segment
		(start 172.221343 186.69)
		(end 177.37866 186.69)
		(width 0.22)
		(layer "F.Cu")
		(net 335)
	)
	(segment
		(start 190.734179 165.75)
		(end 190.725 165.75)
		(width 0.1)
		(layer "F.Cu")
		(net 335)
	)
	(segment
		(start 166.65 199.25)
		(end 166.65 197.3)
		(width 0.22)
		(layer "F.Cu")
		(net 335)
	)
	(segment
		(start 190.858579 164.6)
		(end 190.782843 164.6)
		(width 0.1)
		(layer "F.Cu")
		(net 335)
	)
	(segment
		(start 190.97071 164.67071)
		(end 190.929289 164.629289)
		(width 0.1)
		(layer "F.Cu")
		(net 335)
	)
	(segment
		(start 190.6 165.954724)
		(end 190.6 165.968579)
		(width 0.1)
		(layer "F.Cu")
		(net 335)
	)
	(segment
		(start 190.6 164.782843)
		(end 190.6 165.375)
		(width 0.1)
		(layer "F.Cu")
		(net 335)
	)
	(segment
		(start 190.62929 166.03929)
		(end 190.69 166.1)
		(width 0.1)
		(layer "F.Cu")
		(net 335)
	)
	(segment
		(start 190.6 165.875)
		(end 190.6 165.954724)
		(width 0.1)
		(layer "F.Cu")
		(net 335)
	)
	(segment
		(start 190.725 165.5)
		(end 190.734179 165.5)
		(width 0.1)
		(layer "F.Cu")
		(net 335)
	)
	(segment
		(start 166.65 197.3)
		(end 166.34 196.99)
		(width 0.22)
		(layer "F.Cu")
		(net 335)
	)
	(segment
		(start 190.69 171.307592)
		(end 190.69 166.1)
		(width 0.22)
		(layer "F.Cu")
		(net 335)
	)
	(segment
		(start 179.768681 185.700021)
		(end 188.235555 177.233147)
		(width 0.22)
		(layer "F.Cu")
		(net 335)
	)
	(arc
		(start 166.34 192.571343)
		(mid 166.568361 191.423292)
		(end 167.21868 190.450022)
		(width 0.22)
		(layer "F.Cu")
		(net 335)
	)
	(arc
		(start 190.725 165.75)
		(mid 190.636612 165.786612)
		(end 190.6 165.875)
		(width 0.1)
		(layer "F.Cu")
		(net 335)
	)
	(arc
		(start 191 164.741421)
		(mid 190.992388 164.703152)
		(end 190.97071 164.67071)
		(width 0.1)
		(layer "F.Cu")
		(net 335)
	)
	(arc
		(start 177.37866 186.69)
		(mid 178.67213 186.432713)
		(end 179.768681 185.700021)
		(width 0.22)
		(layer "F.Cu")
		(net 335)
	)
	(arc
		(start 190.6 165.968579)
		(mid 190.607612 166.006848)
		(end 190.62929 166.03929)
		(width 0.1)
		(layer "F.Cu")
		(net 335)
	)
	(arc
		(start 190.629289 164.712133)
		(mid 190.607612 164.744575)
		(end 190.6 164.782843)
		(width 0.1)
		(layer "F.Cu")
		(net 335)
	)
	(arc
		(start 170.100023 187.568679)
		(mid 171.073293 186.918361)
		(end 172.221343 186.69)
		(width 0.22)
		(layer "F.Cu")
		(net 335)
	)
	(arc
		(start 190.782843 164.6)
		(mid 190.744574 164.607612)
		(end 190.712132 164.62929)
		(width 0.1)
		(layer "F.Cu")
		(net 335)
	)
	(arc
		(start 190.734179 165.5)
		(mid 190.822567 165.536612)
		(end 190.859179 165.625)
		(width 0.1)
		(layer "F.Cu")
		(net 335)
	)
	(arc
		(start 188.235555 177.233147)
		(mid 190.052108 174.514479)
		(end 190.69 171.307592)
		(width 0.22)
		(layer "F.Cu")
		(net 335)
	)
	(arc
		(start 190.859179 165.625)
		(mid 190.822567 165.713388)
		(end 190.734179 165.75)
		(width 0.1)
		(layer "F.Cu")
		(net 335)
	)
	(arc
		(start 190.6 165.375)
		(mid 190.636612 165.463388)
		(end 190.725 165.5)
		(width 0.1)
		(layer "F.Cu")
		(net 335)
	)
	(arc
		(start 190.929289 164.629289)
		(mid 190.896847 164.607612)
		(end 190.858579 164.6)
		(width 0.1)
		(layer "F.Cu")
		(net 335)
	)
	(segment
		(start 193 164)
		(end 193 164.258579)
		(width 0.1)
		(layer "F.Cu")
		(net 336)
	)
	(segment
		(start 192.97071 164.32929)
		(end 192.929289 164.370711)
		(width 0.1)
		(layer "F.Cu")
		(net 336)
	)
	(segment
		(start 170.949979 191.281319)
		(end 172.231319 189.999979)
		(width 0.22)
		(layer "F.Cu")
		(net 336)
	)
	(segment
		(start 174.62134 189.01)
		(end 177.578657 189.01)
		(width 0.22)
		(layer "F.Cu")
		(net 336)
	)
	(segment
		(start 192.37071 166.03929)
		(end 192.31 166.1)
		(width 0.1)
		(layer "F.Cu")
		(net 336)
	)
	(segment
		(start 169.65 199.25)
		(end 169.65 197.3)
		(width 0.22)
		(layer "F.Cu")
		(net 336)
	)
	(segment
		(start 192.599999 164.458579)
		(end 192.458578 164.6)
		(width 0.1)
		(layer "F.Cu")
		(net 336)
	)
	(segment
		(start 169.65 197.3)
		(end 169.96 196.99)
		(width 0.22)
		(layer "F.Cu")
		(net 336)
	)
	(segment
		(start 192.858579 164.4)
		(end 192.741421 164.4)
		(width 0.1)
		(layer "F.Cu")
		(net 336)
	)
	(segment
		(start 169.96 196.99)
		(end 169.96 193.67134)
		(width 0.22)
		(layer "F.Cu")
		(net 336)
	)
	(segment
		(start 179.699978 188.13132)
		(end 189.966854 177.864444)
		(width 0.22)
		(layer "F.Cu")
		(net 336)
	)
	(segment
		(start 192.4 164.741421)
		(end 192.4 165.968579)
		(width 0.1)
		(layer "F.Cu")
		(net 336)
	)
	(segment
		(start 192.31 172.20759)
		(end 192.31 166.1)
		(width 0.22)
		(layer "F.Cu")
		(net 336)
	)
	(arc
		(start 193 164.258579)
		(mid 192.992388 164.296848)
		(end 192.97071 164.32929)
		(width 0.1)
		(layer "F.Cu")
		(net 336)
	)
	(arc
		(start 192.929289 164.370711)
		(mid 192.896847 164.392388)
		(end 192.858579 164.4)
		(width 0.1)
		(layer "F.Cu")
		(net 336)
	)
	(arc
		(start 189.966854 177.864444)
		(mid 191.701033 175.269057)
		(end 192.31 172.20759)
		(width 0.22)
		(layer "F.Cu")
		(net 336)
	)
	(arc
		(start 192.458578 164.6)
		(mid 192.415224 164.664885)
		(end 192.4 164.741421)
		(width 0.1)
		(layer "F.Cu")
		(net 336)
	)
	(arc
		(start 172.231319 189.999979)
		(mid 173.32787 189.267287)
		(end 174.62134 189.01)
		(width 0.22)
		(layer "F.Cu")
		(net 336)
	)
	(arc
		(start 192.741421 164.4)
		(mid 192.664884 164.415224)
		(end 192.599999 164.458579)
		(width 0.1)
		(layer "F.Cu")
		(net 336)
	)
	(arc
		(start 177.578657 189.01)
		(mid 178.726708 188.781638)
		(end 179.699978 188.13132)
		(width 0.22)
		(layer "F.Cu")
		(net 336)
	)
	(arc
		(start 169.96 193.67134)
		(mid 170.217287 192.37787)
		(end 170.949979 191.281319)
		(width 0.22)
		(layer "F.Cu")
		(net 336)
	)
	(arc
		(start 192.37071 166.03929)
		(mid 192.392388 166.006848)
		(end 192.4 165.968579)
		(width 0.1)
		(layer "F.Cu")
		(net 336)
	)
	(segment
		(start 170.65 197.3)
		(end 170.34 196.99)
		(width 0.22)
		(layer "F.Cu")
		(net 337)
	)
	(segment
		(start 192.6 165.35)
		(end 192.6 165.225565)
		(width 0.1)
		(layer "F.Cu")
		(net 337)
	)
	(segment
		(start 192.69 166.1)
		(end 192.62929 166.03929)
		(width 0.1)
		(layer "F.Cu")
		(net 337)
	)
	(segment
		(start 192.6 165.225565)
		(end 192.6 164.782843)
		(width 0.1)
		(layer "F.Cu")
		(net 337)
	)
	(segment
		(start 192.782843 164.6)
		(end 192.858579 164.6)
		(width 0.1)
		(layer "F.Cu")
		(net 337)
	)
	(segment
		(start 192.725 165.725)
		(end 192.738671 165.725)
		(width 0.1)
		(layer "F.Cu")
		(net 337)
	)
	(segment
		(start 192.738671 165.475)
		(end 192.725 165.475)
		(width 0.1)
		(layer "F.Cu")
		(net 337)
	)
	(segment
		(start 192.69 172.207592)
		(end 192.69 166.1)
		(width 0.22)
		(layer "F.Cu")
		(net 337)
	)
	(segment
		(start 192.929289 164.629289)
		(end 192.97071 164.67071)
		(width 0.1)
		(layer "F.Cu")
		(net 337)
	)
	(segment
		(start 179.968681 188.400021)
		(end 190.235555 178.133147)
		(width 0.22)
		(layer "F.Cu")
		(net 337)
	)
	(segment
		(start 170.65 199.25)
		(end 170.65 197.3)
		(width 0.22)
		(layer "F.Cu")
		(net 337)
	)
	(segment
		(start 193 164.741421)
		(end 193 165)
		(width 0.1)
		(layer "F.Cu")
		(net 337)
	)
	(segment
		(start 192.6 165.968579)
		(end 192.6 165.85)
		(width 0.1)
		(layer "F.Cu")
		(net 337)
	)
	(segment
		(start 171.21868 191.550022)
		(end 172.500023 190.268679)
		(width 0.22)
		(layer "F.Cu")
		(net 337)
	)
	(segment
		(start 174.621343 189.39)
		(end 177.57866 189.39)
		(width 0.22)
		(layer "F.Cu")
		(net 337)
	)
	(segment
		(start 192.629289 164.712133)
		(end 192.712132 164.62929)
		(width 0.1)
		(layer "F.Cu")
		(net 337)
	)
	(segment
		(start 170.34 196.99)
		(end 170.34 193.671343)
		(width 0.22)
		(layer "F.Cu")
		(net 337)
	)
	(arc
		(start 192.738671 165.725)
		(mid 192.827059 165.688388)
		(end 192.863671 165.6)
		(width 0.1)
		(layer "F.Cu")
		(net 337)
	)
	(arc
		(start 192.6 164.782843)
		(mid 192.607612 164.744575)
		(end 192.629289 164.712133)
		(width 0.1)
		(layer "F.Cu")
		(net 337)
	)
	(arc
		(start 192.863671 165.6)
		(mid 192.827059 165.511612)
		(end 192.738671 165.475)
		(width 0.1)
		(layer "F.Cu")
		(net 337)
	)
	(arc
		(start 192.725 165.475)
		(mid 192.636612 165.438388)
		(end 192.6 165.35)
		(width 0.1)
		(layer "F.Cu")
		(net 337)
	)
	(arc
		(start 192.712132 164.62929)
		(mid 192.744574 164.607612)
		(end 192.782843 164.6)
		(width 0.1)
		(layer "F.Cu")
		(net 337)
	)
	(arc
		(start 192.858579 164.6)
		(mid 192.896847 164.607612)
		(end 192.929289 164.629289)
		(width 0.1)
		(layer "F.Cu")
		(net 337)
	)
	(arc
		(start 190.235555 178.133147)
		(mid 192.052108 175.414479)
		(end 192.69 172.207592)
		(width 0.22)
		(layer "F.Cu")
		(net 337)
	)
	(arc
		(start 192.6 165.85)
		(mid 192.636612 165.761612)
		(end 192.725 165.725)
		(width 0.1)
		(layer "F.Cu")
		(net 337)
	)
	(arc
		(start 177.57866 189.39)
		(mid 178.87213 189.132713)
		(end 179.968681 188.400021)
		(width 0.22)
		(layer "F.Cu")
		(net 337)
	)
	(arc
		(start 192.97071 164.67071)
		(mid 192.992388 164.703152)
		(end 193 164.741421)
		(width 0.1)
		(layer "F.Cu")
		(net 337)
	)
	(arc
		(start 172.500023 190.268679)
		(mid 173.473293 189.618361)
		(end 174.621343 189.39)
		(width 0.22)
		(layer "F.Cu")
		(net 337)
	)
	(arc
		(start 192.62929 166.03929)
		(mid 192.607612 166.006848)
		(end 192.6 165.968579)
		(width 0.1)
		(layer "F.Cu")
		(net 337)
	)
	(arc
		(start 170.34 193.671343)
		(mid 170.568361 192.523292)
		(end 171.21868 191.550022)
		(width 0.22)
		(layer "F.Cu")
		(net 337)
	)
	(segment
		(start 173.96 196.99)
		(end 173.96 195.17134)
		(width 0.22)
		(layer "F.Cu")
		(net 338)
	)
	(segment
		(start 195 164)
		(end 195 164.258579)
		(width 0.1)
		(layer "F.Cu")
		(net 338)
	)
	(segment
		(start 194.37071 166.03929)
		(end 194.31 166.1)
		(width 0.1)
		(layer "F.Cu")
		(net 338)
	)
	(segment
		(start 194.858579 164.4)
		(end 194.741421 164.4)
		(width 0.1)
		(layer "F.Cu")
		(net 338)
	)
	(segment
		(start 194.31 173.10759)
		(end 194.31 166.1)
		(width 0.22)
		(layer "F.Cu")
		(net 338)
	)
	(segment
		(start 194.599999 164.458579)
		(end 194.458578 164.6)
		(width 0.1)
		(layer "F.Cu")
		(net 338)
	)
	(segment
		(start 194.97071 164.32929)
		(end 194.929289 164.370711)
		(width 0.1)
		(layer "F.Cu")
		(net 338)
	)
	(segment
		(start 180.299978 190.43132)
		(end 191.966854 178.764444)
		(width 0.22)
		(layer "F.Cu")
		(net 338)
	)
	(segment
		(start 194.4 164.741421)
		(end 194.4 165.968579)
		(width 0.1)
		(layer "F.Cu")
		(net 338)
	)
	(segment
		(start 177.82134 191.31)
		(end 178.178657 191.31)
		(width 0.22)
		(layer "F.Cu")
		(net 338)
	)
	(segment
		(start 173.65 199.25)
		(end 173.65 197.3)
		(width 0.22)
		(layer "F.Cu")
		(net 338)
	)
	(segment
		(start 174.949979 192.781319)
		(end 175.431319 192.299979)
		(width 0.22)
		(layer "F.Cu")
		(net 338)
	)
	(segment
		(start 173.65 197.3)
		(end 173.96 196.99)
		(width 0.22)
		(layer "F.Cu")
		(net 338)
	)
	(arc
		(start 191.966854 178.764444)
		(mid 193.701036 176.169057)
		(end 194.31 173.10759)
		(width 0.22)
		(layer "F.Cu")
		(net 338)
	)
	(arc
		(start 194.929289 164.370711)
		(mid 194.896847 164.392388)
		(end 194.858579 164.4)
		(width 0.1)
		(layer "F.Cu")
		(net 338)
	)
	(arc
		(start 194.741421 164.4)
		(mid 194.664884 164.415224)
		(end 194.599999 164.458579)
		(width 0.1)
		(layer "F.Cu")
		(net 338)
	)
	(arc
		(start 194.458578 164.6)
		(mid 194.415224 164.664885)
		(end 194.4 164.741421)
		(width 0.1)
		(layer "F.Cu")
		(net 338)
	)
	(arc
		(start 174.949979 192.781319)
		(mid 174.217287 193.87787)
		(end 173.96 195.17134)
		(width 0.22)
		(layer "F.Cu")
		(net 338)
	)
	(arc
		(start 195 164.258579)
		(mid 194.992388 164.296848)
		(end 194.97071 164.32929)
		(width 0.1)
		(layer "F.Cu")
		(net 338)
	)
	(arc
		(start 178.178657 191.31)
		(mid 179.326708 191.081638)
		(end 180.299978 190.43132)
		(width 0.22)
		(layer "F.Cu")
		(net 338)
	)
	(arc
		(start 177.82134 191.31)
		(mid 176.52787 191.567287)
		(end 175.431319 192.299979)
		(width 0.22)
		(layer "F.Cu")
		(net 338)
	)
	(arc
		(start 194.37071 166.03929)
		(mid 194.392388 166.006848)
		(end 194.4 165.968579)
		(width 0.1)
		(layer "F.Cu")
		(net 338)
	)
	(segment
		(start 178.17866 191.69)
		(end 177.821343 191.69)
		(width 0.22)
		(layer "F.Cu")
		(net 339)
	)
	(segment
		(start 174.65 197.3)
		(end 174.65 199.25)
		(width 0.22)
		(layer "F.Cu")
		(net 339)
	)
	(segment
		(start 174.34 196.99)
		(end 174.65 197.3)
		(width 0.22)
		(layer "F.Cu")
		(net 339)
	)
	(segment
		(start 194.725 165.525)
		(end 194.739183 165.525)
		(width 0.1)
		(layer "F.Cu")
		(net 339)
	)
	(segment
		(start 194.712132 164.62929)
		(end 194.629289 164.712133)
		(width 0.1)
		(layer "F.Cu")
		(net 339)
	)
	(segment
		(start 195 165)
		(end 195 164.741421)
		(width 0.1)
		(layer "F.Cu")
		(net 339)
	)
	(segment
		(start 194.97071 164.67071)
		(end 194.929289 164.629289)
		(width 0.1)
		(layer "F.Cu")
		(net 339)
	)
	(segment
		(start 192.235555 179.033147)
		(end 180.568681 190.700021)
		(width 0.22)
		(layer "F.Cu")
		(net 339)
	)
	(segment
		(start 194.858579 164.6)
		(end 194.782843 164.6)
		(width 0.1)
		(layer "F.Cu")
		(net 339)
	)
	(segment
		(start 174.34 195.171343)
		(end 174.34 196.99)
		(width 0.22)
		(layer "F.Cu")
		(net 339)
	)
	(segment
		(start 194.6 164.782843)
		(end 194.6 165.4)
		(width 0.1)
		(layer "F.Cu")
		(net 339)
	)
	(segment
		(start 194.62929 166.03929)
		(end 194.69 166.1)
		(width 0.1)
		(layer "F.Cu")
		(net 339)
	)
	(segment
		(start 194.69 166.1)
		(end 194.69 173.107592)
		(width 0.22)
		(layer "F.Cu")
		(net 339)
	)
	(segment
		(start 194.6 165.9)
		(end 194.6 165.968579)
		(width 0.1)
		(layer "F.Cu")
		(net 339)
	)
	(segment
		(start 194.739183 165.775)
		(end 194.725 165.775)
		(width 0.1)
		(layer "F.Cu")
		(net 339)
	)
	(segment
		(start 175.700022 192.56868)
		(end 175.218679 193.050023)
		(width 0.22)
		(layer "F.Cu")
		(net 339)
	)
	(arc
		(start 174.34 195.171343)
		(mid 174.568361 194.023293)
		(end 175.218679 193.050023)
		(width 0.22)
		(layer "F.Cu")
		(net 339)
	)
	(arc
		(start 194.629289 164.712133)
		(mid 194.607612 164.744575)
		(end 194.6 164.782843)
		(width 0.1)
		(layer "F.Cu")
		(net 339)
	)
	(arc
		(start 194.864183 165.65)
		(mid 194.827571 165.738388)
		(end 194.739183 165.775)
		(width 0.1)
		(layer "F.Cu")
		(net 339)
	)
	(arc
		(start 194.6 165.4)
		(mid 194.636612 165.488388)
		(end 194.725 165.525)
		(width 0.1)
		(layer "F.Cu")
		(net 339)
	)
	(arc
		(start 194.69 173.107592)
		(mid 194.052111 176.314479)
		(end 192.235555 179.033147)
		(width 0.22)
		(layer "F.Cu")
		(net 339)
	)
	(arc
		(start 175.700022 192.56868)
		(mid 176.673292 191.918361)
		(end 177.821343 191.69)
		(width 0.22)
		(layer "F.Cu")
		(net 339)
	)
	(arc
		(start 194.6 165.968579)
		(mid 194.607612 166.006848)
		(end 194.62929 166.03929)
		(width 0.1)
		(layer "F.Cu")
		(net 339)
	)
	(arc
		(start 178.17866 191.69)
		(mid 179.47213 191.432713)
		(end 180.568681 190.700021)
		(width 0.22)
		(layer "F.Cu")
		(net 339)
	)
	(arc
		(start 194.739183 165.525)
		(mid 194.827571 165.561612)
		(end 194.864183 165.65)
		(width 0.1)
		(layer "F.Cu")
		(net 339)
	)
	(arc
		(start 194.782843 164.6)
		(mid 194.744574 164.607612)
		(end 194.712132 164.62929)
		(width 0.1)
		(layer "F.Cu")
		(net 339)
	)
	(arc
		(start 195 164.741421)
		(mid 194.992388 164.703152)
		(end 194.97071 164.67071)
		(width 0.1)
		(layer "F.Cu")
		(net 339)
	)
	(arc
		(start 194.929289 164.629289)
		(mid 194.896847 164.607612)
		(end 194.858579 164.6)
		(width 0.1)
		(layer "F.Cu")
		(net 339)
	)
	(arc
		(start 194.725 165.775)
		(mid 194.636612 165.811612)
		(end 194.6 165.9)
		(width 0.1)
		(layer "F.Cu")
		(net 339)
	)
	(segment
		(start 117.45 115.594921)
		(end 117.088 115.232921)
		(width 0.15)
		(layer "F.Cu")
		(net 340)
	)
	(segment
		(start 197.0005 155.0005)
		(end 197.5 155.5)
		(width 0.256)
		(layer "F.Cu")
		(net 340)
	)
	(segment
		(start 117.45 116.4)
		(end 117.45 115.594921)
		(width 0.15)
		(layer "F.Cu")
		(net 340)
	)
	(segment
		(start 117.45 117.15)
		(end 117.45 116.151)
		(width 0.15)
		(layer "F.Cu")
		(net 340)
	)
	(segment
		(start 117.088 115.232921)
		(end 117.088 113.407921)
		(width 0.15)
		(layer "F.Cu")
		(net 340)
	)
	(via
		(at 174.55 156.45)
		(size 0.45)
		(drill 0.1)
		(layers "F.Cu" "B.Cu")
		(remove_unused_layers yes)
		(keep_end_layers yes)
		(zone_layer_connections)
		(net 340)
	)
	(via
		(at 117.45 117.15)
		(size 0.45)
		(drill 0.1)
		(layers "F.Cu" "B.Cu")
		(remove_unused_layers yes)
		(keep_end_layers yes)
		(zone_layer_connections)
		(net 340)
	)
	(via
		(at 197.5 155.5)
		(size 0.45)
		(drill 0.1)
		(layers "F.Cu" "B.Cu")
		(remove_unused_layers yes)
		(keep_end_layers yes)
		(zone_layer_connections)
		(net 340)
	)
	(segment
		(start 188.9 148.875)
		(end 187.85 149.925)
		(width 0.1)
		(layer "In2.Cu")
		(net 340)
	)
	(segment
		(start 192.125 150.707842)
		(end 192.125 149.311826)
		(width 0.1)
		(layer "In2.Cu")
		(net 340)
	)
	(segment
		(start 173.95 155.85)
		(end 174.55 156.45)
		(width 0.1)
		(layer "In2.Cu")
		(net 340)
	)
	(segment
		(start 191.688174 148.875)
		(end 188.9 148.875)
		(width 0.1)
		(layer "In2.Cu")
		(net 340)
	)
	(segment
		(start 193.515165 153.875)
		(end 191.2 153.875)
		(width 0.1)
		(layer "In2.Cu")
		(net 340)
	)
	(segment
		(start 194.125 154.825)
		(end 194.125 154.484835)
		(width 0.1)
		(layer "In2.Cu")
		(net 340)
	)
	(segment
		(start 182.7 152)
		(end 178.1 152)
		(width 0.1)
		(layer "In2.Cu")
		(net 340)
	)
	(segment
		(start 182.95 151.75)
		(end 182.7 152)
		(width 0.1)
		(layer "In2.Cu")
		(net 340)
	)
	(segment
		(start 174.1 155)
		(end 173.95 155.15)
		(width 0.1)
		(layer "In2.Cu")
		(net 340)
	)
	(segment
		(start 176 154.65)
		(end 175.65 155)
		(width 0.1)
		(layer "In2.Cu")
		(net 340)
	)
	(segment
		(start 176.65 152.6)
		(end 176 153.25)
		(width 0.1)
		(layer "In2.Cu")
		(net 340)
	)
	(segment
		(start 191.125 151.225)
		(end 191.225 151.125)
		(width 0.1)
		(layer "In2.Cu")
		(net 340)
	)
	(segment
		(start 197.5 155.5)
		(end 197 155)
		(width 0.1)
		(layer "In2.Cu")
		(net 340)
	)
	(segment
		(start 197 155)
		(end 194.3 155)
		(width 0.1)
		(layer "In2.Cu")
		(net 340)
	)
	(segment
		(start 191.125 153.8)
		(end 191.125 151.225)
		(width 0.1)
		(layer "In2.Cu")
		(net 340)
	)
	(segment
		(start 194.125 154.484835)
		(end 193.515165 153.875)
		(width 0.1)
		(layer "In2.Cu")
		(net 340)
	)
	(segment
		(start 187.85 149.925)
		(end 183.375 149.925)
		(width 0.1)
		(layer "In2.Cu")
		(net 340)
	)
	(segment
		(start 192.125 149.311826)
		(end 191.688174 148.875)
		(width 0.1)
		(layer "In2.Cu")
		(net 340)
	)
	(segment
		(start 191.2 153.875)
		(end 191.125 153.8)
		(width 0.1)
		(layer "In2.Cu")
		(net 340)
	)
	(segment
		(start 182.95 150.35)
		(end 182.95 151.75)
		(width 0.1)
		(layer "In2.Cu")
		(net 340)
	)
	(segment
		(start 178.1 152)
		(end 177.5 152.6)
		(width 0.1)
		(layer "In2.Cu")
		(net 340)
	)
	(segment
		(start 183.375 149.925)
		(end 182.95 150.35)
		(width 0.1)
		(layer "In2.Cu")
		(net 340)
	)
	(segment
		(start 191.707842 151.125)
		(end 192.125 150.707842)
		(width 0.1)
		(layer "In2.Cu")
		(net 340)
	)
	(segment
		(start 191.225 151.125)
		(end 191.707842 151.125)
		(width 0.1)
		(layer "In2.Cu")
		(net 340)
	)
	(segment
		(start 176 153.25)
		(end 176 154.65)
		(width 0.1)
		(layer "In2.Cu")
		(net 340)
	)
	(segment
		(start 194.3 155)
		(end 194.125 154.825)
		(width 0.1)
		(layer "In2.Cu")
		(net 340)
	)
	(segment
		(start 175.65 155)
		(end 174.1 155)
		(width 0.1)
		(layer "In2.Cu")
		(net 340)
	)
	(segment
		(start 173.95 155.15)
		(end 173.95 155.85)
		(width 0.1)
		(layer "In2.Cu")
		(net 340)
	)
	(segment
		(start 177.5 152.6)
		(end 176.65 152.6)
		(width 0.1)
		(layer "In2.Cu")
		(net 340)
	)
	(segment
		(start 171.3 159.62)
		(end 165.1 159.62)
		(width 0.1)
		(layer "In4.Cu")
		(net 340)
	)
	(segment
		(start 161.5 156.02)
		(end 161.5 153.85)
		(width 0.1)
		(layer "In4.Cu")
		(net 340)
	)
	(segment
		(start 118.025 117.725)
		(end 117.45 117.15)
		(width 0.1)
		(layer "In4.Cu")
		(net 340)
	)
	(segment
		(start 174.55 156.45)
		(end 174.47 156.45)
		(width 0.1)
		(layer "In4.Cu")
		(net 340)
	)
	(segment
		(start 165.1 159.62)
		(end 161.5 156.02)
		(width 0.1)
		(layer "In4.Cu")
		(net 340)
	)
	(segment
		(start 161.5 153.85)
		(end 125.375 117.725)
		(width 0.1)
		(layer "In4.Cu")
		(net 340)
	)
	(segment
		(start 125.375 117.725)
		(end 118.025 117.725)
		(width 0.1)
		(layer "In4.Cu")
		(net 340)
	)
	(segment
		(start 174.47 156.45)
		(end 171.3 159.62)
		(width 0.1)
		(layer "In4.Cu")
		(net 340)
	)
	(segment
		(start 114.098 115.162921)
		(end 114.098 113.417921)
		(width 0.15)
		(layer "F.Cu")
		(net 341)
	)
	(segment
		(start 114.45 117.1)
		(end 114.45 116.151)
		(width 0.15)
		(layer "F.Cu")
		(net 341)
	)
	(segment
		(start 114.45 116.4)
		(end 114.45 115.514921)
		(width 0.15)
		(layer "F.Cu")
		(net 341)
	)
	(segment
		(start 194.0005 156.000499)
		(end 194.5 156.5)
		(width 0.256)
		(layer "F.Cu")
		(net 341)
	)
	(segment
		(start 114.45 115.514921)
		(end 114.098 115.162921)
		(width 0.15)
		(layer "F.Cu")
		(net 341)
	)
	(via
		(at 114.45 117.1)
		(size 0.45)
		(drill 0.1)
		(layers "F.Cu" "B.Cu")
		(remove_unused_layers yes)
		(keep_end_layers yes)
		(zone_layer_connections)
		(net 341)
	)
	(via
		(at 194.5 156.5)
		(size 0.45)
		(drill 0.1)
		(layers "F.Cu" "B.Cu")
		(remove_unused_layers yes)
		(keep_end_layers yes)
		(zone_layer_connections)
		(net 341)
	)
	(via
		(at 174.56 155.515)
		(size 0.45)
		(drill 0.1)
		(layers "F.Cu" "B.Cu")
		(remove_unused_layers yes)
		(keep_end_layers yes)
		(zone_layer_connections)
		(net 341)
	)
	(segment
		(start 192.95 154.3)
		(end 192.95 154.55)
		(width 0.1)
		(layer "In2.Cu")
		(net 341)
	)
	(segment
		(start 177.45 153)
		(end 182.85 153)
		(width 0.1)
		(layer "In2.Cu")
		(net 341)
	)
	(segment
		(start 191.925 150.625)
		(end 191.625 150.925)
		(width 0.1)
		(layer "In2.Cu")
		(net 341)
	)
	(segment
		(start 192.775 154.125)
		(end 192.95 154.3)
		(width 0.1)
		(layer "In2.Cu")
		(net 341)
	)
	(segment
		(start 184.3 150.125)
		(end 187.932842 150.125)
		(width 0.1)
		(layer "In2.Cu")
		(net 341)
	)
	(segment
		(start 175.045 156)
		(end 176.65 156)
		(width 0.1)
		(layer "In2.Cu")
		(net 341)
	)
	(segment
		(start 190.925 153.882842)
		(end 191.167158 154.125)
		(width 0.1)
		(layer "In2.Cu")
		(net 341)
	)
	(segment
		(start 194 155.3)
		(end 194 156)
		(width 0.1)
		(layer "In2.Cu")
		(net 341)
	)
	(segment
		(start 182.85 153)
		(end 184.05 151.8)
		(width 0.1)
		(layer "In2.Cu")
		(net 341)
	)
	(segment
		(start 194 156)
		(end 194.5 156.5)
		(width 0.1)
		(layer "In2.Cu")
		(net 341)
	)
	(segment
		(start 190.925 151.1)
		(end 190.925 153.882842)
		(width 0.1)
		(layer "In2.Cu")
		(net 341)
	)
	(segment
		(start 191.925 149.394668)
		(end 191.925 150.625)
		(width 0.1)
		(layer "In2.Cu")
		(net 341)
	)
	(segment
		(start 192.95 154.55)
		(end 193.35 154.95)
		(width 0.1)
		(layer "In2.Cu")
		(net 341)
	)
	(segment
		(start 176.875 155.775)
		(end 176.875 153.575)
		(width 0.1)
		(layer "In2.Cu")
		(net 341)
	)
	(segment
		(start 191.605332 149.075)
		(end 191.925 149.394668)
		(width 0.1)
		(layer "In2.Cu")
		(net 341)
	)
	(segment
		(start 191.1 150.925)
		(end 190.925 151.1)
		(width 0.1)
		(layer "In2.Cu")
		(net 341)
	)
	(segment
		(start 191.167158 154.125)
		(end 192.775 154.125)
		(width 0.1)
		(layer "In2.Cu")
		(net 341)
	)
	(segment
		(start 191.625 150.925)
		(end 191.1 150.925)
		(width 0.1)
		(layer "In2.Cu")
		(net 341)
	)
	(segment
		(start 187.932842 150.125)
		(end 188.982842 149.075)
		(width 0.1)
		(layer "In2.Cu")
		(net 341)
	)
	(segment
		(start 193.65 154.95)
		(end 194 155.3)
		(width 0.1)
		(layer "In2.Cu")
		(net 341)
	)
	(segment
		(start 176.875 153.575)
		(end 177.45 153)
		(width 0.1)
		(layer "In2.Cu")
		(net 341)
	)
	(segment
		(start 184.05 151.8)
		(end 184.05 150.375)
		(width 0.1)
		(layer "In2.Cu")
		(net 341)
	)
	(segment
		(start 184.05 150.375)
		(end 184.3 150.125)
		(width 0.1)
		(layer "In2.Cu")
		(net 341)
	)
	(segment
		(start 174.56 155.515)
		(end 175.045 156)
		(width 0.1)
		(layer "In2.Cu")
		(net 341)
	)
	(segment
		(start 188.982842 149.075)
		(end 191.605332 149.075)
		(width 0.1)
		(layer "In2.Cu")
		(net 341)
	)
	(segment
		(start 193.35 154.95)
		(end 193.65 154.95)
		(width 0.1)
		(layer "In2.Cu")
		(net 341)
	)
	(segment
		(start 176.65 156)
		(end 176.875 155.775)
		(width 0.1)
		(layer "In2.Cu")
		(net 341)
	)
	(segment
		(start 115.85 115.7)
		(end 114.45 117.1)
		(width 0.1)
		(layer "In4.Cu")
		(net 341)
	)
	(segment
		(start 162.04 155.95)
		(end 162.04 153.622842)
		(width 0.1)
		(layer "In4.Cu")
		(net 341)
	)
	(segment
		(start 171.055 159.02)
		(end 165.11 159.02)
		(width 0.1)
		(layer "In4.Cu")
		(net 341)
	)
	(segment
		(start 162.04 153.622842)
		(end 124.117158 115.7)
		(width 0.1)
		(layer "In4.Cu")
		(net 341)
	)
	(segment
		(start 174.56 155.515)
		(end 171.055 159.02)
		(width 0.1)
		(layer "In4.Cu")
		(net 341)
	)
	(segment
		(start 165.11 159.02)
		(end 162.04 155.95)
		(width 0.1)
		(layer "In4.Cu")
		(net 341)
	)
	(segment
		(start 124.117158 115.7)
		(end 115.85 115.7)
		(width 0.1)
		(layer "In4.Cu")
		(net 341)
	)
	(segment
		(start 121.505 148.61)
		(end 121.975 148.61)
		(width 0.4)
		(layer "F.Cu")
		(net 342)
	)
	(via
		(at 121.975 148.61)
		(size 0.45)
		(drill 0.1)
		(layers "F.Cu" "B.Cu")
		(remove_unused_layers yes)
		(keep_end_layers yes)
		(zone_layer_connections)
		(net 342)
	)
	(segment
		(start 108.534325 156.619)
		(end 107.071674 156.619)
		(width 0.16)
		(layer "B.Cu")
		(net 342)
	)
	(segment
		(start 110.048298 156.170905)
		(end 116.091776 150.127426)
		(width 0.16)
		(layer "B.Cu")
		(net 342)
	)
	(segment
		(start 118.756163 148.265001)
		(end 121.386049 148.265001)
		(width 0.16)
		(layer "B.Cu")
		(net 342)
	)
	(segment
		(start 121.975 148.61)
		(end 121.8025 148.4375)
		(width 0.16)
		(layer "B.Cu")
		(net 342)
	)
	(segment
		(start 121.975 148.61)
		(end 122.47 148.61)
		(width 0.16)
		(layer "B.Cu")
		(net 342)
	)
	(segment
		(start 117.387128 148.832074)
		(end 116.091776 150.127426)
		(width 0.16)
		(layer "B.Cu")
		(net 342)
	)
	(segment
		(start 105.685805 156.869)
		(end 105.17 156.869)
		(width 0.16)
		(layer "B.Cu")
		(net 342)
	)
	(segment
		(start 108.763676 156.524)
		(end 109.195852 156.524)
		(width 0.16)
		(layer "B.Cu")
		(net 342)
	)
	(segment
		(start 106.842323 156.524)
		(end 106.518708 156.524)
		(width 0.16)
		(layer "B.Cu")
		(net 342)
	)
	(arc
		(start 108.534325 156.619)
		(mid 108.596387 156.606655)
		(end 108.649001 156.5715)
		(width 0.16)
		(layer "B.Cu")
		(net 342)
	)
	(arc
		(start 108.763676 156.524)
		(mid 108.701614 156.536344)
		(end 108.649001 156.5715)
		(width 0.16)
		(layer "B.Cu")
		(net 342)
	)
	(arc
		(start 110.048298 156.170905)
		(mid 109.657192 156.432233)
		(end 109.195852 156.524)
		(width 0.16)
		(layer "B.Cu")
		(net 342)
	)
	(arc
		(start 106.102257 156.6965)
		(mid 106.293326 156.568831)
		(end 106.518708 156.524)
		(width 0.16)
		(layer "B.Cu")
		(net 342)
	)
	(arc
		(start 118.756163 148.265001)
		(mid 118.015247 148.412378)
		(end 117.387128 148.832074)
		(width 0.16)
		(layer "B.Cu")
		(net 342)
	)
	(arc
		(start 106.102257 156.6965)
		(mid 105.911187 156.824168)
		(end 105.685805 156.869)
		(width 0.16)
		(layer "B.Cu")
		(net 342)
	)
	(arc
		(start 106.842323 156.524)
		(mid 106.904385 156.536344)
		(end 106.956999 156.5715)
		(width 0.16)
		(layer "B.Cu")
		(net 342)
	)
	(arc
		(start 121.8025 148.4375)
		(mid 121.61143 148.309832)
		(end 121.386049 148.265001)
		(width 0.16)
		(layer "B.Cu")
		(net 342)
	)
	(arc
		(start 106.956999 156.5715)
		(mid 107.009612 156.606655)
		(end 107.071674 156.619)
		(width 0.16)
		(layer "B.Cu")
		(net 342)
	)
	(segment
		(start 121.505 147.61)
		(end 121.975 147.61)
		(width 0.4)
		(layer "F.Cu")
		(net 344)
	)
	(via
		(at 121.975 147.61)
		(size 0.45)
		(drill 0.1)
		(layers "F.Cu" "B.Cu")
		(remove_unused_layers yes)
		(keep_end_layers yes)
		(zone_layer_connections)
		(net 344)
	)
	(segment
		(start 108.534325 156.119)
		(end 107.071674 156.119)
		(width 0.16)
		(layer "B.Cu")
		(net 344)
	)
	(segment
		(start 121.975 147.61)
		(end 121.8025 147.782499)
		(width 0.16)
		(layer "B.Cu")
		(net 344)
	)
	(segment
		(start 109.823576 155.957219)
		(end 115.808312 149.972482)
		(width 0.16)
		(layer "B.Cu")
		(net 344)
	)
	(segment
		(start 121.975 147.61)
		(end 122.47 147.61)
		(width 0.16)
		(layer "B.Cu")
		(net 344)
	)
	(segment
		(start 108.763676 156.214)
		(end 109.203651 156.214)
		(width 0.16)
		(layer "B.Cu")
		(net 344)
	)
	(segment
		(start 118.776846 147.954999)
		(end 121.386049 147.954999)
		(width 0.16)
		(layer "B.Cu")
		(net 344)
	)
	(segment
		(start 105.685805 155.869)
		(end 105.17 155.869)
		(width 0.16)
		(layer "B.Cu")
		(net 344)
	)
	(segment
		(start 117.153301 148.627493)
		(end 115.808312 149.972482)
		(width 0.16)
		(layer "B.Cu")
		(net 344)
	)
	(segment
		(start 106.842323 156.214)
		(end 106.518708 156.214)
		(width 0.16)
		(layer "B.Cu")
		(net 344)
	)
	(arc
		(start 108.534325 156.119)
		(mid 108.596387 156.131344)
		(end 108.649001 156.1665)
		(width 0.16)
		(layer "B.Cu")
		(net 344)
	)
	(arc
		(start 106.102257 156.0415)
		(mid 106.293326 156.169168)
		(end 106.518708 156.214)
		(width 0.16)
		(layer "B.Cu")
		(net 344)
	)
	(arc
		(start 118.776846 147.954999)
		(mid 117.89819 148.129774)
		(end 117.153301 148.627493)
		(width 0.16)
		(layer "B.Cu")
		(net 344)
	)
	(arc
		(start 106.956999 156.1665)
		(mid 106.904385 156.201655)
		(end 106.842323 156.214)
		(width 0.16)
		(layer "B.Cu")
		(net 344)
	)
	(arc
		(start 107.071674 156.119)
		(mid 107.009612 156.131344)
		(end 106.956999 156.1665)
		(width 0.16)
		(layer "B.Cu")
		(net 344)
	)
	(arc
		(start 105.685805 155.869)
		(mid 105.911187 155.913831)
		(end 106.102257 156.0415)
		(width 0.16)
		(layer "B.Cu")
		(net 344)
	)
	(arc
		(start 109.823576 155.957219)
		(mid 109.539152 156.147265)
		(end 109.203651 156.214)
		(width 0.16)
		(layer "B.Cu")
		(net 344)
	)
	(arc
		(start 108.649001 156.1665)
		(mid 108.701614 156.201655)
		(end 108.763676 156.214)
		(width 0.16)
		(layer "B.Cu")
		(net 344)
	)
	(arc
		(start 121.8025 147.782499)
		(mid 121.61143 147.910167)
		(end 121.386049 147.954999)
		(width 0.16)
		(layer "B.Cu")
		(net 344)
	)
	(segment
		(start 121.505 150.61)
		(end 121.975 150.61)
		(width 0.4)
		(layer "F.Cu")
		(net 346)
	)
	(via
		(at 121.975 150.61)
		(size 0.45)
		(drill 0.1)
		(layers "F.Cu" "B.Cu")
		(remove_unused_layers yes)
		(keep_end_layers yes)
		(zone_layer_connections)
		(net 346)
	)
	(segment
		(start 121.975 150.61)
		(end 121.8025 150.4375)
		(width 0.16)
		(layer "B.Cu")
		(net 346)
	)
	(segment
		(start 108.763676 158.025)
		(end 109.195852 158.025)
		(width 0.16)
		(layer "B.Cu")
		(net 346)
	)
	(segment
		(start 121.975 150.61)
		(end 122.47 150.61)
		(width 0.16)
		(layer "B.Cu")
		(net 346)
	)
	(segment
		(start 110.048298 157.671905)
		(end 116.341276 151.378926)
		(width 0.16)
		(layer "B.Cu")
		(net 346)
	)
	(segment
		(start 106.842323 158.025)
		(end 106.518708 158.025)
		(width 0.16)
		(layer "B.Cu")
		(net 346)
	)
	(segment
		(start 117.124448 150.595754)
		(end 116.341276 151.378926)
		(width 0.16)
		(layer "B.Cu")
		(net 346)
	)
	(segment
		(start 117.922957 150.265001)
		(end 121.386049 150.265001)
		(width 0.16)
		(layer "B.Cu")
		(net 346)
	)
	(segment
		(start 108.534325 158.12)
		(end 107.071674 158.12)
		(width 0.16)
		(layer "B.Cu")
		(net 346)
	)
	(segment
		(start 105.685805 158.37)
		(end 105.17 158.37)
		(width 0.16)
		(layer "B.Cu")
		(net 346)
	)
	(arc
		(start 108.763676 158.025)
		(mid 108.701614 158.037344)
		(end 108.649001 158.0725)
		(width 0.16)
		(layer "B.Cu")
		(net 346)
	)
	(arc
		(start 106.102257 158.1975)
		(mid 106.293326 158.069831)
		(end 106.518708 158.025)
		(width 0.16)
		(layer "B.Cu")
		(net 346)
	)
	(arc
		(start 121.8025 150.4375)
		(mid 121.61143 150.309832)
		(end 121.386049 150.265001)
		(width 0.16)
		(layer "B.Cu")
		(net 346)
	)
	(arc
		(start 106.842323 158.025)
		(mid 106.904385 158.037344)
		(end 106.956999 158.0725)
		(width 0.16)
		(layer "B.Cu")
		(net 346)
	)
	(arc
		(start 117.922957 150.265001)
		(mid 117.490807 150.350961)
		(end 117.124448 150.595754)
		(width 0.16)
		(layer "B.Cu")
		(net 346)
	)
	(arc
		(start 110.048298 157.671905)
		(mid 109.657192 157.933233)
		(end 109.195852 158.025)
		(width 0.16)
		(layer "B.Cu")
		(net 346)
	)
	(arc
		(start 107.071674 158.12)
		(mid 107.009612 158.107655)
		(end 106.956999 158.0725)
		(width 0.16)
		(layer "B.Cu")
		(net 346)
	)
	(arc
		(start 108.534325 158.12)
		(mid 108.596387 158.107655)
		(end 108.649001 158.0725)
		(width 0.16)
		(layer "B.Cu")
		(net 346)
	)
	(arc
		(start 105.685805 158.37)
		(mid 105.911187 158.325168)
		(end 106.102257 158.1975)
		(width 0.16)
		(layer "B.Cu")
		(net 346)
	)
	(segment
		(start 121.505 149.61)
		(end 121.975 149.61)
		(width 0.4)
		(layer "F.Cu")
		(net 348)
	)
	(via
		(at 121.975 149.61)
		(size 0.45)
		(drill 0.1)
		(layers "F.Cu" "B.Cu")
		(remove_unused_layers yes)
		(keep_end_layers yes)
		(zone_layer_connections)
		(net 348)
	)
	(segment
		(start 108.19 157.618)
		(end 108.191 157.617)
		(width 0.16)
		(layer "B.Cu")
		(net 348)
	)
	(segment
		(start 117.925 149.954999)
		(end 121.386049 149.954999)
		(width 0.16)
		(layer "B.Cu")
		(net 348)
	)
	(segment
		(start 106.842323 157.715)
		(end 106.518708 157.715)
		(width 0.16)
		(layer "B.Cu")
		(net 348)
	)
	(segment
		(start 109.823576 157.458219)
		(end 116.057812 151.223982)
		(width 0.16)
		(layer "B.Cu")
		(net 348)
	)
	(segment
		(start 121.975 149.61)
		(end 121.8025 149.782499)
		(width 0.16)
		(layer "B.Cu")
		(net 348)
	)
	(segment
		(start 121.975 149.61)
		(end 122.47 149.61)
		(width 0.16)
		(layer "B.Cu")
		(net 348)
	)
	(segment
		(start 107.071674 157.62)
		(end 108.534325 157.62)
		(width 0.16)
		(layer "B.Cu")
		(net 348)
	)
	(segment
		(start 109.203651 157.715)
		(end 108.763676 157.715)
		(width 0.16)
		(layer "B.Cu")
		(net 348)
	)
	(segment
		(start 116.903801 150.377993)
		(end 116.057812 151.223982)
		(width 0.16)
		(layer "B.Cu")
		(net 348)
	)
	(segment
		(start 105.685805 157.37)
		(end 105.17 157.37)
		(width 0.16)
		(layer "B.Cu")
		(net 348)
	)
	(arc
		(start 106.956999 157.6675)
		(mid 106.904385 157.702655)
		(end 106.842323 157.715)
		(width 0.16)
		(layer "B.Cu")
		(net 348)
	)
	(arc
		(start 121.8025 149.782499)
		(mid 121.61143 149.910167)
		(end 121.386049 149.954999)
		(width 0.16)
		(layer "B.Cu")
		(net 348)
	)
	(arc
		(start 108.649001 157.6675)
		(mid 108.701614 157.702655)
		(end 108.763676 157.715)
		(width 0.16)
		(layer "B.Cu")
		(net 348)
	)
	(arc
		(start 106.102257 157.5425)
		(mid 105.911187 157.414831)
		(end 105.685805 157.37)
		(width 0.16)
		(layer "B.Cu")
		(net 348)
	)
	(arc
		(start 108.19 157.618)
		(mid 108.188892 157.61874)
		(end 108.187585 157.619)
		(width 0.16)
		(layer "B.Cu")
		(net 348)
	)
	(arc
		(start 108.649001 157.6675)
		(mid 108.596387 157.632344)
		(end 108.534325 157.62)
		(width 0.16)
		(layer "B.Cu")
		(net 348)
	)
	(arc
		(start 106.102257 157.5425)
		(mid 106.293326 157.670168)
		(end 106.518708 157.715)
		(width 0.16)
		(layer "B.Cu")
		(net 348)
	)
	(arc
		(start 117.925 149.954999)
		(mid 117.372331 150.064931)
		(end 116.903801 150.377993)
		(width 0.16)
		(layer "B.Cu")
		(net 348)
	)
	(arc
		(start 109.203651 157.715)
		(mid 109.539152 157.648265)
		(end 109.823576 157.458219)
		(width 0.16)
		(layer "B.Cu")
		(net 348)
	)
	(arc
		(start 107.071674 157.62)
		(mid 107.009612 157.632344)
		(end 106.956999 157.6675)
		(width 0.16)
		(layer "B.Cu")
		(net 348)
	)
	(segment
		(start 121.505 152.61)
		(end 121.975 152.61)
		(width 0.4)
		(layer "F.Cu")
		(net 349)
	)
	(via
		(at 121.975 152.61)
		(size 0.45)
		(drill 0.1)
		(layers "F.Cu" "B.Cu")
		(remove_unused_layers yes)
		(keep_end_layers yes)
		(zone_layer_connections)
		(net 349)
	)
	(segment
		(start 109.195852 159.525)
		(end 108.763676 159.525)
		(width 0.16)
		(layer "B.Cu")
		(net 349)
	)
	(segment
		(start 117.069147 152.265001)
		(end 121.386049 152.265001)
		(width 0.16)
		(layer "B.Cu")
		(net 349)
	)
	(segment
		(start 110.048298 159.171905)
		(end 116.591276 152.628926)
		(width 0.16)
		(layer "B.Cu")
		(net 349)
	)
	(segment
		(start 121.975 152.61)
		(end 122.47 152.61)
		(width 0.16)
		(layer "B.Cu")
		(net 349)
	)
	(segment
		(start 116.874629 152.345573)
		(end 116.591276 152.628926)
		(width 0.16)
		(layer "B.Cu")
		(net 349)
	)
	(segment
		(start 106.842323 159.525)
		(end 106.518708 159.525)
		(width 0.16)
		(layer "B.Cu")
		(net 349)
	)
	(segment
		(start 121.975 152.61)
		(end 121.8025 152.4375)
		(width 0.16)
		(layer "B.Cu")
		(net 349)
	)
	(segment
		(start 107.071674 159.62)
		(end 108.534325 159.62)
		(width 0.16)
		(layer "B.Cu")
		(net 349)
	)
	(segment
		(start 105.685805 159.87)
		(end 105.17 159.87)
		(width 0.16)
		(layer "B.Cu")
		(net 349)
	)
	(arc
		(start 108.534325 159.62)
		(mid 108.596387 159.607655)
		(end 108.649001 159.5725)
		(width 0.16)
		(layer "B.Cu")
		(net 349)
	)
	(arc
		(start 106.842323 159.525)
		(mid 106.904385 159.537344)
		(end 106.956999 159.5725)
		(width 0.16)
		(layer "B.Cu")
		(net 349)
	)
	(arc
		(start 109.195852 159.525)
		(mid 109.657192 159.433233)
		(end 110.048298 159.171905)
		(width 0.16)
		(layer "B.Cu")
		(net 349)
	)
	(arc
		(start 108.763676 159.525)
		(mid 108.701614 159.537344)
		(end 108.649001 159.5725)
		(width 0.16)
		(layer "B.Cu")
		(net 349)
	)
	(arc
		(start 106.102257 159.6975)
		(mid 106.293326 159.569831)
		(end 106.518708 159.525)
		(width 0.16)
		(layer "B.Cu")
		(net 349)
	)
	(arc
		(start 121.8025 152.4375)
		(mid 121.61143 152.309832)
		(end 121.386049 152.265001)
		(width 0.16)
		(layer "B.Cu")
		(net 349)
	)
	(arc
		(start 107.071674 159.62)
		(mid 107.009612 159.607655)
		(end 106.956999 159.5725)
		(width 0.16)
		(layer "B.Cu")
		(net 349)
	)
	(arc
		(start 117.069147 152.265001)
		(mid 116.963875 152.285941)
		(end 116.874629 152.345573)
		(width 0.16)
		(layer "B.Cu")
		(net 349)
	)
	(arc
		(start 106.102257 159.6975)
		(mid 105.911187 159.825168)
		(end 105.685805 159.87)
		(width 0.16)
		(layer "B.Cu")
		(net 349)
	)
	(segment
		(start 196.0005 154.000499)
		(end 196.5 154.5)
		(width 0.256)
		(layer "F.Cu")
		(net 350)
	)
	(segment
		(start 217.898501 154.403499)
		(end 218.884 154.403499)
		(width 0.256)
		(layer "F.Cu")
		(net 350)
	)
	(segment
		(start 218.884 154.403499)
		(end 218.898499 154.389)
		(width 0.256)
		(layer "F.Cu")
		(net 350)
	)
	(via
		(at 218.898499 154.389)
		(size 0.45)
		(drill 0.1)
		(layers "F.Cu" "B.Cu")
		(remove_unused_layers yes)
		(keep_end_layers yes)
		(zone_layer_connections)
		(net 350)
	)
	(via
		(at 196.5 154.5)
		(size 0.45)
		(drill 0.1)
		(layers "F.Cu" "B.Cu")
		(remove_unused_layers yes)
		(keep_end_layers yes)
		(zone_layer_connections)
		(net 350)
	)
	(segment
		(start 218.898499 154.389)
		(end 219.425 154.389)
		(width 0.256)
		(layer "B.Cu")
		(net 350)
	)
	(segment
		(start 198 155.691421)
		(end 198.308579 156)
		(width 0.1)
		(layer "In4.Cu")
		(net 350)
	)
	(segment
		(start 198.308579 156)
		(end 199.68 156)
		(width 0.1)
		(layer "In4.Cu")
		(net 350)
	)
	(segment
		(start 199.97 156.29)
		(end 199.97 156.635165)
		(width 0.1)
		(layer "In4.Cu")
		(net 350)
	)
	(segment
		(start 216.717499 156.57)
		(end 218.898499 154.389)
		(width 0.1)
		(layer "In4.Cu")
		(net 350)
	)
	(segment
		(start 196.5 154.5)
		(end 196.95 154.95)
		(width 0.1)
		(layer "In4.Cu")
		(net 350)
	)
	(segment
		(start 199.97 156.635165)
		(end 200.264835 156.93)
		(width 0.1)
		(layer "In4.Cu")
		(net 350)
	)
	(segment
		(start 198 155.4)
		(end 198 155.691421)
		(width 0.1)
		(layer "In4.Cu")
		(net 350)
	)
	(segment
		(start 199.68 156)
		(end 199.97 156.29)
		(width 0.1)
		(layer "In4.Cu")
		(net 350)
	)
	(segment
		(start 200.264835 156.93)
		(end 203.94 156.93)
		(width 0.1)
		(layer "In4.Cu")
		(net 350)
	)
	(segment
		(start 196.95 154.95)
		(end 197.55 154.95)
		(width 0.1)
		(layer "In4.Cu")
		(net 350)
	)
	(segment
		(start 197.55 154.95)
		(end 198 155.4)
		(width 0.1)
		(layer "In4.Cu")
		(net 350)
	)
	(segment
		(start 204.3 156.57)
		(end 216.717499 156.57)
		(width 0.1)
		(layer "In4.Cu")
		(net 350)
	)
	(segment
		(start 203.94 156.93)
		(end 204.3 156.57)
		(width 0.1)
		(layer "In4.Cu")
		(net 350)
	)
	(segment
		(start 199.5 155.5)
		(end 199.0005 155.0005)
		(width 0.256)
		(layer "F.Cu")
		(net 351)
	)
	(via
		(at 209.409025 151.149)
		(size 0.45)
		(drill 0.1)
		(layers "F.Cu" "B.Cu")
		(remove_unused_layers yes)
		(keep_end_layers yes)
		(zone_layer_connections)
		(net 351)
	)
	(via
		(at 199.5 155.5)
		(size 0.45)
		(drill 0.1)
		(layers "F.Cu" "B.Cu")
		(remove_unused_layers yes)
		(keep_end_layers yes)
		(zone_layer_connections)
		(net 351)
	)
	(segment
		(start 209.405 151.144975)
		(end 209.409025 151.149)
		(width 0.256)
		(layer "B.Cu")
		(net 351)
	)
	(segment
		(start 209.405 150.6095)
		(end 209.405 151.144975)
		(width 0.256)
		(layer "B.Cu")
		(net 351)
	)
	(segment
		(start 211.2 156.09)
		(end 210.69 156.09)
		(width 0.1)
		(layer "In4.Cu")
		(net 351)
	)
	(segment
		(start 202.46 156.11)
		(end 202.35 156)
		(width 0.1)
		(layer "In4.Cu")
		(net 351)
	)
	(segment
		(start 209.409025 151.962173)
		(end 209.94 152.493148)
		(width 0.1)
		(layer "In4.Cu")
		(net 351)
	)
	(segment
		(start 210.22 154.47)
		(end 210.22 154.11)
		(width 0.1)
		(layer "In4.Cu")
		(net 351)
	)
	(segment
		(start 209.409025 151.149)
		(end 209.409025 151.962173)
		(width 0.1)
		(layer "In4.Cu")
		(net 351)
	)
	(segment
		(start 211.53 155.76)
		(end 211.2 156.09)
		(width 0.1)
		(layer "In4.Cu")
		(net 351)
	)
	(segment
		(start 212.889582 154.905)
		(end 211.805 154.905)
		(width 0.1)
		(layer "In4.Cu")
		(net 351)
	)
	(segment
		(start 209.54 154.44)
		(end 209.7 154.6)
		(width 0.1)
		(layer "In4.Cu")
		(net 351)
	)
	(segment
		(start 210.09 154.6)
		(end 210.22 154.47)
		(width 0.1)
		(layer "In4.Cu")
		(net 351)
	)
	(segment
		(start 209.94 152.493148)
		(end 209.94 153.128717)
		(width 0.1)
		(layer "In4.Cu")
		(net 351)
	)
	(segment
		(start 211.53 154)
		(end 211.53 154.08)
		(width 0.1)
		(layer "In4.Cu")
		(net 351)
	)
	(segment
		(start 210.69 156.09)
		(end 210.05 155.45)
		(width 0.1)
		(layer "In4.Cu")
		(net 351)
	)
	(segment
		(start 209.54 153.528717)
		(end 209.54 154.44)
		(width 0.1)
		(layer "In4.Cu")
		(net 351)
	)
	(segment
		(start 211.805 154.355)
		(end 212.889582 154.355)
		(width 0.1)
		(layer "In4.Cu")
		(net 351)
	)
	(segment
		(start 202.35 156)
		(end 200.37 156)
		(width 0.1)
		(layer "In4.Cu")
		(net 351)
	)
	(segment
		(start 200.37 156)
		(end 199.87 155.5)
		(width 0.1)
		(layer "In4.Cu")
		(net 351)
	)
	(segment
		(start 209.94 153.128717)
		(end 209.54 153.528717)
		(width 0.1)
		(layer "In4.Cu")
		(net 351)
	)
	(segment
		(start 210.05 155.45)
		(end 208.71 155.45)
		(width 0.1)
		(layer "In4.Cu")
		(net 351)
	)
	(segment
		(start 211.27 153.74)
		(end 211.53 154)
		(width 0.1)
		(layer "In4.Cu")
		(net 351)
	)
	(segment
		(start 208.05 156.11)
		(end 202.46 156.11)
		(width 0.1)
		(layer "In4.Cu")
		(net 351)
	)
	(segment
		(start 209.7 154.6)
		(end 210.09 154.6)
		(width 0.1)
		(layer "In4.Cu")
		(net 351)
	)
	(segment
		(start 211.53 155.18)
		(end 211.53 155.76)
		(width 0.1)
		(layer "In4.Cu")
		(net 351)
	)
	(segment
		(start 199.87 155.5)
		(end 199.5 155.5)
		(width 0.1)
		(layer "In4.Cu")
		(net 351)
	)
	(segment
		(start 210.22 154.11)
		(end 210.59 153.74)
		(width 0.1)
		(layer "In4.Cu")
		(net 351)
	)
	(segment
		(start 208.71 155.45)
		(end 208.05 156.11)
		(width 0.1)
		(layer "In4.Cu")
		(net 351)
	)
	(segment
		(start 210.59 153.74)
		(end 211.27 153.74)
		(width 0.1)
		(layer "In4.Cu")
		(net 351)
	)
	(arc
		(start 212.889582 154.355)
		(mid 213.084036 154.435546)
		(end 213.164582 154.63)
		(width 0.1)
		(layer "In4.Cu")
		(net 351)
	)
	(arc
		(start 213.164582 154.63)
		(mid 213.084036 154.824454)
		(end 212.889582 154.905)
		(width 0.1)
		(layer "In4.Cu")
		(net 351)
	)
	(arc
		(start 211.53 154.08)
		(mid 211.610546 154.274454)
		(end 211.805 154.355)
		(width 0.1)
		(layer "In4.Cu")
		(net 351)
	)
	(arc
		(start 211.805 154.905)
		(mid 211.610546 154.985546)
		(end 211.53 155.18)
		(width 0.1)
		(layer "In4.Cu")
		(net 351)
	)
	(segment
		(start 198.0005 154.0005)
		(end 198.5 154.5)
		(width 0.256)
		(layer "F.Cu")
		(net 352)
	)
	(via
		(at 198.5 154.5)
		(size 0.45)
		(drill 0.1)
		(layers "F.Cu" "B.Cu")
		(remove_unused_layers yes)
		(keep_end_layers yes)
		(zone_layer_connections)
		(net 352)
	)
	(via
		(at 216.924 153.12393)
		(size 0.45)
		(drill 0.1)
		(layers "F.Cu" "B.Cu")
		(remove_unused_layers yes)
		(keep_end_layers yes)
		(zone_layer_connections)
		(net 352)
	)
	(segment
		(start 216.92743 153.1205)
		(end 216.924 153.12393)
		(width 0.256)
		(layer "B.Cu")
		(net 352)
	)
	(segment
		(start 217.405 153.1205)
		(end 216.92743 153.1205)
		(width 0.256)
		(layer "B.Cu")
		(net 352)
	)
	(segment
		(start 203.295 154.256055)
		(end 203.295 153.746967)
		(width 0.1)
		(layer "In4.Cu")
		(net 352)
	)
	(segment
		(start 206.35 151.91)
		(end 208.49 151.91)
		(width 0.1)
		(layer "In4.Cu")
		(net 352)
	)
	(segment
		(start 205.13 153.56)
		(end 205.13 153.13)
		(width 0.1)
		(layer "In4.Cu")
		(net 352)
	)
	(segment
		(start 210.566 152.654)
		(end 216.524 152.654)
		(width 0.1)
		(layer "In4.Cu")
		(net 352)
	)
	(segment
		(start 216.924 153.054)
		(end 216.924 153.12393)
		(width 0.1)
		(layer "In4.Cu")
		(net 352)
	)
	(segment
		(start 209.178 150.622)
		(end 209.572 150.622)
		(width 0.1)
		(layer "In4.Cu")
		(net 352)
	)
	(segment
		(start 204.098033 154)
		(end 204.69 154)
		(width 0.1)
		(layer "In4.Cu")
		(net 352)
	)
	(segment
		(start 208.8 151.6)
		(end 208.8 151)
		(width 0.1)
		(layer "In4.Cu")
		(net 352)
	)
	(segment
		(start 203.548033 153.493934)
		(end 203.591967 153.493934)
		(width 0.1)
		(layer "In4.Cu")
		(net 352)
	)
	(segment
		(start 202.426126 153.493873)
		(end 202.491937 153.493873)
		(width 0.1)
		(layer "In4.Cu")
		(net 352)
	)
	(segment
		(start 209.572 150.622)
		(end 209.95 151)
		(width 0.1)
		(layer "In4.Cu")
		(net 352)
	)
	(segment
		(start 204.69 154)
		(end 205.13 153.56)
		(width 0.1)
		(layer "In4.Cu")
		(net 352)
	)
	(segment
		(start 198.85 154.5)
		(end 199.35 154)
		(width 0.1)
		(layer "In4.Cu")
		(net 352)
	)
	(segment
		(start 209.95 151)
		(end 209.95 152.038)
		(width 0.1)
		(layer "In4.Cu")
		(net 352)
	)
	(segment
		(start 203.001054 154.512109)
		(end 203.038946 154.512109)
		(width 0.1)
		(layer "In4.Cu")
		(net 352)
	)
	(segment
		(start 209.95 152.038)
		(end 210.566 152.654)
		(width 0.1)
		(layer "In4.Cu")
		(net 352)
	)
	(segment
		(start 202.745 153.746936)
		(end 202.745 154.256055)
		(width 0.1)
		(layer "In4.Cu")
		(net 352)
	)
	(segment
		(start 199.35 154)
		(end 201.92 154)
		(width 0.1)
		(layer "In4.Cu")
		(net 352)
	)
	(segment
		(start 202.173063 153.746937)
		(end 202.173063 153.746936)
		(width 0.1)
		(layer "In4.Cu")
		(net 352)
	)
	(segment
		(start 216.524 152.654)
		(end 216.924 153.054)
		(width 0.1)
		(layer "In4.Cu")
		(net 352)
	)
	(segment
		(start 205.13 153.13)
		(end 206.35 151.91)
		(width 0.1)
		(layer "In4.Cu")
		(net 352)
	)
	(segment
		(start 208.49 151.91)
		(end 208.8 151.6)
		(width 0.1)
		(layer "In4.Cu")
		(net 352)
	)
	(segment
		(start 198.5 154.5)
		(end 198.85 154.5)
		(width 0.1)
		(layer "In4.Cu")
		(net 352)
	)
	(segment
		(start 208.8 151)
		(end 209.178 150.622)
		(width 0.1)
		(layer "In4.Cu")
		(net 352)
	)
	(arc
		(start 203.591967 153.493934)
		(mid 203.770888 153.568046)
		(end 203.845 153.746967)
		(width 0.1)
		(layer "In4.Cu")
		(net 352)
	)
	(arc
		(start 201.92 154)
		(mid 202.098943 153.92588)
		(end 202.173063 153.746937)
		(width 0.1)
		(layer "In4.Cu")
		(net 352)
	)
	(arc
		(start 203.038946 154.512109)
		(mid 203.220004 154.437113)
		(end 203.295 154.256055)
		(width 0.1)
		(layer "In4.Cu")
		(net 352)
	)
	(arc
		(start 202.173063 153.746936)
		(mid 202.247183 153.567993)
		(end 202.426126 153.493873)
		(width 0.1)
		(layer "In4.Cu")
		(net 352)
	)
	(arc
		(start 202.745 154.256055)
		(mid 202.819996 154.437113)
		(end 203.001054 154.512109)
		(width 0.1)
		(layer "In4.Cu")
		(net 352)
	)
	(arc
		(start 203.845 153.746967)
		(mid 203.919112 153.925888)
		(end 204.098033 154)
		(width 0.1)
		(layer "In4.Cu")
		(net 352)
	)
	(arc
		(start 202.491937 153.493873)
		(mid 202.67088 153.567993)
		(end 202.745 153.746936)
		(width 0.1)
		(layer "In4.Cu")
		(net 352)
	)
	(arc
		(start 203.295 153.746967)
		(mid 203.369112 153.568046)
		(end 203.548033 153.493934)
		(width 0.1)
		(layer "In4.Cu")
		(net 352)
	)
	(segment
		(start 198.500001 155.5)
		(end 198.0005 155.0005)
		(width 0.256)
		(layer "F.Cu")
		(net 353)
	)
	(via
		(at 198.500001 155.5)
		(size 0.45)
		(drill 0.1)
		(layers "F.Cu" "B.Cu")
		(remove_unused_layers yes)
		(keep_end_layers yes)
		(zone_layer_connections)
		(net 353)
	)
	(via
		(at 216.924 151.85343)
		(size 0.45)
		(drill 0.1)
		(layers "F.Cu" "B.Cu")
		(remove_unused_layers yes)
		(keep_end_layers yes)
		(zone_layer_connections)
		(net 353)
	)
	(segment
		(start 217.405 151.85)
		(end 216.92743 151.85)
		(width 0.256)
		(layer "B.Cu")
		(net 353)
	)
	(segment
		(start 216.92743 151.85)
		(end 216.924 151.85343)
		(width 0.256)
		(layer "B.Cu")
		(net 353)
	)
	(segment
		(start 209.08 150.2)
		(end 208.29 150.99)
		(width 0.1)
		(layer "In4.Cu")
		(net 353)
	)
	(segment
		(start 210.35 151.96)
		(end 210.35 150.69)
		(width 0.1)
		(layer "In4.Cu")
		(net 353)
	)
	(segment
		(start 205.955 150.99)
		(end 203.945 153)
		(width 0.1)
		(layer "In4.Cu")
		(net 353)
	)
	(segment
		(start 216.924 151.85343)
		(end 216.52093 152.2565)
		(width 0.1)
		(layer "In4.Cu")
		(net 353)
	)
	(segment
		(start 216.52093 152.2565)
		(end 210.6465 152.2565)
		(width 0.1)
		(layer "In4.Cu")
		(net 353)
	)
	(segment
		(start 198.05 154.34)
		(end 198.05 155.049999)
		(width 0.1)
		(layer "In4.Cu")
		(net 353)
	)
	(segment
		(start 209.86 150.2)
		(end 209.08 150.2)
		(width 0.1)
		(layer "In4.Cu")
		(net 353)
	)
	(segment
		(start 210.35 150.69)
		(end 209.86 150.2)
		(width 0.1)
		(layer "In4.Cu")
		(net 353)
	)
	(segment
		(start 210.6465 152.2565)
		(end 210.35 151.96)
		(width 0.1)
		(layer "In4.Cu")
		(net 353)
	)
	(segment
		(start 199.4 153)
		(end 199 153.4)
		(width 0.1)
		(layer "In4.Cu")
		(net 353)
	)
	(segment
		(start 199 153.71)
		(end 198.71 154)
		(width 0.1)
		(layer "In4.Cu")
		(net 353)
	)
	(segment
		(start 203.945 153)
		(end 199.4 153)
		(width 0.1)
		(layer "In4.Cu")
		(net 353)
	)
	(segment
		(start 198.39 154)
		(end 198.05 154.34)
		(width 0.1)
		(layer "In4.Cu")
		(net 353)
	)
	(segment
		(start 198.71 154)
		(end 198.39 154)
		(width 0.1)
		(layer "In4.Cu")
		(net 353)
	)
	(segment
		(start 198.05 155.049999)
		(end 198.500001 155.5)
		(width 0.1)
		(layer "In4.Cu")
		(net 353)
	)
	(segment
		(start 208.29 150.99)
		(end 205.955 150.99)
		(width 0.1)
		(layer "In4.Cu")
		(net 353)
	)
	(segment
		(start 199 153.4)
		(end 199 153.71)
		(width 0.1)
		(layer "In4.Cu")
		(net 353)
	)
	(segment
		(start 200.0005 155.0005)
		(end 200.5 155.5)
		(width 0.256)
		(layer "F.Cu")
		(net 354)
	)
	(via
		(at 200.5 155.5)
		(size 0.45)
		(drill 0.1)
		(layers "F.Cu" "B.Cu")
		(remove_unused_layers yes)
		(keep_end_layers yes)
		(zone_layer_connections)
		(net 354)
	)
	(via
		(at 209.416283 152.640001)
		(size 0.45)
		(drill 0.1)
		(layers "F.Cu" "B.Cu")
		(remove_unused_layers yes)
		(keep_end_layers yes)
		(zone_layer_connections)
		(net 354)
	)
	(segment
		(start 209.405 153.1505)
		(end 209.405 152.651284)
		(width 0.256)
		(layer "B.Cu")
		(net 354)
	)
	(segment
		(start 209.405 152.651284)
		(end 209.416283 152.640001)
		(width 0.256)
		(layer "B.Cu")
		(net 354)
	)
	(segment
		(start 207.52 152.42)
		(end 207.11 152.42)
		(width 0.1)
		(layer "In4.Cu")
		(net 354)
	)
	(segment
		(start 206.182402 153.347598)
		(end 206.182402 153.61925)
		(width 0.1)
		(layer "In4.Cu")
		(net 354)
	)
	(segment
		(start 201.845 155.04)
		(end 200.96 155.04)
		(width 0.1)
		(layer "In4.Cu")
		(net 354)
	)
	(segment
		(start 202.925 155.615)
		(end 202.925 155.165)
		(width 0.1)
		(layer "In4.Cu")
		(net 354)
	)
	(segment
		(start 203.61 154.94)
		(end 203.6 154.94)
		(width 0.1)
		(layer "In4.Cu")
		(net 354)
	)
	(segment
		(start 202.7 154.94)
		(end 201.945 154.94)
		(width 0.1)
		(layer "In4.Cu")
		(net 354)
	)
	(segment
		(start 200.96 155.04)
		(end 200.5 155.5)
		(width 0.1)
		(layer "In4.Cu")
		(net 354)
	)
	(segment
		(start 207.99 154.47)
		(end 207.99 154.87)
		(width 0.1)
		(layer "In4.Cu")
		(net 354)
	)
	(segment
		(start 206.59 154.66)
		(end 206.31 154.94)
		(width 0.1)
		(layer "In4.Cu")
		(net 354)
	)
	(segment
		(start 204.61 154.54)
		(end 204.61 154.74)
		(width 0.1)
		(layer "In4.Cu")
		(net 354)
	)
	(segment
		(start 206.31 154.94)
		(end 205.21 154.94)
		(width 0.1)
		(layer "In4.Cu")
		(net 354)
	)
	(segment
		(start 203.375 155.165)
		(end 203.375 155.615)
		(width 0.1)
		(layer "In4.Cu")
		(net 354)
	)
	(segment
		(start 205.01 154.74)
		(end 205.01 154.54)
		(width 0.1)
		(layer "In4.Cu")
		(net 354)
	)
	(segment
		(start 208.12 152.62)
		(end 208.12 153.166435)
		(width 0.1)
		(layer "In4.Cu")
		(net 354)
	)
	(segment
		(start 207.72 153.166435)
		(end 207.72 152.62)
		(width 0.1)
		(layer "In4.Cu")
		(net 354)
	)
	(segment
		(start 206.43 153.82)
		(end 208.24 153.82)
		(width 0.1)
		(layer "In4.Cu")
		(net 354)
	)
	(segment
		(start 207.11 152.42)
		(end 206.182402 153.347598)
		(width 0.1)
		(layer "In4.Cu")
		(net 354)
	)
	(segment
		(start 208.24 154.32)
		(end 208.14 154.32)
		(width 0.1)
		(layer "In4.Cu")
		(net 354)
	)
	(segment
		(start 208.52 153.166435)
		(end 208.52 152.62)
		(width 0.1)
		(layer "In4.Cu")
		(net 354)
	)
	(segment
		(start 208.92 152.62)
		(end 208.92 153.166435)
		(width 0.1)
		(layer "In4.Cu")
		(net 354)
	)
	(segment
		(start 201.945 154.94)
		(end 201.845 155.04)
		(width 0.1)
		(layer "In4.Cu")
		(net 354)
	)
	(segment
		(start 209.416283 152.640001)
		(end 209.196282 152.42)
		(width 0.1)
		(layer "In4.Cu")
		(net 354)
	)
	(segment
		(start 203.81 154.54)
		(end 203.81 154.74)
		(width 0.1)
		(layer "In4.Cu")
		(net 354)
	)
	(segment
		(start 207.69 154.87)
		(end 207.69 154.47)
		(width 0.1)
		(layer "In4.Cu")
		(net 354)
	)
	(segment
		(start 209.196282 152.42)
		(end 209.12 152.42)
		(width 0.1)
		(layer "In4.Cu")
		(net 354)
	)
	(segment
		(start 206.59 154.57)
		(end 206.59 154.66)
		(width 0.1)
		(layer "In4.Cu")
		(net 354)
	)
	(segment
		(start 204.21 154.74)
		(end 204.21 154.54)
		(width 0.1)
		(layer "In4.Cu")
		(net 354)
	)
	(segment
		(start 207.54 154.32)
		(end 206.84 154.32)
		(width 0.1)
		(layer "In4.Cu")
		(net 354)
	)
	(arc
		(start 208.52 152.62)
		(mid 208.461421 152.478579)
		(end 208.32 152.42)
		(width 0.1)
		(layer "In4.Cu")
		(net 354)
	)
	(arc
		(start 207.84 155.02)
		(mid 207.733934 154.976066)
		(end 207.69 154.87)
		(width 0.1)
		(layer "In4.Cu")
		(net 354)
	)
	(arc
		(start 208.24 153.82)
		(mid 208.416777 153.893223)
		(end 208.49 154.07)
		(width 0.1)
		(layer "In4.Cu")
		(net 354)
	)
	(arc
		(start 207.72 152.62)
		(mid 207.661421 152.478579)
		(end 207.52 152.42)
		(width 0.1)
		(layer "In4.Cu")
		(net 354)
	)
	(arc
		(start 204.81 154.34)
		(mid 204.668579 154.398579)
		(end 204.61 154.54)
		(width 0.1)
		(layer "In4.Cu")
		(net 354)
	)
	(arc
		(start 203.6 154.94)
		(mid 203.440901 155.005901)
		(end 203.375 155.165)
		(width 0.1)
		(layer "In4.Cu")
		(net 354)
	)
	(arc
		(start 208.49 154.07)
		(mid 208.416777 154.246777)
		(end 208.24 154.32)
		(width 0.1)
		(layer "In4.Cu")
		(net 354)
	)
	(arc
		(start 208.12 153.166435)
		(mid 208.061421 153.307856)
		(end 207.92 153.366435)
		(width 0.1)
		(layer "In4.Cu")
		(net 354)
	)
	(arc
		(start 203.15 155.84)
		(mid 202.990901 155.774099)
		(end 202.925 155.615)
		(width 0.1)
		(layer "In4.Cu")
		(net 354)
	)
	(arc
		(start 208.14 154.32)
		(mid 208.033934 154.363934)
		(end 207.99 154.47)
		(width 0.1)
		(layer "In4.Cu")
		(net 354)
	)
	(arc
		(start 204.41 154.94)
		(mid 204.268579 154.881421)
		(end 204.21 154.74)
		(width 0.1)
		(layer "In4.Cu")
		(net 354)
	)
	(arc
		(start 207.99 154.87)
		(mid 207.946066 154.976066)
		(end 207.84 155.02)
		(width 0.1)
		(layer "In4.Cu")
		(net 354)
	)
	(arc
		(start 205.01 154.54)
		(mid 204.951421 154.398579)
		(end 204.81 154.34)
		(width 0.1)
		(layer "In4.Cu")
		(net 354)
	)
	(arc
		(start 208.72 153.366435)
		(mid 208.578579 153.307856)
		(end 208.52 153.166435)
		(width 0.1)
		(layer "In4.Cu")
		(net 354)
	)
	(arc
		(start 209.12 152.42)
		(mid 208.978579 152.478579)
		(end 208.92 152.62)
		(width 0.1)
		(layer "In4.Cu")
		(net 354)
	)
	(arc
		(start 207.69 154.47)
		(mid 207.646066 154.363934)
		(end 207.54 154.32)
		(width 0.1)
		(layer "In4.Cu")
		(net 354)
	)
	(arc
		(start 203.375 155.615)
		(mid 203.309099 155.774099)
		(end 203.15 155.84)
		(width 0.1)
		(layer "In4.Cu")
		(net 354)
	)
	(arc
		(start 207.92 153.366435)
		(mid 207.778579 153.307856)
		(end 207.72 153.166435)
		(width 0.1)
		(layer "In4.Cu")
		(net 354)
	)
	(arc
		(start 204.61 154.74)
		(mid 204.551421 154.881421)
		(end 204.41 154.94)
		(width 0.1)
		(layer "In4.Cu")
		(net 354)
	)
	(arc
		(start 203.81 154.74)
		(mid 203.751421 154.881421)
		(end 203.61 154.94)
		(width 0.1)
		(layer "In4.Cu")
		(net 354)
	)
	(arc
		(start 208.32 152.42)
		(mid 208.178579 152.478579)
		(end 208.12 152.62)
		(width 0.1)
		(layer "In4.Cu")
		(net 354)
	)
	(arc
		(start 204.01 154.34)
		(mid 203.868579 154.398579)
		(end 203.81 154.54)
		(width 0.1)
		(layer "In4.Cu")
		(net 354)
	)
	(arc
		(start 205.21 154.94)
		(mid 205.068579 154.881421)
		(end 205.01 154.74)
		(width 0.1)
		(layer "In4.Cu")
		(net 354)
	)
	(arc
		(start 206.182402 153.61925)
		(mid 206.271402 153.763253)
		(end 206.43 153.82)
		(width 0.1)
		(layer "In4.Cu")
		(net 354)
	)
	(arc
		(start 208.92 153.166435)
		(mid 208.861421 153.307856)
		(end 208.72 153.366435)
		(width 0.1)
		(layer "In4.Cu")
		(net 354)
	)
	(arc
		(start 202.925 155.165)
		(mid 202.859099 155.005901)
		(end 202.7 154.94)
		(width 0.1)
		(layer "In4.Cu")
		(net 354)
	)
	(arc
		(start 206.84 154.32)
		(mid 206.663223 154.393223)
		(end 206.59 154.57)
		(width 0.1)
		(layer "In4.Cu")
		(net 354)
	)
	(arc
		(start 204.21 154.54)
		(mid 204.151421 154.398579)
		(end 204.01 154.34)
		(width 0.1)
		(layer "In4.Cu")
		(net 354)
	)
	(segment
		(start 209.9 151.896)
		(end 210.885499 151.896)
		(width 0.256)
		(layer "F.Cu")
		(net 355)
	)
	(segment
		(start 210.885499 151.896)
		(end 210.899999 151.8815)
		(width 0.256)
		(layer "F.Cu")
		(net 355)
	)
	(segment
		(start 195.0005 155.0005)
		(end 195.5 155.5)
		(width 0.256)
		(layer "F.Cu")
		(net 355)
	)
	(via
		(at 210.899999 151.8815)
		(size 0.45)
		(drill 0.1)
		(layers "F.Cu" "B.Cu")
		(remove_unused_layers yes)
		(keep_end_layers yes)
		(zone_layer_connections)
		(net 355)
	)
	(via
		(at 195.5 155.5)
		(size 0.45)
		(drill 0.1)
		(layers "F.Cu" "B.Cu")
		(remove_unused_layers yes)
		(keep_end_layers yes)
		(zone_layer_connections)
		(net 355)
	)
	(segment
		(start 211.4185 151.8815)
		(end 211.425 151.875)
		(width 0.256)
		(layer "B.Cu")
		(net 355)
	)
	(segment
		(start 210.899999 151.8815)
		(end 211.4185 151.8815)
		(width 0.256)
		(layer "B.Cu")
		(net 355)
	)
	(segment
		(start 211.69 150.74)
		(end 214.81 150.74)
		(width 0.1)
		(layer "In4.Cu")
		(net 355)
	)
	(segment
		(start 210.8 149.85)
		(end 211.69 150.74)
		(width 0.1)
		(layer "In4.Cu")
		(net 355)
	)
	(segment
		(start 198.80967 152.66)
		(end 202.57 152.66)
		(width 0.1)
		(layer "In4.Cu")
		(net 355)
	)
	(segment
		(start 214.98 150.91)
		(end 214.98 151.45)
		(width 0.1)
		(layer "In4.Cu")
		(net 355)
	)
	(segment
		(start 214.81 150.74)
		(end 214.98 150.91)
		(width 0.1)
		(layer "In4.Cu")
		(net 355)
	)
	(segment
		(start 204.86 150.37)
		(end 208.36 150.37)
		(width 0.1)
		(layer "In4.Cu")
		(net 355)
	)
	(segment
		(start 195.5 155.5)
		(end 196 155)
		(width 0.1)
		(layer "In4.Cu")
		(net 355)
	)
	(segment
		(start 198 153.75)
		(end 198 153.46967)
		(width 0.1)
		(layer "In4.Cu")
		(net 355)
	)
	(segment
		(start 198 153.46967)
		(end 198.80967 152.66)
		(width 0.1)
		(layer "In4.Cu")
		(net 355)
	)
	(segment
		(start 214.82 151.61)
		(end 211.171499 151.61)
		(width 0.1)
		(layer "In4.Cu")
		(net 355)
	)
	(segment
		(start 211.171499 151.61)
		(end 210.899999 151.8815)
		(width 0.1)
		(layer "In4.Cu")
		(net 355)
	)
	(segment
		(start 196.35 153.95)
		(end 197.8 153.95)
		(width 0.1)
		(layer "In4.Cu")
		(net 355)
	)
	(segment
		(start 196 155)
		(end 196 154.3)
		(width 0.1)
		(layer "In4.Cu")
		(net 355)
	)
	(segment
		(start 208.88 149.85)
		(end 210.8 149.85)
		(width 0.1)
		(layer "In4.Cu")
		(net 355)
	)
	(segment
		(start 196 154.3)
		(end 196.35 153.95)
		(width 0.1)
		(layer "In4.Cu")
		(net 355)
	)
	(segment
		(start 197.8 153.95)
		(end 198 153.75)
		(width 0.1)
		(layer "In4.Cu")
		(net 355)
	)
	(segment
		(start 214.98 151.45)
		(end 214.82 151.61)
		(width 0.1)
		(layer "In4.Cu")
		(net 355)
	)
	(segment
		(start 202.57 152.66)
		(end 204.86 150.37)
		(width 0.1)
		(layer "In4.Cu")
		(net 355)
	)
	(segment
		(start 208.36 150.37)
		(end 208.88 149.85)
		(width 0.1)
		(layer "In4.Cu")
		(net 355)
	)
	(segment
		(start 196.5 156.5)
		(end 196.0005 156.0005)
		(width 0.256)
		(layer "F.Cu")
		(net 356)
	)
	(via
		(at 196.5 156.5)
		(size 0.45)
		(drill 0.1)
		(layers "F.Cu" "B.Cu")
		(remove_unused_layers yes)
		(keep_end_layers yes)
		(zone_layer_connections)
		(net 356)
	)
	(segment
		(start 196.5 156.5)
		(end 197 156)
		(width 0.256)
		(layer "B.Cu")
		(net 356)
	)
	(segment
		(start 258.710999 139.526)
		(end 258.714 139.522999)
		(width 0.256)
		(layer "F.Cu")
		(net 357)
	)
	(segment
		(start 259.736 139.522999)
		(end 258.714 139.522999)
		(width 0.4)
		(layer "F.Cu")
		(net 357)
	)
	(segment
		(start 257.8 139.526)
		(end 258.710999 139.526)
		(width 0.256)
		(layer "F.Cu")
		(net 357)
	)
	(segment
		(start 197.0005 157.0005)
		(end 197.5 157.5)
		(width 0.256)
		(layer "F.Cu")
		(net 357)
	)
	(segment
		(start 259.773 135.424999)
		(end 258.751 135.424999)
		(width 0.4)
		(layer "F.Cu")
		(net 357)
	)
	(via
		(at 197.5 157.5)
		(size 0.45)
		(drill 0.1)
		(layers "F.Cu" "B.Cu")
		(remove_unused_layers yes)
		(keep_end_layers yes)
		(zone_layer_connections)
		(net 357)
	)
	(via
		(at 235.575 146.325)
		(size 0.45)
		(drill 0.1)
		(layers "F.Cu" "B.Cu")
		(remove_unused_layers yes)
		(keep_end_layers yes)
		(zone_layer_connections)
		(net 357)
	)
	(via
		(at 258.714 139.522999)
		(size 0.45)
		(drill 0.1)
		(layers "F.Cu" "B.Cu")
		(remove_unused_layers yes)
		(keep_end_layers yes)
		(zone_layer_connections)
		(net 357)
	)
	(via
		(at 258.751 135.424999)
		(size 0.45)
		(drill 0.1)
		(layers "F.Cu" "B.Cu")
		(remove_unused_layers yes)
		(keep_end_layers yes)
		(zone_layer_connections)
		(net 357)
	)
	(segment
		(start 197.489 157.5)
		(end 197.009 157.98)
		(width 0.256)
		(layer "B.Cu")
		(net 357)
	)
	(segment
		(start 197.5 157.5)
		(end 197.489 157.5)
		(width 0.256)
		(layer "B.Cu")
		(net 357)
	)
	(segment
		(start 219.2 155.1)
		(end 219.6 154.7)
		(width 0.1)
		(layer "In2.Cu")
		(net 357)
	)
	(segment
		(start 202.625 157.125)
		(end 203.5 158)
		(width 0.1)
		(layer "In2.Cu")
		(net 357)
	)
	(segment
		(start 204.925 157.825)
		(end 211.975 157.825)
		(width 0.1)
		(layer "In2.Cu")
		(net 357)
	)
	(segment
		(start 197.5 157.5)
		(end 197.875 157.125)
		(width 0.1)
		(layer "In2.Cu")
		(net 357)
	)
	(segment
		(start 211.975 157.825)
		(end 213.35 156.45)
		(width 0.1)
		(layer "In2.Cu")
		(net 357)
	)
	(segment
		(start 203.5 158)
		(end 204.75 158)
		(width 0.1)
		(layer "In2.Cu")
		(net 357)
	)
	(segment
		(start 219.6 154.7)
		(end 219.6 152)
		(width 0.1)
		(layer "In2.Cu")
		(net 357)
	)
	(segment
		(start 221.15 148.85)
		(end 222.55 147.45)
		(width 0.1)
		(layer "In2.Cu")
		(net 357)
	)
	(segment
		(start 217.022334 156.45)
		(end 218.372334 155.1)
		(width 0.1)
		(layer "In2.Cu")
		(net 357)
	)
	(segment
		(start 221.15 150.45)
		(end 221.15 148.85)
		(width 0.1)
		(layer "In2.Cu")
		(net 357)
	)
	(segment
		(start 222.55 147.45)
		(end 234.45 147.45)
		(width 0.1)
		(layer "In2.Cu")
		(net 357)
	)
	(segment
		(start 213.35 156.45)
		(end 217.022334 156.45)
		(width 0.1)
		(layer "In2.Cu")
		(net 357)
	)
	(segment
		(start 218.372334 155.1)
		(end 219.2 155.1)
		(width 0.1)
		(layer "In2.Cu")
		(net 357)
	)
	(segment
		(start 197.875 157.125)
		(end 202.625 157.125)
		(width 0.1)
		(layer "In2.Cu")
		(net 357)
	)
	(segment
		(start 204.75 158)
		(end 204.925 157.825)
		(width 0.1)
		(layer "In2.Cu")
		(net 357)
	)
	(segment
		(start 219.6 152)
		(end 221.15 150.45)
		(width 0.1)
		(layer "In2.Cu")
		(net 357)
	)
	(segment
		(start 234.45 147.45)
		(end 235.575 146.325)
		(width 0.1)
		(layer "In2.Cu")
		(net 357)
	)
	(segment
		(start 249.95 140.675)
		(end 257.561999 140.675)
		(width 0.1)
		(layer "In4.Cu")
		(net 357)
	)
	(segment
		(start 248.151 142.474)
		(end 249.95 140.675)
		(width 0.1)
		(layer "In4.Cu")
		(net 357)
	)
	(segment
		(start 258.714 135.461999)
		(end 258.751 135.424999)
		(width 0.1)
		(layer "In4.Cu")
		(net 357)
	)
	(segment
		(start 258.714 139.522999)
		(end 258.714 135.461999)
		(width 0.1)
		(layer "In4.Cu")
		(net 357)
	)
	(segment
		(start 235.575 146.325)
		(end 239.426 142.474)
		(width 0.1)
		(layer "In4.Cu")
		(net 357)
	)
	(segment
		(start 239.426 142.474)
		(end 248.151 142.474)
		(width 0.1)
		(layer "In4.Cu")
		(net 357)
	)
	(segment
		(start 257.561999 140.675)
		(end 258.714 139.522999)
		(width 0.1)
		(layer "In4.Cu")
		(net 357)
	)
	(segment
		(start 183.9995 142.9995)
		(end 183.5 142.5)
		(width 0.256)
		(layer "F.Cu")
		(net 358)
	)
	(segment
		(start 146.25 110.598)
		(end 146.25 111.75)
		(width 0.38)
		(layer "F.Cu")
		(net 358)
	)
	(via
		(at 183.5 142.5)
		(size 0.45)
		(drill 0.1)
		(layers "F.Cu" "B.Cu")
		(remove_unused_layers yes)
		(keep_end_layers yes)
		(zone_layer_connections)
		(net 358)
	)
	(via
		(at 146.25 111.75)
		(size 0.45)
		(drill 0.1)
		(layers "F.Cu" "B.Cu")
		(remove_unused_layers yes)
		(keep_end_layers yes)
		(zone_layer_connections)
		(net 358)
	)
	(segment
		(start 159.95 143)
		(end 183 143)
		(width 0.148)
		(layer "In6.Cu")
		(net 358)
	)
	(segment
		(start 146.6 127.68)
		(end 147.053882 127.68)
		(width 0.148)
		(layer "In6.Cu")
		(net 358)
	)
	(segment
		(start 148.826561 129.531534)
		(end 149.038692 129.743668)
		(width 0.148)
		(layer "In6.Cu")
		(net 358)
	)
	(segment
		(start 147.836612 130.026511)
		(end 147.836612 130.02651)
		(width 0.148)
		(layer "In6.Cu")
		(net 358)
	)
	(segment
		(start 147.836612 130.02651)
		(end 147.707081 130.15604)
		(width 0.148)
		(layer "In6.Cu")
		(net 358)
	)
	(segment
		(start 146.25 129.3)
		(end 146.505 129.555)
		(width 0.148)
		(layer "In6.Cu")
		(net 358)
	)
	(segment
		(start 148.944518 128.317563)
		(end 148.944517 128.317563)
		(width 0.148)
		(layer "In6.Cu")
		(net 358)
	)
	(segment
		(start 148.944517 128.918603)
		(end 148.82656 129.03656)
		(width 0.148)
		(layer "In6.Cu")
		(net 358)
	)
	(segment
		(start 148.944516 128.918604)
		(end 148.944517 128.918603)
		(width 0.148)
		(layer "In6.Cu")
		(net 358)
	)
	(segment
		(start 147.053882 126.98)
		(end 146.6 126.98)
		(width 0.148)
		(layer "In6.Cu")
		(net 358)
	)
	(segment
		(start 147.053882 128.38)
		(end 146.6 128.38)
		(width 0.148)
		(layer "In6.Cu")
		(net 358)
	)
	(segment
		(start 147.10604 129.555)
		(end 148.343477 128.317564)
		(width 0.148)
		(layer "In6.Cu")
		(net 358)
	)
	(segment
		(start 148.82656 129.531536)
		(end 148.826561 129.531534)
		(width 0.148)
		(layer "In6.Cu")
		(net 358)
	)
	(segment
		(start 146.25 128.73)
		(end 146.25 129.3)
		(width 0.148)
		(layer "In6.Cu")
		(net 358)
	)
	(segment
		(start 146.25 111.748)
		(end 146.25 125.93)
		(width 0.148)
		(layer "In6.Cu")
		(net 358)
	)
	(segment
		(start 146.6 126.28)
		(end 147.053882 126.28)
		(width 0.148)
		(layer "In6.Cu")
		(net 358)
	)
	(segment
		(start 148.54372 130.238642)
		(end 148.331588 130.026511)
		(width 0.148)
		(layer "In6.Cu")
		(net 358)
	)
	(segment
		(start 147.70708 130.75708)
		(end 159.95 143)
		(width 0.148)
		(layer "In6.Cu")
		(net 358)
	)
	(segment
		(start 147.70708 130.757081)
		(end 147.70708 130.75708)
		(width 0.148)
		(layer "In6.Cu")
		(net 358)
	)
	(segment
		(start 183 143)
		(end 183.5 142.5)
		(width 0.148)
		(layer "In6.Cu")
		(net 358)
	)
	(segment
		(start 147.106041 129.554999)
		(end 147.10604 129.555)
		(width 0.148)
		(layer "In6.Cu")
		(net 358)
	)
	(arc
		(start 147.403882 128.03)
		(mid 147.301369 128.277487)
		(end 147.053882 128.38)
		(width 0.148)
		(layer "In6.Cu")
		(net 358)
	)
	(arc
		(start 149.038692 129.743668)
		(mid 149.141205 129.991154)
		(end 149.038694 130.238642)
		(width 0.148)
		(layer "In6.Cu")
		(net 358)
	)
	(arc
		(start 147.707081 130.15604)
		(mid 147.582601 130.45656)
		(end 147.70708 130.757081)
		(width 0.148)
		(layer "In6.Cu")
		(net 358)
	)
	(arc
		(start 147.053882 127.68)
		(mid 147.301369 127.782513)
		(end 147.403882 128.03)
		(width 0.148)
		(layer "In6.Cu")
		(net 358)
	)
	(arc
		(start 148.343477 128.317564)
		(mid 148.643997 128.193084)
		(end 148.944518 128.317563)
		(width 0.148)
		(layer "In6.Cu")
		(net 358)
	)
	(arc
		(start 149.038694 130.238642)
		(mid 148.791206 130.341155)
		(end 148.54372 130.238642)
		(width 0.148)
		(layer "In6.Cu")
		(net 358)
	)
	(arc
		(start 146.505 129.555)
		(mid 146.805521 129.679479)
		(end 147.106041 129.554999)
		(width 0.148)
		(layer "In6.Cu")
		(net 358)
	)
	(arc
		(start 146.6 128.38)
		(mid 146.352513 128.482513)
		(end 146.25 128.73)
		(width 0.148)
		(layer "In6.Cu")
		(net 358)
	)
	(arc
		(start 146.25 127.33)
		(mid 146.352513 127.577487)
		(end 146.6 127.68)
		(width 0.148)
		(layer "In6.Cu")
		(net 358)
	)
	(arc
		(start 147.053882 126.28)
		(mid 147.301369 126.382513)
		(end 147.403882 126.63)
		(width 0.148)
		(layer "In6.Cu")
		(net 358)
	)
	(arc
		(start 146.25 125.93)
		(mid 146.352513 126.177487)
		(end 146.6 126.28)
		(width 0.148)
		(layer "In6.Cu")
		(net 358)
	)
	(arc
		(start 146.6 126.98)
		(mid 146.352513 127.082513)
		(end 146.25 127.33)
		(width 0.148)
		(layer "In6.Cu")
		(net 358)
	)
	(arc
		(start 148.944517 128.317563)
		(mid 149.068996 128.618084)
		(end 148.944516 128.918604)
		(width 0.148)
		(layer "In6.Cu")
		(net 358)
	)
	(arc
		(start 148.82656 129.03656)
		(mid 148.724048 129.284049)
		(end 148.82656 129.531536)
		(width 0.148)
		(layer "In6.Cu")
		(net 358)
	)
	(arc
		(start 147.403882 126.63)
		(mid 147.301369 126.877487)
		(end 147.053882 126.98)
		(width 0.148)
		(layer "In6.Cu")
		(net 358)
	)
	(arc
		(start 148.331588 130.026511)
		(mid 148.084099 129.923997)
		(end 147.836612 130.026511)
		(width 0.148)
		(layer "In6.Cu")
		(net 358)
	)
	(segment
		(start 144.55 110.598)
		(end 144.55 111.75)
		(width 0.38)
		(layer "F.Cu")
		(net 359)
	)
	(segment
		(start 184.9995 143.9995)
		(end 184.5 143.5)
		(width 0.256)
		(layer "F.Cu")
		(net 359)
	)
	(via
		(at 144.55 111.75)
		(size 0.45)
		(drill 0.1)
		(layers "F.Cu" "B.Cu")
		(remove_unused_layers yes)
		(keep_end_layers yes)
		(zone_layer_connections)
		(net 359)
	)
	(via
		(at 184.5 143.5)
		(size 0.45)
		(drill 0.1)
		(layers "F.Cu" "B.Cu")
		(remove_unused_layers yes)
		(keep_end_layers yes)
		(zone_layer_connections)
		(net 359)
	)
	(segment
		(start 143.110881 121.685881)
		(end 143.110882 121.685881)
		(width 0.148)
		(layer "In6.Cu")
		(net 359)
	)
	(segment
		(start 144.55 111.748)
		(end 142.675 113.623)
		(width 0.148)
		(layer "In6.Cu")
		(net 359)
	)
	(segment
		(start 143.110882 125.185881)
		(end 143.110881 125.185881)
		(width 0.148)
		(layer "In6.Cu")
		(net 359)
	)
	(segment
		(start 183.8 145)
		(end 184 144.8)
		(width 0.148)
		(layer "In6.Cu")
		(net 359)
	)
	(segment
		(start 142.675 118.621748)
		(end 142.675 121.25)
		(width 0.148)
		(layer "In6.Cu")
		(net 359)
	)
	(segment
		(start 158.375 145)
		(end 183.8 145)
		(width 0.148)
		(layer "In6.Cu")
		(net 359)
	)
	(segment
		(start 142.675 113.623)
		(end 142.675 114.25)
		(width 0.148)
		(layer "In6.Cu")
		(net 359)
	)
	(segment
		(start 184 144.3)
		(end 184.5 143.8)
		(width 0.148)
		(layer "In6.Cu")
		(net 359)
	)
	(segment
		(start 142.675 129.3)
		(end 158.375 145)
		(width 0.148)
		(layer "In6.Cu")
		(net 359)
	)
	(segment
		(start 143.546763 122.121762)
		(end 143.546763 124.75)
		(width 0.148)
		(layer "In6.Cu")
		(net 359)
	)
	(segment
		(start 143.110874 114.685874)
		(end 143.110875 114.685874)
		(width 0.148)
		(layer "In6.Cu")
		(net 359)
	)
	(segment
		(start 142.675 128.25)
		(end 142.675 129.3)
		(width 0.148)
		(layer "In6.Cu")
		(net 359)
	)
	(segment
		(start 143.110875 118.185874)
		(end 143.110874 118.185874)
		(width 0.148)
		(layer "In6.Cu")
		(net 359)
	)
	(segment
		(start 142.675 125.621762)
		(end 142.675 128.25)
		(width 0.148)
		(layer "In6.Cu")
		(net 359)
	)
	(segment
		(start 184 144.8)
		(end 184 144.3)
		(width 0.148)
		(layer "In6.Cu")
		(net 359)
	)
	(segment
		(start 184.5 143.8)
		(end 184.5 143.5)
		(width 0.148)
		(layer "In6.Cu")
		(net 359)
	)
	(segment
		(start 143.546749 115.121748)
		(end 143.546749 117.75)
		(width 0.148)
		(layer "In6.Cu")
		(net 359)
	)
	(arc
		(start 143.546749 117.75)
		(mid 143.419084 118.058209)
		(end 143.110875 118.185874)
		(width 0.148)
		(layer "In6.Cu")
		(net 359)
	)
	(arc
		(start 142.675 114.25)
		(mid 142.802665 114.558209)
		(end 143.110874 114.685874)
		(width 0.148)
		(layer "In6.Cu")
		(net 359)
	)
	(arc
		(start 143.546763 124.75)
		(mid 143.419096 125.058214)
		(end 143.110882 125.185881)
		(width 0.148)
		(layer "In6.Cu")
		(net 359)
	)
	(arc
		(start 143.110881 125.185881)
		(mid 142.802667 125.313548)
		(end 142.675 125.621762)
		(width 0.148)
		(layer "In6.Cu")
		(net 359)
	)
	(arc
		(start 143.110874 118.185874)
		(mid 142.802665 118.313539)
		(end 142.675 118.621748)
		(width 0.148)
		(layer "In6.Cu")
		(net 359)
	)
	(arc
		(start 142.675 121.25)
		(mid 142.802667 121.558214)
		(end 143.110881 121.685881)
		(width 0.148)
		(layer "In6.Cu")
		(net 359)
	)
	(arc
		(start 143.110875 114.685874)
		(mid 143.419084 114.813539)
		(end 143.546749 115.121748)
		(width 0.148)
		(layer "In6.Cu")
		(net 359)
	)
	(arc
		(start 143.110882 121.685881)
		(mid 143.419096 121.813548)
		(end 143.546763 122.121762)
		(width 0.148)
		(layer "In6.Cu")
		(net 359)
	)
	(segment
		(start 142.85 110.598)
		(end 142.85 111.75)
		(width 0.38)
		(layer "F.Cu")
		(net 360)
	)
	(segment
		(start 182.9995 141.9995)
		(end 182.5 141.5)
		(width 0.256)
		(layer "F.Cu")
		(net 360)
	)
	(via
		(at 182.5 141.5)
		(size 0.45)
		(drill 0.1)
		(layers "F.Cu" "B.Cu")
		(remove_unused_layers yes)
		(keep_end_layers yes)
		(zone_layer_connections)
		(net 360)
	)
	(via
		(at 142.85 111.75)
		(size 0.45)
		(drill 0.1)
		(layers "F.Cu" "B.Cu")
		(remove_unused_layers yes)
		(keep_end_layers yes)
		(zone_layer_connections)
		(net 360)
	)
	(segment
		(start 143.76 112.42)
		(end 146.36 115.02)
		(width 0.148)
		(layer "In4.Cu")
		(net 360)
	)
	(segment
		(start 142.85 111.75)
		(end 142.85 111.22)
		(width 0.148)
		(layer "In4.Cu")
		(net 360)
	)
	(segment
		(start 143.76 111.12)
		(end 143.76 112.42)
		(width 0.148)
		(layer "In4.Cu")
		(net 360)
	)
	(segment
		(start 153.84 114.62)
		(end 153.84 114.61228)
		(width 0.148)
		(layer "In4.Cu")
		(net 360)
	)
	(segment
		(start 152.24 114.62)
		(end 152.24 114.612303)
		(width 0.148)
		(layer "In4.Cu")
		(net 360)
	)
	(segment
		(start 149.84 114.61228)
		(end 149.84 114.62)
		(width 0.148)
		(layer "In4.Cu")
		(net 360)
	)
	(segment
		(start 151.44 114.61228)
		(end 151.44 114.62)
		(width 0.148)
		(layer "In4.Cu")
		(net 360)
	)
	(segment
		(start 183.3 141.05)
		(end 182.85 141.5)
		(width 0.148)
		(layer "In4.Cu")
		(net 360)
	)
	(segment
		(start 185 126.13)
		(end 185 140.8)
		(width 0.148)
		(layer "In4.Cu")
		(net 360)
	)
	(segment
		(start 147.44 114.62)
		(end 147.44 114.61228)
		(width 0.148)
		(layer "In4.Cu")
		(net 360)
	)
	(segment
		(start 149.04 114.62)
		(end 149.04 114.61228)
		(width 0.148)
		(layer "In4.Cu")
		(net 360)
	)
	(segment
		(start 148.24 114.61228)
		(end 148.24 114.62)
		(width 0.148)
		(layer "In4.Cu")
		(net 360)
	)
	(segment
		(start 142.85 111.22)
		(end 143.235 110.835)
		(width 0.148)
		(layer "In4.Cu")
		(net 360)
	)
	(segment
		(start 173.37 114.5)
		(end 185 126.13)
		(width 0.148)
		(layer "In4.Cu")
		(net 360)
	)
	(segment
		(start 150.64 114.62)
		(end 150.64 114.61228)
		(width 0.148)
		(layer "In4.Cu")
		(net 360)
	)
	(segment
		(start 153.04 114.612303)
		(end 153.04 114.62)
		(width 0.148)
		(layer "In4.Cu")
		(net 360)
	)
	(segment
		(start 143.475 110.835)
		(end 143.76 111.12)
		(width 0.148)
		(layer "In4.Cu")
		(net 360)
	)
	(segment
		(start 155.04 115.02)
		(end 155.89 115.02)
		(width 0.148)
		(layer "In4.Cu")
		(net 360)
	)
	(segment
		(start 154.64 114.61228)
		(end 154.64 114.62)
		(width 0.148)
		(layer "In4.Cu")
		(net 360)
	)
	(segment
		(start 146.36 115.02)
		(end 147.04 115.02)
		(width 0.148)
		(layer "In4.Cu")
		(net 360)
	)
	(segment
		(start 185 140.8)
		(end 184.75 141.05)
		(width 0.148)
		(layer "In4.Cu")
		(net 360)
	)
	(segment
		(start 182.85 141.5)
		(end 182.5 141.5)
		(width 0.148)
		(layer "In4.Cu")
		(net 360)
	)
	(segment
		(start 143.235 110.835)
		(end 143.475 110.835)
		(width 0.148)
		(layer "In4.Cu")
		(net 360)
	)
	(segment
		(start 155.89 115.02)
		(end 156.08 115.02)
		(width 0.148)
		(layer "In4.Cu")
		(net 360)
	)
	(segment
		(start 156.6 114.5)
		(end 173.37 114.5)
		(width 0.148)
		(layer "In4.Cu")
		(net 360)
	)
	(segment
		(start 156.08 115.02)
		(end 156.6 114.5)
		(width 0.148)
		(layer "In4.Cu")
		(net 360)
	)
	(segment
		(start 184.75 141.05)
		(end 183.3 141.05)
		(width 0.148)
		(layer "In4.Cu")
		(net 360)
	)
	(arc
		(start 152.64 114.212303)
		(mid 152.922843 114.32946)
		(end 153.04 114.612303)
		(width 0.148)
		(layer "In4.Cu")
		(net 360)
	)
	(arc
		(start 152.24 114.612303)
		(mid 152.357157 114.32946)
		(end 152.64 114.212303)
		(width 0.148)
		(layer "In4.Cu")
		(net 360)
	)
	(arc
		(start 150.64 114.61228)
		(mid 150.757157 114.329437)
		(end 151.04 114.21228)
		(width 0.148)
		(layer "In4.Cu")
		(net 360)
	)
	(arc
		(start 154.64 114.62)
		(mid 154.757157 114.902843)
		(end 155.04 115.02)
		(width 0.148)
		(layer "In4.Cu")
		(net 360)
	)
	(arc
		(start 149.84 114.62)
		(mid 149.957157 114.902843)
		(end 150.24 115.02)
		(width 0.148)
		(layer "In4.Cu")
		(net 360)
	)
	(arc
		(start 150.24 115.02)
		(mid 150.522843 114.902843)
		(end 150.64 114.62)
		(width 0.148)
		(layer "In4.Cu")
		(net 360)
	)
	(arc
		(start 149.44 114.21228)
		(mid 149.722843 114.329437)
		(end 149.84 114.61228)
		(width 0.148)
		(layer "In4.Cu")
		(net 360)
	)
	(arc
		(start 147.84 114.21228)
		(mid 148.122843 114.329437)
		(end 148.24 114.61228)
		(width 0.148)
		(layer "In4.Cu")
		(net 360)
	)
	(arc
		(start 147.44 114.61228)
		(mid 147.557157 114.329437)
		(end 147.84 114.21228)
		(width 0.148)
		(layer "In4.Cu")
		(net 360)
	)
	(arc
		(start 148.64 115.02)
		(mid 148.922843 114.902843)
		(end 149.04 114.62)
		(width 0.148)
		(layer "In4.Cu")
		(net 360)
	)
	(arc
		(start 148.24 114.62)
		(mid 148.357157 114.902843)
		(end 148.64 115.02)
		(width 0.148)
		(layer "In4.Cu")
		(net 360)
	)
	(arc
		(start 153.44 115.02)
		(mid 153.722843 114.902843)
		(end 153.84 114.62)
		(width 0.148)
		(layer "In4.Cu")
		(net 360)
	)
	(arc
		(start 151.44 114.62)
		(mid 151.557157 114.902843)
		(end 151.84 115.02)
		(width 0.148)
		(layer "In4.Cu")
		(net 360)
	)
	(arc
		(start 154.24 114.21228)
		(mid 154.522843 114.329437)
		(end 154.64 114.61228)
		(width 0.148)
		(layer "In4.Cu")
		(net 360)
	)
	(arc
		(start 151.84 115.02)
		(mid 152.122843 114.902843)
		(end 152.24 114.62)
		(width 0.148)
		(layer "In4.Cu")
		(net 360)
	)
	(arc
		(start 153.04 114.62)
		(mid 153.157157 114.902843)
		(end 153.44 115.02)
		(width 0.148)
		(layer "In4.Cu")
		(net 360)
	)
	(arc
		(start 149.04 114.61228)
		(mid 149.157157 114.329437)
		(end 149.44 114.21228)
		(width 0.148)
		(layer "In4.Cu")
		(net 360)
	)
	(arc
		(start 147.04 115.02)
		(mid 147.322843 114.902843)
		(end 147.44 114.62)
		(width 0.148)
		(layer "In4.Cu")
		(net 360)
	)
	(arc
		(start 151.04 114.21228)
		(mid 151.322843 114.329437)
		(end 151.44 114.61228)
		(width 0.148)
		(layer "In4.Cu")
		(net 360)
	)
	(arc
		(start 153.84 114.61228)
		(mid 153.957157 114.329437)
		(end 154.24 114.21228)
		(width 0.148)
		(layer "In4.Cu")
		(net 360)
	)
	(segment
		(start 108 142.25)
		(end 108 141.988499)
		(width 0.201)
		(layer "F.Cu")
		(net 363)
	)
	(segment
		(start 108 141.988499)
		(end 108.339499 141.649)
		(width 0.201)
		(layer "F.Cu")
		(net 363)
	)
	(segment
		(start 108.439499 142.751)
		(end 107.971 142.751)
		(width 0.201)
		(layer "F.Cu")
		(net 363)
	)
	(segment
		(start 107.735 142.515)
		(end 108 142.25)
		(width 0.201)
		(layer "F.Cu")
		(net 363)
	)
	(segment
		(start 109.211499 142.751)
		(end 108.439499 142.751)
		(width 0.15)
		(layer "F.Cu")
		(net 363)
	)
	(segment
		(start 106.325 142.515)
		(end 107.735 142.515)
		(width 0.201)
		(layer "F.Cu")
		(net 363)
	)
	(segment
		(start 107.971 142.751)
		(end 107.735 142.515)
		(width 0.201)
		(layer "F.Cu")
		(net 363)
	)
	(segment
		(start 137.159499 163.084)
		(end 137.746 163.084)
		(width 0.2)
		(layer "F.Cu")
		(net 364)
	)
	(segment
		(start 110.056501 144.249)
		(end 109.211499 144.249)
		(width 0.201)
		(layer "F.Cu")
		(net 364)
	)
	(segment
		(start 128.415 159.322847)
		(end 132.091654 162.999501)
		(width 0.2)
		(layer "F.Cu")
		(net 364)
	)
	(segment
		(start 122.641655 143.915001)
		(end 128.415 149.688346)
		(width 0.2)
		(layer "F.Cu")
		(net 364)
	)
	(segment
		(start 107.060499 144.513)
		(end 106.325 144.513)
		(width 0.201)
		(layer "F.Cu")
		(net 364)
	)
	(segment
		(start 132.091654 162.999501)
		(end 137.075 162.999501)
		(width 0.2)
		(layer "F.Cu")
		(net 364)
	)
	(segment
		(start 109.211499 144.249)
		(end 108.439499 144.249)
		(width 0.201)
		(layer "F.Cu")
		(net 364)
	)
	(segment
		(start 110.056501 144.249)
		(end 110.3905 143.915001)
		(width 0.201)
		(layer "F.Cu")
		(net 364)
	)
	(segment
		(start 108.439499 144.249)
		(end 107.324499 144.249)
		(width 0.201)
		(layer "F.Cu")
		(net 364)
	)
	(segment
		(start 105.590499 143.515)
		(end 105.424499 143.349)
		(width 0.256)
		(layer "F.Cu")
		(net 364)
	)
	(segment
		(start 110.3905 143.915001)
		(end 122.641655 143.915001)
		(width 0.2)
		(layer "F.Cu")
		(net 364)
	)
	(segment
		(start 137.075 162.999501)
		(end 137.159499 163.084)
		(width 0.2)
		(layer "F.Cu")
		(net 364)
	)
	(segment
		(start 105.402601 144.896813)
		(end 105.786414 144.513)
		(width 0.201)
		(layer "F.Cu")
		(net 364)
	)
	(segment
		(start 105.786414 144.513)
		(end 106.325 144.513)
		(width 0.201)
		(layer "F.Cu")
		(net 364)
	)
	(segment
		(start 107.324499 144.249)
		(end 107.060499 144.513)
		(width 0.201)
		(layer "F.Cu")
		(net 364)
	)
	(segment
		(start 106.325 143.515)
		(end 105.590499 143.515)
		(width 0.256)
		(layer "F.Cu")
		(net 364)
	)
	(segment
		(start 128.415 149.688346)
		(end 128.415 159.322847)
		(width 0.2)
		(layer "F.Cu")
		(net 364)
	)
	(via
		(at 105.424499 143.349)
		(size 0.45)
		(drill 0.1)
		(layers "F.Cu" "B.Cu")
		(remove_unused_layers yes)
		(keep_end_layers yes)
		(zone_layer_connections)
		(net 364)
	)
	(via
		(at 105.402601 144.896813)
		(size 0.45)
		(drill 0.1)
		(layers "F.Cu" "B.Cu")
		(remove_unused_layers yes)
		(keep_end_layers yes)
		(zone_layer_connections)
		(net 364)
	)
	(segment
		(start 104.971499 144.465711)
		(end 105.402601 144.896813)
		(width 0.114)
		(layer "In2.Cu")
		(net 364)
	)
	(segment
		(start 105.424499 143.349)
		(end 104.971499 143.802)
		(width 0.114)
		(layer "In2.Cu")
		(net 364)
	)
	(segment
		(start 104.971499 143.802)
		(end 104.971499 144.465711)
		(width 0.114)
		(layer "In2.Cu")
		(net 364)
	)
	(segment
		(start 132.228344 162.669499)
		(end 137.044998 162.669499)
		(width 0.2)
		(layer "F.Cu")
		(net 365)
	)
	(segment
		(start 110.0655 143.251)
		(end 109.211499 143.251)
		(width 0.201)
		(layer "F.Cu")
		(net 365)
	)
	(segment
		(start 107.360499 143.251)
		(end 107.124499 143.015)
		(width 0.201)
		(layer "F.Cu")
		(net 365)
	)
	(segment
		(start 107.124499 143.015)
		(end 106.325 143.015)
		(width 0.201)
		(layer "F.Cu")
		(net 365)
	)
	(segment
		(start 105.766164 143.013)
		(end 106.325 143.013)
		(width 0.201)
		(layer "F.Cu")
		(net 365)
	)
	(segment
		(start 128.745 149.551654)
		(end 128.745 159.186155)
		(width 0.2)
		(layer "F.Cu")
		(net 365)
	)
	(segment
		(start 106.325 144.013)
		(end 105.590498 144.013)
		(width 0.256)
		(layer "F.Cu")
		(net 365)
	)
	(segment
		(start 110.0655 143.251)
		(end 110.399499 143.584999)
		(width 0.201)
		(layer "F.Cu")
		(net 365)
	)
	(segment
		(start 137.044998 162.669499)
		(end 137.129497 162.585)
		(width 0.2)
		(layer "F.Cu")
		(net 365)
	)
	(segment
		(start 108.439499 143.251)
		(end 109.211499 143.251)
		(width 0.201)
		(layer "F.Cu")
		(net 365)
	)
	(segment
		(start 108.439499 143.251)
		(end 107.360499 143.251)
		(width 0.201)
		(layer "F.Cu")
		(net 365)
	)
	(segment
		(start 105.405032 142.651868)
		(end 105.766164 143.013)
		(width 0.201)
		(layer "F.Cu")
		(net 365)
	)
	(segment
		(start 105.590498 144.013)
		(end 105.424499 144.179)
		(width 0.256)
		(layer "F.Cu")
		(net 365)
	)
	(segment
		(start 137.129497 162.585)
		(end 137.746 162.585)
		(width 0.2)
		(layer "F.Cu")
		(net 365)
	)
	(segment
		(start 122.778345 143.584999)
		(end 128.745 149.551654)
		(width 0.2)
		(layer "F.Cu")
		(net 365)
	)
	(segment
		(start 128.745 159.186155)
		(end 132.228344 162.669499)
		(width 0.2)
		(layer "F.Cu")
		(net 365)
	)
	(segment
		(start 110.399499 143.584999)
		(end 122.778345 143.584999)
		(width 0.2)
		(layer "F.Cu")
		(net 365)
	)
	(via
		(at 105.405032 142.651868)
		(size 0.45)
		(drill 0.1)
		(layers "F.Cu" "B.Cu")
		(remove_unused_layers yes)
		(keep_end_layers yes)
		(zone_layer_connections)
		(net 365)
	)
	(via
		(at 105.424499 144.179)
		(size 0.45)
		(drill 0.1)
		(layers "F.Cu" "B.Cu")
		(remove_unused_layers yes)
		(keep_end_layers yes)
		(zone_layer_connections)
		(net 365)
	)
	(segment
		(start 105.405032 142.651868)
		(end 105.849999 143.096835)
		(width 0.114)
		(layer "In2.Cu")
		(net 365)
	)
	(segment
		(start 105.849999 143.7535)
		(end 105.424499 144.179)
		(width 0.114)
		(layer "In2.Cu")
		(net 365)
	)
	(segment
		(start 105.849999 143.096835)
		(end 105.849999 143.7535)
		(width 0.114)
		(layer "In2.Cu")
		(net 365)
	)
	(segment
		(start 107.904499 145.095501)
		(end 108.251 144.749)
		(width 0.201)
		(layer "F.Cu")
		(net 366)
	)
	(segment
		(start 108.057499 145.514)
		(end 108.339499 145.796)
		(width 0.201)
		(layer "F.Cu")
		(net 366)
	)
	(segment
		(start 109.211499 144.749)
		(end 108.439499 144.749)
		(width 0.15)
		(layer "F.Cu")
		(net 366)
	)
	(segment
		(start 107.904499 145.514)
		(end 108.057499 145.514)
		(width 0.201)
		(layer "F.Cu")
		(net 366)
	)
	(segment
		(start 108.251 144.749)
		(end 108.439499 144.749)
		(width 0.201)
		(layer "F.Cu")
		(net 366)
	)
	(segment
		(start 107.904499 145.514)
		(end 106.325 145.514)
		(width 0.201)
		(layer "F.Cu")
		(net 366)
	)
	(segment
		(start 107.904499 145.514)
		(end 107.904499 145.095501)
		(width 0.201)
		(layer "F.Cu")
		(net 366)
	)
	(segment
		(start 125.399 120.652)
		(end 128.399 120.652)
		(width 0.256)
		(layer "B.Cu")
		(net 367)
	)
	(segment
		(start 253.024 185.199)
		(end 252.585 185.199)
		(width 0.201)
		(layer "F.Cu")
		(net 368)
	)
	(segment
		(start 254.025 186.475)
		(end 253.35 185.8)
		(width 0.201)
		(layer "F.Cu")
		(net 368)
	)
	(segment
		(start 253.35 185.525)
		(end 253.024 185.199)
		(width 0.201)
		(layer "F.Cu")
		(net 368)
	)
	(segment
		(start 251.813 185.199)
		(end 252.585 185.199)
		(width 0.177)
		(layer "F.Cu")
		(net 368)
	)
	(segment
		(start 250.211155 184.836188)
		(end 250.124967 184.75)
		(width 0.182)
		(layer "F.Cu")
		(net 368)
	)
	(segment
		(start 253.35 185.8)
		(end 253.35 185.525)
		(width 0.201)
		(layer "F.Cu")
		(net 368)
	)
	(segment
		(start 250.211155 184.836188)
		(end 250.573967 185.199)
		(width 0.182)
		(layer "F.Cu")
		(net 368)
	)
	(segment
		(start 254.525 186.475)
		(end 254.025 186.475)
		(width 0.201)
		(layer "F.Cu")
		(net 368)
	)
	(segment
		(start 250.573967 185.199)
		(end 251.813 185.199)
		(width 0.182)
		(layer "F.Cu")
		(net 368)
	)
	(segment
		(start 252.605 185.179)
		(end 252.585 185.199)
		(width 0.182)
		(layer "F.Cu")
		(net 368)
	)
	(segment
		(start 250.124967 184.75)
		(end 248.629 184.75)
		(width 0.182)
		(layer "F.Cu")
		(net 368)
	)
	(via
		(at 250.211155 184.836188)
		(size 0.45)
		(drill 0.1)
		(layers "F.Cu" "B.Cu")
		(remove_unused_layers yes)
		(keep_end_layers yes)
		(zone_layer_connections)
		(net 368)
	)
	(segment
		(start 250.211155 184.836188)
		(end 250.573967 185.199)
		(width 0.182)
		(layer "B.Cu")
		(net 368)
	)
	(segment
		(start 250.573967 185.199)
		(end 251.611 185.199)
		(width 0.182)
		(layer "B.Cu")
		(net 368)
	)
	(segment
		(start 251.611 185.199)
		(end 251.72 185.308)
		(width 0.182)
		(layer "B.Cu")
		(net 368)
	)
	(segment
		(start 249.902 185.251)
		(end 250.848 186.197)
		(width 0.182)
		(layer "F.Cu")
		(net 369)
	)
	(segment
		(start 249.85 185.251)
		(end 248.629 185.251)
		(width 0.182)
		(layer "F.Cu")
		(net 369)
	)
	(segment
		(start 250.848 186.197)
		(end 251.813 186.197)
		(width 0.182)
		(layer "F.Cu")
		(net 369)
	)
	(segment
		(start 255.85 186.85)
		(end 255.85 185.85)
		(width 0.182)
		(layer "F.Cu")
		(net 369)
	)
	(segment
		(start 253.7 187.25)
		(end 255.45 187.25)
		(width 0.182)
		(layer "F.Cu")
		(net 369)
	)
	(segment
		(start 255.475 185.475)
		(end 254.525 185.475)
		(width 0.182)
		(layer "F.Cu")
		(net 369)
	)
	(segment
		(start 252.585 186.197)
		(end 251.813 186.197)
		(width 0.182)
		(layer "F.Cu")
		(net 369)
	)
	(segment
		(start 253.4 186.55)
		(end 253.4 186.95)
		(width 0.182)
		(layer "F.Cu")
		(net 369)
	)
	(segment
		(start 253.4 186.95)
		(end 253.7 187.25)
		(width 0.182)
		(layer "F.Cu")
		(net 369)
	)
	(segment
		(start 255.45 187.25)
		(end 255.85 186.85)
		(width 0.182)
		(layer "F.Cu")
		(net 369)
	)
	(segment
		(start 249.85 185.251)
		(end 249.902 185.251)
		(width 0.182)
		(layer "F.Cu")
		(net 369)
	)
	(segment
		(start 255.85 185.85)
		(end 255.475 185.475)
		(width 0.182)
		(layer "F.Cu")
		(net 369)
	)
	(segment
		(start 252.585 186.197)
		(end 253.047 186.197)
		(width 0.182)
		(layer "F.Cu")
		(net 369)
	)
	(segment
		(start 253.047 186.197)
		(end 253.4 186.55)
		(width 0.182)
		(layer "F.Cu")
		(net 369)
	)
	(via
		(at 249.85 185.251)
		(size 0.45)
		(drill 0.1)
		(layers "F.Cu" "B.Cu")
		(remove_unused_layers yes)
		(keep_end_layers yes)
		(zone_layer_connections)
		(net 369)
	)
	(segment
		(start 249.902 185.251)
		(end 251 186.349)
		(width 0.182)
		(layer "B.Cu")
		(net 369)
	)
	(segment
		(start 251 186.349)
		(end 251.72 186.349)
		(width 0.182)
		(layer "B.Cu")
		(net 369)
	)
	(segment
		(start 249.85 185.251)
		(end 249.902 185.251)
		(width 0.182)
		(layer "B.Cu")
		(net 369)
	)
	(segment
		(start 125.399 102.638)
		(end 128.399 102.638)
		(width 0.256)
		(layer "B.Cu")
		(net 370)
	)
	(segment
		(start 138.399 102.658)
		(end 168.399 102.658)
		(width 0.256)
		(layer "B.Cu")
		(net 371)
	)
	(segment
		(start 139.809499 177.964)
		(end 140.824499 177.964)
		(width 0.201)
		(layer "F.Cu")
		(net 372)
	)
	(segment
		(start 139.020499 179.148)
		(end 139.020499 178.453)
		(width 0.201)
		(layer "F.Cu")
		(net 372)
	)
	(segment
		(start 120.113 138.603)
		(end 120.56 139.05)
		(width 0.4)
		(layer "F.Cu")
		(net 372)
	)
	(segment
		(start 139.449499 157.874)
		(end 139.434 157.889499)
		(width 0.15)
		(layer "F.Cu")
		(net 372)
	)
	(segment
		(start 120.082 138.603)
		(end 120.113 138.603)
		(width 0.4)
		(layer "F.Cu")
		(net 372)
	)
	(segment
		(start 139.434 157.889499)
		(end 139.434 158.897)
		(width 0.15)
		(layer "F.Cu")
		(net 372)
	)
	(segment
		(start 139.020499 178.453)
		(end 139.509499 177.964)
		(width 0.201)
		(layer "F.Cu")
		(net 372)
	)
	(segment
		(start 139.509499 177.964)
		(end 139.809499 177.964)
		(width 0.201)
		(layer "F.Cu")
		(net 372)
	)
	(via
		(at 120.56 139.05)
		(size 0.45)
		(drill 0.1)
		(layers "F.Cu" "B.Cu")
		(remove_unused_layers yes)
		(keep_end_layers yes)
		(zone_layer_connections)
		(net 372)
	)
	(via
		(at 139.809499 177.964)
		(size 0.45)
		(drill 0.1)
		(layers "F.Cu" "B.Cu")
		(remove_unused_layers yes)
		(keep_end_layers yes)
		(zone_layer_connections)
		(net 372)
	)
	(via
		(at 139.449499 157.874)
		(size 0.45)
		(drill 0.1)
		(layers "F.Cu" "B.Cu")
		(remove_unused_layers yes)
		(keep_end_layers yes)
		(zone_layer_connections)
		(net 372)
	)
	(segment
		(start 120.56 139.05)
		(end 120.56 141.05)
		(width 0.177)
		(layer "B.Cu")
		(net 372)
	)
	(segment
		(start 139.32 157.744501)
		(end 139.449499 157.874)
		(width 0.177)
		(layer "B.Cu")
		(net 372)
	)
	(segment
		(start 120.56 141.05)
		(end 136.48 156.97)
		(width 0.177)
		(layer "B.Cu")
		(net 372)
	)
	(segment
		(start 136.48 156.97)
		(end 138.72 156.97)
		(width 0.177)
		(layer "B.Cu")
		(net 372)
	)
	(segment
		(start 138.72 156.97)
		(end 139.32 157.57)
		(width 0.177)
		(layer "B.Cu")
		(net 372)
	)
	(segment
		(start 139.32 157.57)
		(end 139.32 157.744501)
		(width 0.177)
		(layer "B.Cu")
		(net 372)
	)
	(segment
		(start 139.809499 172.834)
		(end 139.809499 177.964)
		(width 0.15)
		(layer "In2.Cu")
		(net 372)
	)
	(segment
		(start 139.449499 172.474)
		(end 139.809499 172.834)
		(width 0.15)
		(layer "In2.Cu")
		(net 372)
	)
	(segment
		(start 139.449499 157.874)
		(end 139.449499 172.474)
		(width 0.15)
		(layer "In2.Cu")
		(net 372)
	)
	(segment
		(start 148.364499 163.809)
		(end 149.074499 163.809)
		(width 0.15)
		(layer "F.Cu")
		(net 373)
	)
	(segment
		(start 149.074499 163.809)
		(end 149.414499 163.469)
		(width 0.15)
		(layer "F.Cu")
		(net 373)
	)
	(segment
		(start 150.384499 163.469)
		(end 150.934499 163.469)
		(width 0.15)
		(layer "F.Cu")
		(net 374)
	)
	(segment
		(start 181.9995 157.0005)
		(end 181.5 157.5)
		(width 0.256)
		(layer "F.Cu")
		(net 374)
	)
	(via
		(at 150.934499 163.469)
		(size 0.45)
		(drill 0.1)
		(layers "F.Cu" "B.Cu")
		(remove_unused_layers yes)
		(keep_end_layers yes)
		(zone_layer_connections)
		(net 374)
	)
	(via
		(at 181.5 157.5)
		(size 0.45)
		(drill 0.1)
		(layers "F.Cu" "B.Cu")
		(remove_unused_layers yes)
		(keep_end_layers yes)
		(zone_layer_connections)
		(net 374)
	)
	(segment
		(start 152.05 164.1)
		(end 151.419 163.469)
		(width 0.1)
		(layer "In6.Cu")
		(net 374)
	)
	(segment
		(start 155.017157 164.1)
		(end 152.05 164.1)
		(width 0.1)
		(layer "In6.Cu")
		(net 374)
	)
	(segment
		(start 151.419 163.469)
		(end 150.934499 163.469)
		(width 0.1)
		(layer "In6.Cu")
		(net 374)
	)
	(segment
		(start 164.65 158)
		(end 159.275 163.375)
		(width 0.1)
		(layer "In6.Cu")
		(net 374)
	)
	(segment
		(start 159.275 163.375)
		(end 155.742157 163.375)
		(width 0.1)
		(layer "In6.Cu")
		(net 374)
	)
	(segment
		(start 181 158)
		(end 164.65 158)
		(width 0.1)
		(layer "In6.Cu")
		(net 374)
	)
	(segment
		(start 181.5 157.5)
		(end 181 158)
		(width 0.1)
		(layer "In6.Cu")
		(net 374)
	)
	(segment
		(start 155.742157 163.375)
		(end 155.017157 164.1)
		(width 0.1)
		(layer "In6.Cu")
		(net 374)
	)
	(segment
		(start 149.079499 164.159)
		(end 149.414499 164.494)
		(width 0.15)
		(layer "F.Cu")
		(net 375)
	)
	(segment
		(start 148.364499 164.159)
		(end 149.079499 164.159)
		(width 0.15)
		(layer "F.Cu")
		(net 375)
	)
	(segment
		(start 150.384499 164.494)
		(end 150.759499 164.494)
		(width 0.15)
		(layer "F.Cu")
		(net 376)
	)
	(segment
		(start 150.759499 164.494)
		(end 151.079665 164.173834)
		(width 0.15)
		(layer "F.Cu")
		(net 376)
	)
	(segment
		(start 181.9995 156.0005)
		(end 181.5 156.5)
		(width 0.256)
		(layer "F.Cu")
		(net 376)
	)
	(via
		(at 181.5 156.5)
		(size 0.45)
		(drill 0.1)
		(layers "F.Cu" "B.Cu")
		(remove_unused_layers yes)
		(keep_end_layers yes)
		(zone_layer_connections)
		(net 376)
	)
	(via
		(at 151.079665 164.173834)
		(size 0.45)
		(drill 0.1)
		(layers "F.Cu" "B.Cu")
		(remove_unused_layers yes)
		(keep_end_layers yes)
		(zone_layer_connections)
		(net 376)
	)
	(segment
		(start 181.5 156.5)
		(end 181.875 156.875)
		(width 0.1)
		(layer "In6.Cu")
		(net 376)
	)
	(segment
		(start 164.325 160.19533)
		(end 159.825331 164.694999)
		(width 0.1)
		(layer "In6.Cu")
		(net 376)
	)
	(segment
		(start 151.60083 164.694999)
		(end 151.079665 164.173834)
		(width 0.1)
		(layer "In6.Cu")
		(net 376)
	)
	(segment
		(start 159.825331 164.694999)
		(end 151.60083 164.694999)
		(width 0.1)
		(layer "In6.Cu")
		(net 376)
	)
	(segment
		(start 181.875 158.775)
		(end 181.7 158.95)
		(width 0.1)
		(layer "In6.Cu")
		(net 376)
	)
	(segment
		(start 181.875 156.875)
		(end 181.875 158.775)
		(width 0.1)
		(layer "In6.Cu")
		(net 376)
	)
	(segment
		(start 181.7 158.95)
		(end 165.259668 158.95)
		(width 0.1)
		(layer "In6.Cu")
		(net 376)
	)
	(segment
		(start 165.259668 158.95)
		(end 164.325 159.884668)
		(width 0.1)
		(layer "In6.Cu")
		(net 376)
	)
	(segment
		(start 164.325 159.884668)
		(end 164.325 160.19533)
		(width 0.1)
		(layer "In6.Cu")
		(net 376)
	)
	(segment
		(start 150.759499 160.079)
		(end 151.004499 160.079)
		(width 0.15)
		(layer "F.Cu")
		(net 377)
	)
	(segment
		(start 180.9995 156.000499)
		(end 180.5 156.5)
		(width 0.256)
		(layer "F.Cu")
		(net 377)
	)
	(segment
		(start 150.389499 159.709)
		(end 150.759499 160.079)
		(width 0.15)
		(layer "F.Cu")
		(net 377)
	)
	(via
		(at 151.004499 160.079)
		(size 0.45)
		(drill 0.1)
		(layers "F.Cu" "B.Cu")
		(remove_unused_layers yes)
		(keep_end_layers yes)
		(zone_layer_connections)
		(net 377)
	)
	(via
		(at 180.5 156.5)
		(size 0.45)
		(drill 0.1)
		(layers "F.Cu" "B.Cu")
		(remove_unused_layers yes)
		(keep_end_layers yes)
		(zone_layer_connections)
		(net 377)
	)
	(segment
		(start 180 156)
		(end 173.925 156)
		(width 0.1)
		(layer "In6.Cu")
		(net 377)
	)
	(segment
		(start 173.65 155.725)
		(end 165.375 155.725)
		(width 0.1)
		(layer "In6.Cu")
		(net 377)
	)
	(segment
		(start 161.021 160.079)
		(end 151.004499 160.079)
		(width 0.1)
		(layer "In6.Cu")
		(net 377)
	)
	(segment
		(start 173.925 156)
		(end 173.65 155.725)
		(width 0.1)
		(layer "In6.Cu")
		(net 377)
	)
	(segment
		(start 165.375 155.725)
		(end 161.021 160.079)
		(width 0.1)
		(layer "In6.Cu")
		(net 377)
	)
	(segment
		(start 180.5 156.5)
		(end 180 156)
		(width 0.1)
		(layer "In6.Cu")
		(net 377)
	)
	(segment
		(start 180.9995 157.0005)
		(end 180.5 157.5)
		(width 0.256)
		(layer "F.Cu")
		(net 378)
	)
	(segment
		(start 151.05 160.7)
		(end 150.398499 160.7)
		(width 0.15)
		(layer "F.Cu")
		(net 378)
	)
	(segment
		(start 150.398499 160.7)
		(end 150.389499 160.709)
		(width 0.15)
		(layer "F.Cu")
		(net 378)
	)
	(via
		(at 151.05 160.7)
		(size 0.45)
		(drill 0.1)
		(layers "F.Cu" "B.Cu")
		(remove_unused_layers yes)
		(keep_end_layers yes)
		(zone_layer_connections)
		(net 378)
	)
	(via
		(at 180.5 157.5)
		(size 0.45)
		(drill 0.1)
		(layers "F.Cu" "B.Cu")
		(remove_unused_layers yes)
		(keep_end_layers yes)
		(zone_layer_connections)
		(net 378)
	)
	(segment
		(start 152.165 161.815)
		(end 151.05 160.7)
		(width 0.1)
		(layer "In6.Cu")
		(net 378)
	)
	(segment
		(start 180.5 157.5)
		(end 180.125 157.125)
		(width 0.1)
		(layer "In6.Cu")
		(net 378)
	)
	(segment
		(start 160.035 161.815)
		(end 152.165 161.815)
		(width 0.1)
		(layer "In6.Cu")
		(net 378)
	)
	(segment
		(start 164.725 157.125)
		(end 160.035 161.815)
		(width 0.1)
		(layer "In6.Cu")
		(net 378)
	)
	(segment
		(start 180.125 157.125)
		(end 164.725 157.125)
		(width 0.1)
		(layer "In6.Cu")
		(net 378)
	)
	(segment
		(start 148.775498 167.54)
		(end 148.769499 167.534)
		(width 0.15)
		(layer "F.Cu")
		(net 379)
	)
	(segment
		(start 141.933 166.772)
		(end 141.933 168.140499)
		(width 0.15)
		(layer "F.Cu")
		(net 379)
	)
	(segment
		(start 148.775499 168.884)
		(end 148.775498 167.54)
		(width 0.15)
		(layer "F.Cu")
		(net 379)
	)
	(segment
		(start 141.933 168.140499)
		(end 141.924499 168.149)
		(width 0.15)
		(layer "F.Cu")
		(net 379)
	)
	(via
		(at 141.924499 168.149)
		(size 0.45)
		(drill 0.1)
		(layers "F.Cu" "B.Cu")
		(remove_unused_layers yes)
		(keep_end_layers yes)
		(zone_layer_connections)
		(net 379)
	)
	(via
		(at 148.769499 167.534)
		(size 0.45)
		(drill 0.1)
		(layers "F.Cu" "B.Cu")
		(remove_unused_layers yes)
		(keep_end_layers yes)
		(zone_layer_connections)
		(net 379)
	)
	(segment
		(start 148.769499 167.534)
		(end 148.234499 166.999)
		(width 0.15)
		(layer "B.Cu")
		(net 379)
	)
	(segment
		(start 141.124499 168.449)
		(end 141.424499 168.149)
		(width 0.15)
		(layer "B.Cu")
		(net 379)
	)
	(segment
		(start 142.624499 165.999)
		(end 141.924499 166.699)
		(width 0.15)
		(layer "B.Cu")
		(net 379)
	)
	(segment
		(start 141.424499 168.149)
		(end 141.924499 168.149)
		(width 0.15)
		(layer "B.Cu")
		(net 379)
	)
	(segment
		(start 141.924499 166.699)
		(end 141.924499 168.149)
		(width 0.15)
		(layer "B.Cu")
		(net 379)
	)
	(segment
		(start 146.924499 165.999)
		(end 142.624499 165.999)
		(width 0.15)
		(layer "B.Cu")
		(net 379)
	)
	(segment
		(start 141.124499 168.914)
		(end 141.124499 168.449)
		(width 0.15)
		(layer "B.Cu")
		(net 379)
	)
	(segment
		(start 147.924499 166.999)
		(end 146.924499 165.999)
		(width 0.15)
		(layer "B.Cu")
		(net 379)
	)
	(segment
		(start 148.234499 166.999)
		(end 147.924499 166.999)
		(width 0.15)
		(layer "B.Cu")
		(net 379)
	)
	(segment
		(start 121.505 151.61)
		(end 121.975 151.61)
		(width 0.4)
		(layer "F.Cu")
		(net 380)
	)
	(via
		(at 121.975 151.61)
		(size 0.45)
		(drill 0.1)
		(layers "F.Cu" "B.Cu")
		(remove_unused_layers yes)
		(keep_end_layers yes)
		(zone_layer_connections)
		(net 380)
	)
	(segment
		(start 116.653801 152.127993)
		(end 116.307812 152.473982)
		(width 0.16)
		(layer "B.Cu")
		(net 380)
	)
	(segment
		(start 109.203651 159.215)
		(end 108.763676 159.215)
		(width 0.16)
		(layer "B.Cu")
		(net 380)
	)
	(segment
		(start 121.975 151.61)
		(end 122.47 151.61)
		(width 0.16)
		(layer "B.Cu")
		(net 380)
	)
	(segment
		(start 121.975 151.61)
		(end 121.8025 151.782499)
		(width 0.16)
		(layer "B.Cu")
		(net 380)
	)
	(segment
		(start 109.823576 158.958219)
		(end 116.307812 152.473982)
		(width 0.16)
		(layer "B.Cu")
		(net 380)
	)
	(segment
		(start 108.534325 159.12)
		(end 107.071674 159.12)
		(width 0.16)
		(layer "B.Cu")
		(net 380)
	)
	(segment
		(start 117.071447 151.954999)
		(end 121.386049 151.954999)
		(width 0.16)
		(layer "B.Cu")
		(net 380)
	)
	(segment
		(start 106.842323 159.215)
		(end 106.518708 159.215)
		(width 0.16)
		(layer "B.Cu")
		(net 380)
	)
	(segment
		(start 105.685805 158.87)
		(end 105.17 158.87)
		(width 0.16)
		(layer "B.Cu")
		(net 380)
	)
	(arc
		(start 107.071674 159.12)
		(mid 107.009612 159.132344)
		(end 106.956999 159.1675)
		(width 0.16)
		(layer "B.Cu")
		(net 380)
	)
	(arc
		(start 106.102257 159.0425)
		(mid 105.911187 158.914831)
		(end 105.685805 158.87)
		(width 0.16)
		(layer "B.Cu")
		(net 380)
	)
	(arc
		(start 109.203651 159.215)
		(mid 109.539152 159.148265)
		(end 109.823576 158.958219)
		(width 0.16)
		(layer "B.Cu")
		(net 380)
	)
	(arc
		(start 121.8025 151.782499)
		(mid 121.61143 151.910167)
		(end 121.386049 151.954999)
		(width 0.16)
		(layer "B.Cu")
		(net 380)
	)
	(arc
		(start 117.071447 151.954999)
		(mid 116.845418 151.999958)
		(end 116.653801 152.127993)
		(width 0.16)
		(layer "B.Cu")
		(net 380)
	)
	(arc
		(start 108.534325 159.12)
		(mid 108.596387 159.132344)
		(end 108.649001 159.1675)
		(width 0.16)
		(layer "B.Cu")
		(net 380)
	)
	(arc
		(start 108.649001 159.1675)
		(mid 108.701614 159.202655)
		(end 108.763676 159.215)
		(width 0.16)
		(layer "B.Cu")
		(net 380)
	)
	(arc
		(start 106.842323 159.215)
		(mid 106.904385 159.202655)
		(end 106.956999 159.1675)
		(width 0.16)
		(layer "B.Cu")
		(net 380)
	)
	(arc
		(start 106.518708 159.215)
		(mid 106.293326 159.170168)
		(end 106.102257 159.0425)
		(width 0.16)
		(layer "B.Cu")
		(net 380)
	)
	(segment
		(start 130.031294 178.4135)
		(end 131.696741 178.4135)
		(width 0.16)
		(layer "F.Cu")
		(net 381)
	)
	(segment
		(start 128.371325 179.053)
		(end 127.801 179.053)
		(width 0.16)
		(layer "F.Cu")
		(net 381)
	)
	(segment
		(start 133.026753 177.67095)
		(end 132.850257 177.847446)
		(width 0.16)
		(layer "F.Cu")
		(net 381)
	)
	(segment
		(start 129.592417 178.595288)
		(end 129.515006 178.672697)
		(width 0.16)
		(layer "F.Cu")
		(net 381)
	)
	(segment
		(start 128.600676 178.958)
		(end 128.881602 178.958)
		(width 0.16)
		(layer "F.Cu")
		(net 381)
	)
	(segment
		(start 129.515006 178.672697)
		(end 129.488901 178.698802)
		(width 0.16)
		(layer "F.Cu")
		(net 381)
	)
	(segment
		(start 133.115001 177.4579)
		(end 133.115001 177.288556)
		(width 0.16)
		(layer "F.Cu")
		(net 381)
	)
	(segment
		(start 129.475848 178.711855)
		(end 129.488901 178.698802)
		(width 0.16)
		(layer "F.Cu")
		(net 381)
	)
	(segment
		(start 132.699602 177.998101)
		(end 132.850257 177.847446)
		(width 0.16)
		(layer "F.Cu")
		(net 381)
	)
	(via
		(at 133.26 176.9385)
		(size 0.45)
		(drill 0.1)
		(layers "F.Cu" "B.Cu")
		(remove_unused_layers yes)
		(keep_end_layers yes)
		(zone_layer_connections)
		(net 381)
	)
	(arc
		(start 128.486001 179.0055)
		(mid 128.433387 179.040655)
		(end 128.371325 179.053)
		(width 0.16)
		(layer "F.Cu")
		(net 381)
	)
	(arc
		(start 129.592417 178.595288)
		(mid 129.793776 178.460745)
		(end 130.031294 178.4135)
		(width 0.16)
		(layer "F.Cu")
		(net 381)
	)
	(arc
		(start 132.699602 177.998101)
		(mid 132.239485 178.305541)
		(end 131.696741 178.4135)
		(width 0.16)
		(layer "F.Cu")
		(net 381)
	)
	(arc
		(start 133.26 176.9385)
		(mid 133.152686 177.099106)
		(end 133.115001 177.288556)
		(width 0.16)
		(layer "F.Cu")
		(net 381)
	)
	(arc
		(start 128.486001 179.0055)
		(mid 128.538614 178.970344)
		(end 128.600676 178.958)
		(width 0.16)
		(layer "F.Cu")
		(net 381)
	)
	(arc
		(start 129.475848 178.711855)
		(mid 129.203205 178.894028)
		(end 128.881602 178.958)
		(width 0.16)
		(layer "F.Cu")
		(net 381)
	)
	(arc
		(start 133.115001 177.4579)
		(mid 133.092066 177.573201)
		(end 133.026753 177.67095)
		(width 0.16)
		(layer "F.Cu")
		(net 381)
	)
	(segment
		(start 143.142002 180.588792)
		(end 142.876534 180.854261)
		(width 0.16)
		(layer "B.Cu")
		(net 381)
	)
	(segment
		(start 178.57633 170.530911)
		(end 178.576331 170.530911)
		(width 0.16)
		(layer "B.Cu")
		(net 381)
	)
	(segment
		(start 175.271856 173.392407)
		(end 175.493344 173.613895)
		(width 0.16)
		(layer "B.Cu")
		(net 381)
	)
	(segment
		(start 134.273008 179.084601)
		(end 134.317432 179.040176)
		(width 0.16)
		(layer "B.Cu")
		(net 381)
	)
	(segment
		(start 176.638858 172.821935)
		(end 176.638857 172.821936)
		(width 0.16)
		(layer "B.Cu")
		(net 381)
	)
	(segment
		(start 134.098229 178.820973)
		(end 134.053806 178.865399)
		(width 0.16)
		(layer "B.Cu")
		(net 381)
	)
	(segment
		(start 134.273007 179.303803)
		(end 134.273007 179.303804)
		(width 0.16)
		(layer "B.Cu")
		(net 381)
	)
	(segment
		(start 178.929883 170.530909)
		(end 178.929884 170.530909)
		(width 0.16)
		(layer "B.Cu")
		(net 381)
	)
	(segment
		(start 178.708407 169.163921)
		(end 178.708407 169.16392)
		(width 0.16)
		(layer "B.Cu")
		(net 381)
	)
	(segment
		(start 172.848766 176.258476)
		(end 172.627277 176.036987)
		(width 0.16)
		(layer "B.Cu")
		(net 381)
	)
	(segment
		(start 177.430818 171.676424)
		(end 177.209318 171.454924)
		(width 0.16)
		(layer "B.Cu")
		(net 381)
	)
	(segment
		(start 175.493344 173.967448)
		(end 175.493345 173.96745)
		(width 0.16)
		(layer "B.Cu")
		(net 381)
	)
	(segment
		(start 172.056805 177.403988)
		(end 172.056805 177.403987)
		(width 0.16)
		(layer "B.Cu")
		(net 381)
	)
	(segment
		(start 134.317433 178.820974)
		(end 134.317432 178.820972)
		(width 0.16)
		(layer "B.Cu")
		(net 381)
	)
	(segment
		(start 176.285304 172.821937)
		(end 176.285305 172.821937)
		(width 0.16)
		(layer "B.Cu")
		(net 381)
	)
	(segment
		(start 133.115001 177.675604)
		(end 133.115001 177.288556)
		(width 0.16)
		(layer "B.Cu")
		(net 381)
	)
	(segment
		(start 173.202318 176.258475)
		(end 173.202318 176.258474)
		(width 0.16)
		(layer "B.Cu")
		(net 381)
	)
	(segment
		(start 173.994278 175.112963)
		(end 173.994279 175.112963)
		(width 0.16)
		(layer "B.Cu")
		(net 381)
	)
	(segment
		(start 178.929884 170.530909)
		(end 178.929884 170.530911)
		(width 0.16)
		(layer "B.Cu")
		(net 381)
	)
	(segment
		(start 177.562894 171.101392)
		(end 177.784371 171.322869)
		(width 0.16)
		(layer "B.Cu")
		(net 381)
	)
	(segment
		(start 175.271856 173.392406)
		(end 175.271856 173.392407)
		(width 0.16)
		(layer "B.Cu")
		(net 381)
	)
	(segment
		(start 174.347831 175.112961)
		(end 174.347832 175.112963)
		(width 0.16)
		(layer "B.Cu")
		(net 381)
	)
	(segment
		(start 179.721843 169.385398)
		(end 179.721844 169.385398)
		(width 0.16)
		(layer "B.Cu")
		(net 381)
	)
	(segment
		(start 174.347831 175.112962)
		(end 174.347831 175.112961)
		(width 0.16)
		(layer "B.Cu")
		(net 381)
	)
	(segment
		(start 177.78437 171.676422)
		(end 177.784371 171.676422)
		(width 0.16)
		(layer "B.Cu")
		(net 381)
	)
	(segment
		(start 134.053806 178.865399)
		(end 134.053805 178.865397)
		(width 0.16)
		(layer "B.Cu")
		(net 381)
	)
	(segment
		(start 171.835317 176.828945)
		(end 171.835317 176.828946)
		(width 0.16)
		(layer "B.Cu")
		(net 381)
	)
	(segment
		(start 176.417358 172.246883)
		(end 176.638857 172.468382)
		(width 0.16)
		(layer "B.Cu")
		(net 381)
	)
	(segment
		(start 135.823465 180.854261)
		(end 134.273007 179.303803)
		(width 0.16)
		(layer "B.Cu")
		(net 381)
	)
	(segment
		(start 172.98083 175.683433)
		(end 173.202318 175.904921)
		(width 0.16)
		(layer "B.Cu")
		(net 381)
	)
	(segment
		(start 179.721844 169.385398)
		(end 179.500366 169.16392)
		(width 0.16)
		(layer "B.Cu")
		(net 381)
	)
	(segment
		(start 180.845001 168.452897)
		(end 180.845001 168.523593)
		(width 0.16)
		(layer "B.Cu")
		(net 381)
	)
	(segment
		(start 175.493344 173.967449)
		(end 175.493344 173.967448)
		(width 0.16)
		(layer "B.Cu")
		(net 381)
	)
	(segment
		(start 168.341456 178.995)
		(end 146.989759 178.995)
		(width 0.16)
		(layer "B.Cu")
		(net 381)
	)
	(segment
		(start 134.317432 179.040176)
		(end 134.317432 179.040177)
		(width 0.16)
		(layer "B.Cu")
		(net 381)
	)
	(segment
		(start 172.056806 177.403989)
		(end 171.967928 177.492866)
		(width 0.16)
		(layer "B.Cu")
		(net 381)
	)
	(segment
		(start 180.779807 168.680988)
		(end 180.075397 169.385398)
		(width 0.16)
		(layer "B.Cu")
		(net 381)
	)
	(segment
		(start 175.139791 173.96745)
		(end 175.139792 173.96745)
		(width 0.16)
		(layer "B.Cu")
		(net 381)
	)
	(segment
		(start 171.835317 176.828946)
		(end 172.056805 177.050434)
		(width 0.16)
		(layer "B.Cu")
		(net 381)
	)
	(segment
		(start 172.98083 175.683432)
		(end 172.98083 175.683433)
		(width 0.16)
		(layer "B.Cu")
		(net 381)
	)
	(segment
		(start 172.848765 176.258476)
		(end 172.848766 176.258476)
		(width 0.16)
		(layer "B.Cu")
		(net 381)
	)
	(segment
		(start 173.202318 176.258474)
		(end 173.202319 176.258476)
		(width 0.16)
		(layer "B.Cu")
		(net 381)
	)
	(segment
		(start 173.994279 175.112963)
		(end 173.77279 174.891474)
		(width 0.16)
		(layer "B.Cu")
		(net 381)
	)
	(segment
		(start 177.784371 171.676422)
		(end 177.784371 171.676424)
		(width 0.16)
		(layer "B.Cu")
		(net 381)
	)
	(segment
		(start 180.510001 167.93)
		(end 180.510001 167.9425)
		(width 0.16)
		(layer "B.Cu")
		(net 381)
	)
	(segment
		(start 174.126377 174.537954)
		(end 174.347831 174.759408)
		(width 0.16)
		(layer "B.Cu")
		(net 381)
	)
	(segment
		(start 176.285305 172.821937)
		(end 176.063816 172.600448)
		(width 0.16)
		(layer "B.Cu")
		(net 381)
	)
	(segment
		(start 180.518839 167.963838)
		(end 180.729815 168.174814)
		(width 0.16)
		(layer "B.Cu")
		(net 381)
	)
	(segment
		(start 177.562894 171.101391)
		(end 177.562894 171.101392)
		(width 0.16)
		(layer "B.Cu")
		(net 381)
	)
	(segment
		(start 177.430817 171.676424)
		(end 177.430818 171.676424)
		(width 0.16)
		(layer "B.Cu")
		(net 381)
	)
	(segment
		(start 176.638857 172.821936)
		(end 176.638858 172.821937)
		(width 0.16)
		(layer "B.Cu")
		(net 381)
	)
	(segment
		(start 177.562894 170.309434)
		(end 177.562894 170.309433)
		(width 0.16)
		(layer "B.Cu")
		(net 381)
	)
	(segment
		(start 133.834602 178.865398)
		(end 133.447478 178.478274)
		(width 0.16)
		(layer "B.Cu")
		(net 381)
	)
	(segment
		(start 178.708407 169.955879)
		(end 178.929884 170.177356)
		(width 0.16)
		(layer "B.Cu")
		(net 381)
	)
	(segment
		(start 172.056805 177.403987)
		(end 172.056806 177.403989)
		(width 0.16)
		(layer "B.Cu")
		(net 381)
	)
	(segment
		(start 174.126377 174.537953)
		(end 174.126377 174.537954)
		(width 0.16)
		(layer "B.Cu")
		(net 381)
	)
	(segment
		(start 178.708407 169.955878)
		(end 178.708407 169.955879)
		(width 0.16)
		(layer "B.Cu")
		(net 381)
	)
	(segment
		(start 178.576331 170.530911)
		(end 178.354853 170.309433)
		(width 0.16)
		(layer "B.Cu")
		(net 381)
	)
	(segment
		(start 175.139792 173.96745)
		(end 174.918337 173.745995)
		(width 0.16)
		(layer "B.Cu")
		(net 381)
	)
	(segment
		(start 176.417358 172.246882)
		(end 176.417358 172.246883)
		(width 0.16)
		(layer "B.Cu")
		(net 381)
	)
	(arc
		(start 174.918337 173.745995)
		(mid 174.522357 173.581975)
		(end 174.126377 173.745995)
		(width 0.16)
		(layer "B.Cu")
		(net 381)
	)
	(arc
		(start 173.202318 175.904921)
		(mid 173.275541 176.081698)
		(end 173.202318 176.258475)
		(width 0.16)
		(layer "B.Cu")
		(net 381)
	)
	(arc
		(start 176.063816 172.600448)
		(mid 175.667836 172.436428)
		(end 175.271856 172.600448)
		(width 0.16)
		(layer "B.Cu")
		(net 381)
	)
	(arc
		(start 180.075397 169.385398)
		(mid 179.89862 169.458621)
		(end 179.721843 169.385398)
		(width 0.16)
		(layer "B.Cu")
		(net 381)
	)
	(arc
		(start 177.784371 171.676424)
		(mid 177.607594 171.749647)
		(end 177.430817 171.676424)
		(width 0.16)
		(layer "B.Cu")
		(net 381)
	)
	(arc
		(start 146.989759 178.995)
		(mid 144.907368 179.409213)
		(end 143.142002 180.588792)
		(width 0.16)
		(layer "B.Cu")
		(net 381)
	)
	(arc
		(start 175.271856 172.600448)
		(mid 175.107836 172.996427)
		(end 175.271856 173.392406)
		(width 0.16)
		(layer "B.Cu")
		(net 381)
	)
	(arc
		(start 173.202319 176.258476)
		(mid 173.025542 176.331699)
		(end 172.848765 176.258476)
		(width 0.16)
		(layer "B.Cu")
		(net 381)
	)
	(arc
		(start 133.115001 177.288556)
		(mid 133.152686 177.099106)
		(end 133.26 176.9385)
		(width 0.16)
		(layer "B.Cu")
		(net 381)
	)
	(arc
		(start 180.729815 168.174814)
		(mid 180.815065 168.302399)
		(end 180.845001 168.452897)
		(width 0.16)
		(layer "B.Cu")
		(net 381)
	)
	(arc
		(start 177.209318 171.454924)
		(mid 176.813338 171.290904)
		(end 176.417358 171.454924)
		(width 0.16)
		(layer "B.Cu")
		(net 381)
	)
	(arc
		(start 134.273007 179.303804)
		(mid 134.227609 179.194202)
		(end 134.273008 179.084601)
		(width 0.16)
		(layer "B.Cu")
		(net 381)
	)
	(arc
		(start 177.784371 171.322869)
		(mid 177.857594 171.499646)
		(end 177.78437 171.676422)
		(width 0.16)
		(layer "B.Cu")
		(net 381)
	)
	(arc
		(start 175.493344 173.613895)
		(mid 175.566567 173.790672)
		(end 175.493344 173.967449)
		(width 0.16)
		(layer "B.Cu")
		(net 381)
	)
	(arc
		(start 180.510001 167.9425)
		(mid 180.512297 167.954048)
		(end 180.518839 167.963838)
		(width 0.16)
		(layer "B.Cu")
		(net 381)
	)
	(arc
		(start 171.967928 177.492866)
		(mid 170.304088 178.604608)
		(end 168.341456 178.995)
		(width 0.16)
		(layer "B.Cu")
		(net 381)
	)
	(arc
		(start 178.354853 170.309433)
		(mid 177.958873 170.145413)
		(end 177.562894 170.309434)
		(width 0.16)
		(layer "B.Cu")
		(net 381)
	)
	(arc
		(start 171.835317 176.036987)
		(mid 171.671297 176.432966)
		(end 171.835317 176.828945)
		(width 0.16)
		(layer "B.Cu")
		(net 381)
	)
	(arc
		(start 180.845001 168.523593)
		(mid 180.828058 168.608774)
		(end 180.779807 168.680988)
		(width 0.16)
		(layer "B.Cu")
		(net 381)
	)
	(arc
		(start 142.876534 180.854261)
		(mid 141.258546 181.935366)
		(end 139.35 182.315)
		(width 0.16)
		(layer "B.Cu")
		(net 381)
	)
	(arc
		(start 176.417358 171.454924)
		(mid 176.253338 171.850903)
		(end 176.417358 172.246882)
		(width 0.16)
		(layer "B.Cu")
		(net 381)
	)
	(arc
		(start 175.493345 173.96745)
		(mid 175.316568 174.040673)
		(end 175.139791 173.96745)
		(width 0.16)
		(layer "B.Cu")
		(net 381)
	)
	(arc
		(start 174.126377 173.745995)
		(mid 173.962357 174.141974)
		(end 174.126377 174.537953)
		(width 0.16)
		(layer "B.Cu")
		(net 381)
	)
	(arc
		(start 139.35 182.315)
		(mid 137.441453 181.935366)
		(end 135.823465 180.854261)
		(width 0.16)
		(layer "B.Cu")
		(net 381)
	)
	(arc
		(start 176.638857 172.468382)
		(mid 176.712081 172.645158)
		(end 176.638858 172.821935)
		(width 0.16)
		(layer "B.Cu")
		(net 381)
	)
	(arc
		(start 176.638858 172.821937)
		(mid 176.462081 172.89516)
		(end 176.285304 172.821937)
		(width 0.16)
		(layer "B.Cu")
		(net 381)
	)
	(arc
		(start 179.500366 169.16392)
		(mid 179.104386 168.9999)
		(end 178.708407 169.163921)
		(width 0.16)
		(layer "B.Cu")
		(net 381)
	)
	(arc
		(start 134.053805 178.865397)
		(mid 133.944204 178.910796)
		(end 133.834602 178.865398)
		(width 0.16)
		(layer "B.Cu")
		(net 381)
	)
	(arc
		(start 174.347831 174.759408)
		(mid 174.421054 174.936185)
		(end 174.347831 175.112962)
		(width 0.16)
		(layer "B.Cu")
		(net 381)
	)
	(arc
		(start 178.708407 169.16392)
		(mid 178.544387 169.559899)
		(end 178.708407 169.955878)
		(width 0.16)
		(layer "B.Cu")
		(net 381)
	)
	(arc
		(start 174.347832 175.112963)
		(mid 174.171055 175.186186)
		(end 173.994278 175.112963)
		(width 0.16)
		(layer "B.Cu")
		(net 381)
	)
	(arc
		(start 178.929884 170.530911)
		(mid 178.753107 170.604134)
		(end 178.57633 170.530911)
		(width 0.16)
		(layer "B.Cu")
		(net 381)
	)
	(arc
		(start 172.056805 177.050434)
		(mid 172.130028 177.227211)
		(end 172.056805 177.403988)
		(width 0.16)
		(layer "B.Cu")
		(net 381)
	)
	(arc
		(start 177.562894 170.309433)
		(mid 177.398874 170.705412)
		(end 177.562894 171.101391)
		(width 0.16)
		(layer "B.Cu")
		(net 381)
	)
	(arc
		(start 133.447478 178.478274)
		(mid 133.201409 178.110006)
		(end 133.115001 177.675604)
		(width 0.16)
		(layer "B.Cu")
		(net 381)
	)
	(arc
		(start 173.77279 174.891474)
		(mid 173.37681 174.727454)
		(end 172.98083 174.891474)
		(width 0.16)
		(layer "B.Cu")
		(net 381)
	)
	(arc
		(start 172.627277 176.036987)
		(mid 172.231297 175.872967)
		(end 171.835317 176.036987)
		(width 0.16)
		(layer "B.Cu")
		(net 381)
	)
	(arc
		(start 178.929884 170.177356)
		(mid 179.003107 170.354133)
		(end 178.929883 170.530909)
		(width 0.16)
		(layer "B.Cu")
		(net 381)
	)
	(arc
		(start 172.98083 174.891474)
		(mid 172.81681 175.287453)
		(end 172.98083 175.683432)
		(width 0.16)
		(layer "B.Cu")
		(net 381)
	)
	(arc
		(start 134.317432 179.040177)
		(mid 134.362831 178.930576)
		(end 134.317433 178.820974)
		(width 0.16)
		(layer "B.Cu")
		(net 381)
	)
	(arc
		(start 134.317432 178.820972)
		(mid 134.20783 178.775574)
		(end 134.098229 178.820973)
		(width 0.16)
		(layer "B.Cu")
		(net 381)
	)
	(segment
		(start 181.5005 161.4995)
		(end 182 161)
		(width 0.256)
		(layer "F.Cu")
		(net 382)
	)
	(via
		(at 181.5005 161.4995)
		(size 0.45)
		(drill 0.1)
		(layers "F.Cu" "B.Cu")
		(remove_unused_layers yes)
		(keep_end_layers yes)
		(zone_layer_connections)
		(net 382)
	)
	(segment
		(start 181.029788 162.038788)
		(end 181.073722 161.994855)
		(width 0.1)
		(layer "B.Cu")
		(net 382)
	)
	(segment
		(start 180.9005 166.278728)
		(end 180.9005 165.628728)
		(width 0.1)
		(layer "B.Cu")
		(net 382)
	)
	(segment
		(start 180.510501 166.9695)
		(end 180.510501 166.957)
		(width 0.1)
		(layer "B.Cu")
		(net 382)
	)
	(segment
		(start 180.9005 165.628728)
		(end 180.9005 162.35092)
		(width 0.1)
		(layer "B.Cu")
		(net 382)
	)
	(segment
		(start 181.279789 161.9095)
		(end 181.329789 161.9095)
		(width 0.1)
		(layer "B.Cu")
		(net 382)
	)
	(segment
		(start 180.519339 166.935661)
		(end 180.7055 166.749499)
		(width 0.1)
		(layer "B.Cu")
		(net 382)
	)
	(segment
		(start 181.5005 161.738789)
		(end 181.5005 161.4995)
		(width 0.1)
		(layer "B.Cu")
		(net 382)
	)
	(arc
		(start 181.4505 161.8595)
		(mid 181.487505 161.804117)
		(end 181.5005 161.738789)
		(width 0.1)
		(layer "B.Cu")
		(net 382)
	)
	(arc
		(start 180.9005 162.35092)
		(mid 180.9341 162.181995)
		(end 181.029788 162.038788)
		(width 0.1)
		(layer "B.Cu")
		(net 382)
	)
	(arc
		(start 180.7055 166.749499)
		(mid 180.849821 166.533507)
		(end 180.9005 166.278728)
		(width 0.1)
		(layer "B.Cu")
		(net 382)
	)
	(arc
		(start 181.329789 161.9095)
		(mid 181.395117 161.896505)
		(end 181.4505 161.8595)
		(width 0.1)
		(layer "B.Cu")
		(net 382)
	)
	(arc
		(start 180.510501 166.957)
		(mid 180.512797 166.945451)
		(end 180.519339 166.935661)
		(width 0.1)
		(layer "B.Cu")
		(net 382)
	)
	(arc
		(start 181.073722 161.994855)
		(mid 181.168266 161.931683)
		(end 181.279789 161.9095)
		(width 0.1)
		(layer "B.Cu")
		(net 382)
	)
	(segment
		(start 130.030815 178.1035)
		(end 131.69674 178.1035)
		(width 0.16)
		(layer "F.Cu")
		(net 383)
	)
	(segment
		(start 128.600676 178.648)
		(end 128.879308 178.648)
		(width 0.16)
		(layer "F.Cu")
		(net 383)
	)
	(segment
		(start 132.804999 177.454295)
		(end 132.67417 177.585124)
		(width 0.16)
		(layer "F.Cu")
		(net 383)
	)
	(segment
		(start 132.480397 177.778898)
		(end 132.67417 177.585124)
		(width 0.16)
		(layer "F.Cu")
		(net 383)
	)
	(segment
		(start 129.373546 178.37575)
		(end 129.258259 178.491035)
		(width 0.16)
		(layer "F.Cu")
		(net 383)
	)
	(segment
		(start 128.371325 178.553)
		(end 127.801 178.553)
		(width 0.16)
		(layer "F.Cu")
		(net 383)
	)
	(segment
		(start 132.804999 177.454295)
		(end 132.804999 177.288549)
		(width 0.16)
		(layer "F.Cu")
		(net 383)
	)
	(via
		(at 132.66 176.9385)
		(size 0.45)
		(drill 0.1)
		(layers "F.Cu" "B.Cu")
		(remove_unused_layers yes)
		(keep_end_layers yes)
		(zone_layer_connections)
		(net 383)
	)
	(arc
		(start 129.373546 178.37575)
		(mid 129.675103 178.174255)
		(end 130.030815 178.1035)
		(width 0.16)
		(layer "F.Cu")
		(net 383)
	)
	(arc
		(start 132.480397 177.778898)
		(mid 132.120852 178.019138)
		(end 131.69674 178.1035)
		(width 0.16)
		(layer "F.Cu")
		(net 383)
	)
	(arc
		(start 128.600676 178.648)
		(mid 128.538614 178.635655)
		(end 128.486001 178.6005)
		(width 0.16)
		(layer "F.Cu")
		(net 383)
	)
	(arc
		(start 128.371325 178.553)
		(mid 128.433387 178.565344)
		(end 128.486001 178.6005)
		(width 0.16)
		(layer "F.Cu")
		(net 383)
	)
	(arc
		(start 132.66 176.9385)
		(mid 132.767316 177.099107)
		(end 132.804999 177.288549)
		(width 0.16)
		(layer "F.Cu")
		(net 383)
	)
	(arc
		(start 128.879308 178.648)
		(mid 129.084394 178.607206)
		(end 129.258259 178.491035)
		(width 0.16)
		(layer "F.Cu")
		(net 383)
	)
	(segment
		(start 177.211614 171.895627)
		(end 176.990114 171.674127)
		(width 0.16)
		(layer "B.Cu")
		(net 383)
	)
	(segment
		(start 174.345579 173.965198)
		(end 174.34558 173.965198)
		(width 0.16)
		(layer "B.Cu")
		(net 383)
	)
	(segment
		(start 179.149086 170.750112)
		(end 179.149087 170.750114)
		(width 0.16)
		(layer "B.Cu")
		(net 383)
	)
	(segment
		(start 173.200032 175.110677)
		(end 173.200033 175.110677)
		(width 0.16)
		(layer "B.Cu")
		(net 383)
	)
	(segment
		(start 172.276009 177.623192)
		(end 172.187996 177.711207)
		(width 0.16)
		(layer "B.Cu")
		(net 383)
	)
	(segment
		(start 174.920588 174.186653)
		(end 174.699133 173.965198)
		(width 0.16)
		(layer "B.Cu")
		(net 383)
	)
	(segment
		(start 178.003573 171.895625)
		(end 178.003574 171.895627)
		(width 0.16)
		(layer "B.Cu")
		(net 383)
	)
	(segment
		(start 172.05452 176.609743)
		(end 172.276008 176.831231)
		(width 0.16)
		(layer "B.Cu")
		(net 383)
	)
	(segment
		(start 178.927609 169.736675)
		(end 178.927609 169.736676)
		(width 0.16)
		(layer "B.Cu")
		(net 383)
	)
	(segment
		(start 177.782096 170.528637)
		(end 177.782096 170.528636)
		(width 0.16)
		(layer "B.Cu")
		(net 383)
	)
	(segment
		(start 173.421521 176.477678)
		(end 173.421522 176.477679)
		(width 0.16)
		(layer "B.Cu")
		(net 383)
	)
	(segment
		(start 181.481161 167.963838)
		(end 181.315585 168.129414)
		(width 0.16)
		(layer "B.Cu")
		(net 383)
	)
	(segment
		(start 173.775075 175.332166)
		(end 173.553586 175.110677)
		(width 0.16)
		(layer "B.Cu")
		(net 383)
	)
	(segment
		(start 135.604259 181.073463)
		(end 133.225976 178.69518)
		(width 0.16)
		(layer "B.Cu")
		(net 383)
	)
	(segment
		(start 178.357127 170.750114)
		(end 178.135649 170.528636)
		(width 0.16)
		(layer "B.Cu")
		(net 383)
	)
	(segment
		(start 176.63656 172.02768)
		(end 176.858059 172.249179)
		(width 0.16)
		(layer "B.Cu")
		(net 383)
	)
	(segment
		(start 174.34558 174.31875)
		(end 174.34558 174.318751)
		(width 0.16)
		(layer "B.Cu")
		(net 383)
	)
	(segment
		(start 172.629562 176.477679)
		(end 172.408073 176.25619)
		(width 0.16)
		(layer "B.Cu")
		(net 383)
	)
	(segment
		(start 172.05452 176.609742)
		(end 172.05452 176.609743)
		(width 0.16)
		(layer "B.Cu")
		(net 383)
	)
	(segment
		(start 179.149085 170.750112)
		(end 179.149086 170.750112)
		(width 0.16)
		(layer "B.Cu")
		(net 383)
	)
	(segment
		(start 175.491058 172.819651)
		(end 175.491059 172.819651)
		(width 0.16)
		(layer "B.Cu")
		(net 383)
	)
	(segment
		(start 174.34558 174.318751)
		(end 174.567034 174.540205)
		(width 0.16)
		(layer "B.Cu")
		(net 383)
	)
	(segment
		(start 173.200033 175.46423)
		(end 173.421521 175.685718)
		(width 0.16)
		(layer "B.Cu")
		(net 383)
	)
	(segment
		(start 172.276008 177.623191)
		(end 172.276009 177.623192)
		(width 0.16)
		(layer "B.Cu")
		(net 383)
	)
	(segment
		(start 176.066101 173.04114)
		(end 175.844612 172.819651)
		(width 0.16)
		(layer "B.Cu")
		(net 383)
	)
	(segment
		(start 179.50264 169.604601)
		(end 179.281162 169.383123)
		(width 0.16)
		(layer "B.Cu")
		(net 383)
	)
	(segment
		(start 178.927609 169.736676)
		(end 179.149086 169.958153)
		(width 0.16)
		(layer "B.Cu")
		(net 383)
	)
	(segment
		(start 178.003572 171.895625)
		(end 178.003573 171.895625)
		(width 0.16)
		(layer "B.Cu")
		(net 383)
	)
	(segment
		(start 174.567034 175.332165)
		(end 174.567035 175.332166)
		(width 0.16)
		(layer "B.Cu")
		(net 383)
	)
	(segment
		(start 176.63656 172.027679)
		(end 176.63656 172.02768)
		(width 0.16)
		(layer "B.Cu")
		(net 383)
	)
	(segment
		(start 132.804999 177.678851)
		(end 132.804999 177.288549)
		(width 0.16)
		(layer "B.Cu")
		(net 383)
	)
	(segment
		(start 177.782096 170.882188)
		(end 177.782096 170.882189)
		(width 0.16)
		(layer "B.Cu")
		(net 383)
	)
	(segment
		(start 168.34024 179.305)
		(end 146.977266 179.305)
		(width 0.16)
		(layer "B.Cu")
		(net 383)
	)
	(segment
		(start 172.054519 176.25619)
		(end 172.05452 176.25619)
		(width 0.16)
		(layer "B.Cu")
		(net 383)
	)
	(segment
		(start 178.927609 169.383124)
		(end 178.927609 169.383123)
		(width 0.16)
		(layer "B.Cu")
		(net 383)
	)
	(segment
		(start 175.491059 173.173204)
		(end 175.712547 173.394692)
		(width 0.16)
		(layer "B.Cu")
		(net 383)
	)
	(segment
		(start 176.636561 171.674126)
		(end 176.63656 171.674127)
		(width 0.16)
		(layer "B.Cu")
		(net 383)
	)
	(segment
		(start 143.370042 180.799161)
		(end 143.09574 181.073463)
		(width 0.16)
		(layer "B.Cu")
		(net 383)
	)
	(segment
		(start 177.782096 170.882189)
		(end 178.003573 171.103666)
		(width 0.16)
		(layer "B.Cu")
		(net 383)
	)
	(segment
		(start 181.49 167.93)
		(end 181.49 167.9425)
		(width 0.16)
		(layer "B.Cu")
		(net 383)
	)
	(segment
		(start 173.200033 175.464229)
		(end 173.200033 175.46423)
		(width 0.16)
		(layer "B.Cu")
		(net 383)
	)
	(segment
		(start 175.491059 173.173203)
		(end 175.491059 173.173204)
		(width 0.16)
		(layer "B.Cu")
		(net 383)
	)
	(segment
		(start 176.858059 173.041139)
		(end 176.858061 173.04114)
		(width 0.16)
		(layer "B.Cu")
		(net 383)
	)
	(segment
		(start 180.294601 169.604602)
		(end 180.2946 169.604601)
		(width 0.16)
		(layer "B.Cu")
		(net 383)
	)
	(segment
		(start 180.994414 168.904789)
		(end 180.294601 169.604602)
		(width 0.16)
		(layer "B.Cu")
		(net 383)
	)
	(segment
		(start 175.712547 174.186652)
		(end 175.712548 174.186653)
		(width 0.16)
		(layer "B.Cu")
		(net 383)
	)
	(arc
		(start 174.567034 174.540205)
		(mid 174.731054 174.936185)
		(end 174.567034 175.332165)
		(width 0.16)
		(layer "B.Cu")
		(net 383)
	)
	(arc
		(start 178.927609 169.383123)
		(mid 178.854386 169.559899)
		(end 178.927609 169.736675)
		(width 0.16)
		(layer "B.Cu")
		(net 383)
	)
	(arc
		(start 175.491059 172.819651)
		(mid 175.417836 172.996427)
		(end 175.491059 173.173203)
		(width 0.16)
		(layer "B.Cu")
		(net 383)
	)
	(arc
		(start 174.567035 175.332166)
		(mid 174.171055 175.496186)
		(end 173.775075 175.332166)
		(width 0.16)
		(layer "B.Cu")
		(net 383)
	)
	(arc
		(start 181.315585 168.129414)
		(mid 181.196734 168.307286)
		(end 181.155 168.517102)
		(width 0.16)
		(layer "B.Cu")
		(net 383)
	)
	(arc
		(start 146.977266 179.305)
		(mid 145.02505 179.69332)
		(end 143.370042 180.799161)
		(width 0.16)
		(layer "B.Cu")
		(net 383)
	)
	(arc
		(start 143.09574 181.073463)
		(mid 141.37718 182.221768)
		(end 139.35 182.625)
		(width 0.16)
		(layer "B.Cu")
		(net 383)
	)
	(arc
		(start 173.421521 175.685718)
		(mid 173.585541 176.081698)
		(end 173.421521 176.477678)
		(width 0.16)
		(layer "B.Cu")
		(net 383)
	)
	(arc
		(start 175.712547 173.394692)
		(mid 175.876567 173.790672)
		(end 175.712547 174.186652)
		(width 0.16)
		(layer "B.Cu")
		(net 383)
	)
	(arc
		(start 133.225976 178.69518)
		(mid 132.914407 178.228884)
		(end 132.804999 177.678851)
		(width 0.16)
		(layer "B.Cu")
		(net 383)
	)
	(arc
		(start 181.155 168.517102)
		(mid 181.113265 168.726916)
		(end 180.994414 168.904789)
		(width 0.16)
		(layer "B.Cu")
		(net 383)
	)
	(arc
		(start 175.712548 174.186653)
		(mid 175.316568 174.350673)
		(end 174.920588 174.186653)
		(width 0.16)
		(layer "B.Cu")
		(net 383)
	)
	(arc
		(start 178.003574 171.895627)
		(mid 177.607594 172.059647)
		(end 177.211614 171.895627)
		(width 0.16)
		(layer "B.Cu")
		(net 383)
	)
	(arc
		(start 176.858061 173.04114)
		(mid 176.462081 173.20516)
		(end 176.066101 173.04114)
		(width 0.16)
		(layer "B.Cu")
		(net 383)
	)
	(arc
		(start 181.49 167.9425)
		(mid 181.487702 167.954048)
		(end 181.481161 167.963838)
		(width 0.16)
		(layer "B.Cu")
		(net 383)
	)
	(arc
		(start 179.281162 169.383123)
		(mid 179.104385 169.3099)
		(end 178.927609 169.383124)
		(width 0.16)
		(layer "B.Cu")
		(net 383)
	)
	(arc
		(start 174.34558 173.965198)
		(mid 174.272357 174.141974)
		(end 174.34558 174.31875)
		(width 0.16)
		(layer "B.Cu")
		(net 383)
	)
	(arc
		(start 172.276008 176.831231)
		(mid 172.440028 177.227211)
		(end 172.276008 177.623191)
		(width 0.16)
		(layer "B.Cu")
		(net 383)
	)
	(arc
		(start 172.187996 177.711207)
		(mid 170.42263 178.890786)
		(end 168.34024 179.305)
		(width 0.16)
		(layer "B.Cu")
		(net 383)
	)
	(arc
		(start 180.2946 169.604601)
		(mid 179.89862 169.768621)
		(end 179.50264 169.604601)
		(width 0.16)
		(layer "B.Cu")
		(net 383)
	)
	(arc
		(start 132.804999 177.288549)
		(mid 132.767316 177.099107)
		(end 132.66 176.9385)
		(width 0.16)
		(layer "B.Cu")
		(net 383)
	)
	(arc
		(start 179.149086 169.958153)
		(mid 179.313106 170.354133)
		(end 179.149085 170.750112)
		(width 0.16)
		(layer "B.Cu")
		(net 383)
	)
	(arc
		(start 178.003573 171.103666)
		(mid 178.167593 171.499646)
		(end 178.003572 171.895625)
		(width 0.16)
		(layer "B.Cu")
		(net 383)
	)
	(arc
		(start 176.990114 171.674127)
		(mid 176.813338 171.600903)
		(end 176.636561 171.674126)
		(width 0.16)
		(layer "B.Cu")
		(net 383)
	)
	(arc
		(start 173.200033 175.110677)
		(mid 173.12681 175.287453)
		(end 173.200033 175.464229)
		(width 0.16)
		(layer "B.Cu")
		(net 383)
	)
	(arc
		(start 173.553586 175.110677)
		(mid 173.376809 175.037454)
		(end 173.200032 175.110677)
		(width 0.16)
		(layer "B.Cu")
		(net 383)
	)
	(arc
		(start 175.844612 172.819651)
		(mid 175.667835 172.746428)
		(end 175.491058 172.819651)
		(width 0.16)
		(layer "B.Cu")
		(net 383)
	)
	(arc
		(start 176.858059 172.249179)
		(mid 177.022079 172.645159)
		(end 176.858059 173.041139)
		(width 0.16)
		(layer "B.Cu")
		(net 383)
	)
	(arc
		(start 177.782096 170.528636)
		(mid 177.708873 170.705412)
		(end 177.782096 170.882188)
		(width 0.16)
		(layer "B.Cu")
		(net 383)
	)
	(arc
		(start 173.421522 176.477679)
		(mid 173.025542 176.641699)
		(end 172.629562 176.477679)
		(width 0.16)
		(layer "B.Cu")
		(net 383)
	)
	(arc
		(start 176.63656 171.674127)
		(mid 176.563337 171.850903)
		(end 176.63656 172.027679)
		(width 0.16)
		(layer "B.Cu")
		(net 383)
	)
	(arc
		(start 139.35 182.625)
		(mid 137.322819 182.221768)
		(end 135.604259 181.073463)
		(width 0.16)
		(layer "B.Cu")
		(net 383)
	)
	(arc
		(start 174.699133 173.965198)
		(mid 174.522356 173.891975)
		(end 174.345579 173.965198)
		(width 0.16)
		(layer "B.Cu")
		(net 383)
	)
	(arc
		(start 178.135649 170.528636)
		(mid 177.958872 170.455413)
		(end 177.782096 170.528637)
		(width 0.16)
		(layer "B.Cu")
		(net 383)
	)
	(arc
		(start 172.408073 176.25619)
		(mid 172.231296 176.182967)
		(end 172.054519 176.25619)
		(width 0.16)
		(layer "B.Cu")
		(net 383)
	)
	(arc
		(start 172.05452 176.25619)
		(mid 171.981297 176.432966)
		(end 172.05452 176.609742)
		(width 0.16)
		(layer "B.Cu")
		(net 383)
	)
	(arc
		(start 179.149087 170.750114)
		(mid 178.753107 170.914134)
		(end 178.357127 170.750114)
		(width 0.16)
		(layer "B.Cu")
		(net 383)
	)
	(segment
		(start 181.5005 162.4995)
		(end 182 162)
		(width 0.256)
		(layer "F.Cu")
		(net 384)
	)
	(via
		(at 181.5005 162.4995)
		(size 0.45)
		(drill 0.1)
		(layers "F.Cu" "B.Cu")
		(remove_unused_layers yes)
		(keep_end_layers yes)
		(zone_layer_connections)
		(net 384)
	)
	(segment
		(start 181.4905 166.9695)
		(end 181.4905 166.957)
		(width 0.1)
		(layer "B.Cu")
		(net 384)
	)
	(segment
		(start 181.321211 162.1095)
		(end 181.329789 162.1095)
		(width 0.1)
		(layer "B.Cu")
		(net 384)
	)
	(segment
		(start 181.171211 162.180211)
		(end 181.185856 162.165565)
		(width 0.1)
		(layer "B.Cu")
		(net 384)
	)
	(segment
		(start 181.5005 162.28021)
		(end 181.5005 162.4995)
		(width 0.1)
		(layer "B.Cu")
		(net 384)
	)
	(segment
		(start 181.481661 166.935661)
		(end 181.189161 166.643161)
		(width 0.1)
		(layer "B.Cu")
		(net 384)
	)
	(segment
		(start 181.1005 165.829114)
		(end 181.1005 162.350922)
		(width 0.1)
		(layer "B.Cu")
		(net 384)
	)
	(segment
		(start 181.1005 165.844618)
		(end 181.1005 165.829114)
		(width 0.1)
		(layer "B.Cu")
		(net 384)
	)
	(segment
		(start 181.384996 166.144618)
		(end 181.384996 166.129114)
		(width 0.1)
		(layer "B.Cu")
		(net 384)
	)
	(arc
		(start 181.1005 166.429114)
		(mid 181.142163 166.328529)
		(end 181.242748 166.286866)
		(width 0.1)
		(layer "B.Cu")
		(net 384)
	)
	(arc
		(start 181.185856 162.165565)
		(mid 181.247957 162.12407)
		(end 181.321211 162.1095)
		(width 0.1)
		(layer "B.Cu")
		(net 384)
	)
	(arc
		(start 181.242748 166.286866)
		(mid 181.343333 166.245203)
		(end 181.384996 166.144618)
		(width 0.1)
		(layer "B.Cu")
		(net 384)
	)
	(arc
		(start 181.384996 166.129114)
		(mid 181.343333 166.028529)
		(end 181.242748 165.986866)
		(width 0.1)
		(layer "B.Cu")
		(net 384)
	)
	(arc
		(start 181.242748 165.986866)
		(mid 181.142163 165.945203)
		(end 181.1005 165.844618)
		(width 0.1)
		(layer "B.Cu")
		(net 384)
	)
	(arc
		(start 181.4505 162.1595)
		(mid 181.487505 162.214882)
		(end 181.5005 162.28021)
		(width 0.1)
		(layer "B.Cu")
		(net 384)
	)
	(arc
		(start 181.1005 162.350922)
		(mid 181.118877 162.258533)
		(end 181.171211 162.180211)
		(width 0.1)
		(layer "B.Cu")
		(net 384)
	)
	(arc
		(start 181.4905 166.957)
		(mid 181.488202 166.945451)
		(end 181.481661 166.935661)
		(width 0.1)
		(layer "B.Cu")
		(net 384)
	)
	(arc
		(start 181.329789 162.1095)
		(mid 181.395117 162.122494)
		(end 181.4505 162.1595)
		(width 0.1)
		(layer "B.Cu")
		(net 384)
	)
	(arc
		(start 181.189161 166.643161)
		(mid 181.123542 166.544955)
		(end 181.1005 166.429114)
		(width 0.1)
		(layer "B.Cu")
		(net 384)
	)
	(segment
		(start 177.9995 154.0005)
		(end 177.5 154.5)
		(width 0.256)
		(layer "F.Cu")
		(net 385)
	)
	(segment
		(start 123.766 186.742)
		(end 123.766 186.232)
		(width 0.201)
		(layer "F.Cu")
		(net 385)
	)
	(segment
		(start 123.766 186.232)
		(end 124.076 185.922)
		(width 0.201)
		(layer "F.Cu")
		(net 385)
	)
	(segment
		(start 124.076 185.922)
		(end 124.076 184.778)
		(width 0.201)
		(layer "F.Cu")
		(net 385)
	)
	(via
		(at 177.5 154.5)
		(size 0.45)
		(drill 0.1)
		(layers "F.Cu" "B.Cu")
		(remove_unused_layers yes)
		(keep_end_layers yes)
		(zone_layer_connections)
		(net 385)
	)
	(via
		(at 123.766 186.222)
		(size 0.45)
		(drill 0.1)
		(layers "F.Cu" "B.Cu")
		(remove_unused_layers yes)
		(keep_end_layers yes)
		(zone_layer_connections)
		(net 385)
	)
	(segment
		(start 142.1 159.6)
		(end 138.7 163)
		(width 0.1)
		(layer "In9.Cu")
		(net 385)
	)
	(segment
		(start 178 155)
		(end 178 155.7)
		(width 0.1)
		(layer "In9.Cu")
		(net 385)
	)
	(segment
		(start 126.7895 183.1)
		(end 123.766 186.1235)
		(width 0.1)
		(layer "In9.Cu")
		(net 385)
	)
	(segment
		(start 135.9 166.169669)
		(end 130.2 171.869669)
		(width 0.1)
		(layer "In9.Cu")
		(net 385)
	)
	(segment
		(start 127.9 176.8)
		(end 127.9 180.5)
		(width 0.1)
		(layer "In9.Cu")
		(net 385)
	)
	(segment
		(start 168.9125 158.95)
		(end 158.45 158.95)
		(width 0.1)
		(layer "In9.Cu")
		(net 385)
	)
	(segment
		(start 171.8625 156)
		(end 168.9125 158.95)
		(width 0.1)
		(layer "In9.Cu")
		(net 385)
	)
	(segment
		(start 177.7 156)
		(end 171.8625 156)
		(width 0.1)
		(layer "In9.Cu")
		(net 385)
	)
	(segment
		(start 158.45 158.95)
		(end 157.5 158)
		(width 0.1)
		(layer "In9.Cu")
		(net 385)
	)
	(segment
		(start 145.4 158.6)
		(end 144.4 159.6)
		(width 0.1)
		(layer "In9.Cu")
		(net 385)
	)
	(segment
		(start 144.4 159.6)
		(end 142.1 159.6)
		(width 0.1)
		(layer "In9.Cu")
		(net 385)
	)
	(segment
		(start 129.4 182.4)
		(end 128.7 183.1)
		(width 0.1)
		(layer "In9.Cu")
		(net 385)
	)
	(segment
		(start 127.9 180.5)
		(end 129.4 182)
		(width 0.1)
		(layer "In9.Cu")
		(net 385)
	)
	(segment
		(start 152.2 158)
		(end 151.6 158.6)
		(width 0.1)
		(layer "In9.Cu")
		(net 385)
	)
	(segment
		(start 157.5 158)
		(end 152.2 158)
		(width 0.1)
		(layer "In9.Cu")
		(net 385)
	)
	(segment
		(start 128.7 183.1)
		(end 126.7895 183.1)
		(width 0.1)
		(layer "In9.Cu")
		(net 385)
	)
	(segment
		(start 151.6 158.6)
		(end 145.4 158.6)
		(width 0.1)
		(layer "In9.Cu")
		(net 385)
	)
	(segment
		(start 130.2 171.869669)
		(end 130.2 174.5)
		(width 0.1)
		(layer "In9.Cu")
		(net 385)
	)
	(segment
		(start 177.5 154.5)
		(end 178 155)
		(width 0.1)
		(layer "In9.Cu")
		(net 385)
	)
	(segment
		(start 178 155.7)
		(end 177.7 156)
		(width 0.1)
		(layer "In9.Cu")
		(net 385)
	)
	(segment
		(start 135.9 164.1)
		(end 135.9 166.169669)
		(width 0.1)
		(layer "In9.Cu")
		(net 385)
	)
	(segment
		(start 138.7 163)
		(end 137 163)
		(width 0.1)
		(layer "In9.Cu")
		(net 385)
	)
	(segment
		(start 137 163)
		(end 135.9 164.1)
		(width 0.1)
		(layer "In9.Cu")
		(net 385)
	)
	(segment
		(start 129.4 182)
		(end 129.4 182.4)
		(width 0.1)
		(layer "In9.Cu")
		(net 385)
	)
	(segment
		(start 130.2 174.5)
		(end 127.9 176.8)
		(width 0.1)
		(layer "In9.Cu")
		(net 385)
	)
	(segment
		(start 162.625 163.349998)
		(end 163.685001 163.349998)
		(width 0.16)
		(layer "F.Cu")
		(net 386)
	)
	(segment
		(start 163.685001 163.349998)
		(end 163.97 163.064999)
		(width 0.16)
		(layer "F.Cu")
		(net 386)
	)
	(segment
		(start 164.955 163.064999)
		(end 165.285 163.394999)
		(width 0.16)
		(layer "F.Cu")
		(net 387)
	)
	(segment
		(start 164.93 163.064999)
		(end 164.955 163.064999)
		(width 0.16)
		(layer "F.Cu")
		(net 387)
	)
	(segment
		(start 189.000501 160.0005)
		(end 189.5 160.499999)
		(width 0.256)
		(layer "F.Cu")
		(net 387)
	)
	(segment
		(start 166.1745 163.394998)
		(end 166.319499 163.249999)
		(width 0.16)
		(layer "F.Cu")
		(net 387)
	)
	(segment
		(start 165.285 163.394999)
		(end 166.1745 163.394998)
		(width 0.16)
		(layer "F.Cu")
		(net 387)
	)
	(via
		(at 189.5 160.499999)
		(size 0.45)
		(drill 0.1)
		(layers "F.Cu" "B.Cu")
		(remove_unused_layers yes)
		(keep_end_layers yes)
		(zone_layer_connections)
		(net 387)
	)
	(via
		(at 166.319499 163.249999)
		(size 0.45)
		(drill 0.1)
		(layers "F.Cu" "B.Cu")
		(remove_unused_layers yes)
		(keep_end_layers yes)
		(zone_layer_connections)
		(net 387)
	)
	(segment
		(start 165.803163 163.211741)
		(end 165.803163 162.288259)
		(width 0.1)
		(layer "In6.Cu")
		(net 387)
	)
	(segment
		(start 166.041421 163.449999)
		(end 165.803163 163.211741)
		(width 0.1)
		(layer "In6.Cu")
		(net 387)
	)
	(segment
		(start 166.382198 162.114)
		(end 166.391596 162.123398)
		(width 0.1)
		(layer "In6.Cu")
		(net 387)
	)
	(segment
		(start 165.803163 162.288259)
		(end 165.977422 162.114)
		(width 0.1)
		(layer "In6.Cu")
		(net 387)
	)
	(segment
		(start 166.319499 163.249999)
		(end 166.119499 163.449999)
		(width 0.1)
		(layer "In6.Cu")
		(net 387)
	)
	(segment
		(start 167.991422 160.1)
		(end 189.100001 160.1)
		(width 0.1)
		(layer "In6.Cu")
		(net 387)
	)
	(segment
		(start 166.709794 161.805199)
		(end 166.657106 161.752511)
		(width 0.1)
		(layer "In6.Cu")
		(net 387)
	)
	(segment
		(start 166.119499 163.449999)
		(end 166.041421 163.449999)
		(width 0.1)
		(layer "In6.Cu")
		(net 387)
	)
	(segment
		(start 166.657107 161.434314)
		(end 167.991422 160.1)
		(width 0.1)
		(layer "In6.Cu")
		(net 387)
	)
	(segment
		(start 189.100001 160.1)
		(end 189.5 160.499999)
		(width 0.1)
		(layer "In6.Cu")
		(net 387)
	)
	(segment
		(start 166.657106 161.434313)
		(end 166.657107 161.434314)
		(width 0.1)
		(layer "In6.Cu")
		(net 387)
	)
	(segment
		(start 166.709794 161.805198)
		(end 166.709794 161.805199)
		(width 0.1)
		(layer "In6.Cu")
		(net 387)
	)
	(arc
		(start 165.977422 162.114)
		(mid 166.17981 162.030168)
		(end 166.382198 162.114)
		(width 0.1)
		(layer "In6.Cu")
		(net 387)
	)
	(arc
		(start 166.709794 162.123398)
		(mid 166.775695 161.964298)
		(end 166.709794 161.805198)
		(width 0.1)
		(layer "In6.Cu")
		(net 387)
	)
	(arc
		(start 166.391596 162.123398)
		(mid 166.550695 162.189299)
		(end 166.709794 162.123398)
		(width 0.1)
		(layer "In6.Cu")
		(net 387)
	)
	(arc
		(start 166.657106 161.752511)
		(mid 166.591205 161.593412)
		(end 166.657106 161.434313)
		(width 0.1)
		(layer "In6.Cu")
		(net 387)
	)
	(segment
		(start 177.9995 157.0005)
		(end 177.5 157.5)
		(width 0.256)
		(layer "F.Cu")
		(net 388)
	)
	(via
		(at 177.5 157.5)
		(size 0.45)
		(drill 0.1)
		(layers "F.Cu" "B.Cu")
		(remove_unused_layers yes)
		(keep_end_layers yes)
		(zone_layer_connections)
		(net 388)
	)
	(via
		(at 141.124499 170.599)
		(size 0.45)
		(drill 0.1)
		(layers "F.Cu" "B.Cu")
		(remove_unused_layers yes)
		(keep_end_layers yes)
		(zone_layer_connections)
		(net 388)
	)
	(segment
		(start 141.124499 169.884)
		(end 141.124499 170.599)
		(width 0.15)
		(layer "B.Cu")
		(net 388)
	)
	(segment
		(start 141.124499 170.599)
		(end 141.124499 173.624499)
		(width 0.1)
		(layer "In9.Cu")
		(net 388)
	)
	(segment
		(start 155.5 175)
		(end 164 166.5)
		(width 0.1)
		(layer "In9.Cu")
		(net 388)
	)
	(segment
		(start 164 166.5)
		(end 167 166.5)
		(width 0.1)
		(layer "In9.Cu")
		(net 388)
	)
	(segment
		(start 176.7 159)
		(end 177 158.7)
		(width 0.1)
		(layer "In9.Cu")
		(net 388)
	)
	(segment
		(start 177 158.7)
		(end 177 158)
		(width 0.1)
		(layer "In9.Cu")
		(net 388)
	)
	(segment
		(start 142.5 175)
		(end 155.5 175)
		(width 0.1)
		(layer "In9.Cu")
		(net 388)
	)
	(segment
		(start 177 158)
		(end 177.5 157.5)
		(width 0.1)
		(layer "In9.Cu")
		(net 388)
	)
	(segment
		(start 167 166.5)
		(end 174.5 159)
		(width 0.1)
		(layer "In9.Cu")
		(net 388)
	)
	(segment
		(start 174.5 159)
		(end 176.7 159)
		(width 0.1)
		(layer "In9.Cu")
		(net 388)
	)
	(segment
		(start 141.124499 173.624499)
		(end 142.5 175)
		(width 0.1)
		(layer "In9.Cu")
		(net 388)
	)
	(segment
		(start 162.625 163.749999)
		(end 163.685 163.749999)
		(width 0.16)
		(layer "F.Cu")
		(net 389)
	)
	(segment
		(start 163.685 163.749999)
		(end 163.97 164.034999)
		(width 0.16)
		(layer "F.Cu")
		(net 389)
	)
	(segment
		(start 147.781498 167.54)
		(end 147.775499 167.534)
		(width 0.15)
		(layer "F.Cu")
		(net 390)
	)
	(segment
		(start 142.433 167.640499)
		(end 142.424499 167.649)
		(width 0.15)
		(layer "F.Cu")
		(net 390)
	)
	(segment
		(start 147.781499 168.884)
		(end 147.781498 167.54)
		(width 0.15)
		(layer "F.Cu")
		(net 390)
	)
	(segment
		(start 142.433 166.772)
		(end 142.433 167.640499)
		(width 0.15)
		(layer "F.Cu")
		(net 390)
	)
	(via
		(at 142.424499 167.649)
		(size 0.45)
		(drill 0.1)
		(layers "F.Cu" "B.Cu")
		(remove_unused_layers yes)
		(keep_end_layers yes)
		(zone_layer_connections)
		(net 390)
	)
	(via
		(at 147.775499 167.534)
		(size 0.45)
		(drill 0.1)
		(layers "F.Cu" "B.Cu")
		(remove_unused_layers yes)
		(keep_end_layers yes)
		(zone_layer_connections)
		(net 390)
	)
	(segment
		(start 142.424499 168.664)
		(end 142.174499 168.914)
		(width 0.15)
		(layer "B.Cu")
		(net 390)
	)
	(segment
		(start 146.790499 166.549)
		(end 142.974499 166.549)
		(width 0.15)
		(layer "B.Cu")
		(net 390)
	)
	(segment
		(start 147.775499 167.534)
		(end 146.790499 166.549)
		(width 0.15)
		(layer "B.Cu")
		(net 390)
	)
	(segment
		(start 142.424499 167.649)
		(end 142.424499 168.664)
		(width 0.15)
		(layer "B.Cu")
		(net 390)
	)
	(segment
		(start 142.424499 167.099)
		(end 142.424499 167.649)
		(width 0.15)
		(layer "B.Cu")
		(net 390)
	)
	(segment
		(start 142.974499 166.549)
		(end 142.424499 167.099)
		(width 0.15)
		(layer "B.Cu")
		(net 390)
	)
	(segment
		(start 176.9995 157.0005)
		(end 176.5 157.5)
		(width 0.256)
		(layer "F.Cu")
		(net 391)
	)
	(via
		(at 141.724499 171.074)
		(size 0.45)
		(drill 0.1)
		(layers "F.Cu" "B.Cu")
		(remove_unused_layers yes)
		(keep_end_layers yes)
		(zone_layer_connections)
		(net 391)
	)
	(via
		(at 176.5 157.5)
		(size 0.45)
		(drill 0.1)
		(layers "F.Cu" "B.Cu")
		(remove_unused_layers yes)
		(keep_end_layers yes)
		(zone_layer_connections)
		(net 391)
	)
	(segment
		(start 141.724499 170.334)
		(end 141.724499 171.074)
		(width 0.15)
		(layer "B.Cu")
		(net 391)
	)
	(segment
		(start 142.174499 169.884)
		(end 141.724499 170.334)
		(width 0.15)
		(layer "B.Cu")
		(net 391)
	)
	(segment
		(start 155 174.5)
		(end 143 174.5)
		(width 0.1)
		(layer "In9.Cu")
		(net 391)
	)
	(segment
		(start 174.5 158)
		(end 166.5 166)
		(width 0.1)
		(layer "In9.Cu")
		(net 391)
	)
	(segment
		(start 166.5 166)
		(end 163.5 166)
		(width 0.1)
		(layer "In9.Cu")
		(net 391)
	)
	(segment
		(start 141.724499 173.224499)
		(end 141.724499 171.074)
		(width 0.1)
		(layer "In9.Cu")
		(net 391)
	)
	(segment
		(start 163.5 166)
		(end 155 174.5)
		(width 0.1)
		(layer "In9.Cu")
		(net 391)
	)
	(segment
		(start 143 174.5)
		(end 141.724499 173.224499)
		(width 0.1)
		(layer "In9.Cu")
		(net 391)
	)
	(segment
		(start 176.25 158)
		(end 174.5 158)
		(width 0.1)
		(layer "In9.Cu")
		(net 391)
	)
	(segment
		(start 176.5 157.5)
		(end 176.5 157.75)
		(width 0.1)
		(layer "In9.Cu")
		(net 391)
	)
	(segment
		(start 176.5 157.75)
		(end 176.25 158)
		(width 0.1)
		(layer "In9.Cu")
		(net 391)
	)
	(segment
		(start 142.933 168.140499)
		(end 142.924499 168.149)
		(width 0.15)
		(layer "F.Cu")
		(net 392)
	)
	(segment
		(start 147.281498 168.884)
		(end 147.281499 168.034)
		(width 0.15)
		(layer "F.Cu")
		(net 392)
	)
	(segment
		(start 142.933 166.772)
		(end 142.933 168.140499)
		(width 0.15)
		(layer "F.Cu")
		(net 392)
	)
	(via
		(at 142.924499 168.149)
		(size 0.45)
		(drill 0.1)
		(layers "F.Cu" "B.Cu")
		(remove_unused_layers yes)
		(keep_end_layers yes)
		(zone_layer_connections)
		(net 392)
	)
	(via
		(at 147.281499 168.034)
		(size 0.45)
		(drill 0.1)
		(layers "F.Cu" "B.Cu")
		(remove_unused_layers yes)
		(keep_end_layers yes)
		(zone_layer_connections)
		(net 392)
	)
	(segment
		(start 146.246499 166.999)
		(end 147.281499 168.034)
		(width 0.15)
		(layer "B.Cu")
		(net 392)
	)
	(segment
		(start 142.924499 168.149)
		(end 142.924499 167.249)
		(width 0.15)
		(layer "B.Cu")
		(net 392)
	)
	(segment
		(start 142.924499 168.614)
		(end 143.224499 168.914)
		(width 0.15)
		(layer "B.Cu")
		(net 392)
	)
	(segment
		(start 143.174499 166.999)
		(end 146.246499 166.999)
		(width 0.15)
		(layer "B.Cu")
		(net 392)
	)
	(segment
		(start 142.924499 168.149)
		(end 142.924499 168.614)
		(width 0.15)
		(layer "B.Cu")
		(net 392)
	)
	(segment
		(start 142.924499 167.249)
		(end 143.174499 166.999)
		(width 0.15)
		(layer "B.Cu")
		(net 392)
	)
	(segment
		(start 140.625 151.075)
		(end 140.625 151.175)
		(width 0.256)
		(layer "F.Cu")
		(net 393)
	)
	(segment
		(start 135.425 146.734)
		(end 135.425 148.475)
		(width 0.256)
		(layer "F.Cu")
		(net 393)
	)
	(segment
		(start 138.88 149.33)
		(end 140.625 151.075)
		(width 0.256)
		(layer "F.Cu")
		(net 393)
	)
	(segment
		(start 175.999501 146.9995)
		(end 175.5 146.5)
		(width 0.256)
		(layer "F.Cu")
		(net 393)
	)
	(segment
		(start 135.425 148.475)
		(end 136.28 149.33)
		(width 0.256)
		(layer "F.Cu")
		(net 393)
	)
	(segment
		(start 136.28 149.33)
		(end 138.88 149.33)
		(width 0.256)
		(layer "F.Cu")
		(net 393)
	)
	(via
		(at 175.5 146.5)
		(size 0.45)
		(drill 0.1)
		(layers "F.Cu" "B.Cu")
		(remove_unused_layers yes)
		(keep_end_layers yes)
		(zone_layer_connections)
		(net 393)
	)
	(via
		(at 140.625 151.175)
		(size 0.45)
		(drill 0.1)
		(layers "F.Cu" "B.Cu")
		(remove_unused_layers yes)
		(keep_end_layers yes)
		(zone_layer_connections)
		(net 393)
	)
	(segment
		(start 140.625 151.89)
		(end 140.65 151.915)
		(width 0.256)
		(layer "B.Cu")
		(net 393)
	)
	(segment
		(start 140.625 150.51)
		(end 140.625 151.89)
		(width 0.256)
		(layer "B.Cu")
		(net 393)
	)
	(segment
		(start 171.35 144.75)
		(end 171.35 144.932621)
		(width 0.1)
		(layer "In9.Cu")
		(net 393)
	)
	(segment
		(start 169.35 144.75)
		(end 169.35 144.932621)
		(width 0.1)
		(layer "In9.Cu")
		(net 393)
	)
	(segment
		(start 170.35 144.75)
		(end 170.35 144.932603)
		(width 0.1)
		(layer "In9.Cu")
		(net 393)
	)
	(segment
		(start 171.85 144.932621)
		(end 171.85 144.75)
		(width 0.1)
		(layer "In9.Cu")
		(net 393)
	)
	(segment
		(start 165.85 144.932621)
		(end 165.85 144.75)
		(width 0.1)
		(layer "In9.Cu")
		(net 393)
	)
	(segment
		(start 165.35 144.75)
		(end 165.35 144.932621)
		(width 0.1)
		(layer "In9.Cu")
		(net 393)
	)
	(segment
		(start 172.1 144.5)
		(end 172.65 144.5)
		(width 0.1)
		(layer "In9.Cu")
		(net 393)
	)
	(segment
		(start 168.35 144.75)
		(end 168.35 144.932621)
		(width 0.1)
		(layer "In9.Cu")
		(net 393)
	)
	(segment
		(start 172.66 144.5)
		(end 174.66 146.5)
		(width 0.1)
		(layer "In9.Cu")
		(net 393)
	)
	(segment
		(start 152.2 146.9)
		(end 153.7 146.9)
		(width 0.1)
		(layer "In9.Cu")
		(net 393)
	)
	(segment
		(start 170.85 144.932603)
		(end 170.85 144.75)
		(width 0.1)
		(layer "In9.Cu")
		(net 393)
	)
	(segment
		(start 168.85 144.932621)
		(end 168.85 144.75)
		(width 0.1)
		(layer "In9.Cu")
		(net 393)
	)
	(segment
		(start 167.85 144.932621)
		(end 167.85 144.75)
		(width 0.1)
		(layer "In9.Cu")
		(net 393)
	)
	(segment
		(start 146.6 152.5)
		(end 152.2 146.9)
		(width 0.1)
		(layer "In9.Cu")
		(net 393)
	)
	(segment
		(start 166.35 144.75)
		(end 166.35 144.932621)
		(width 0.1)
		(layer "In9.Cu")
		(net 393)
	)
	(segment
		(start 169.85 144.932621)
		(end 169.85 144.75)
		(width 0.1)
		(layer "In9.Cu")
		(net 393)
	)
	(segment
		(start 174.66 146.5)
		(end 175.5 146.5)
		(width 0.1)
		(layer "In9.Cu")
		(net 393)
	)
	(segment
		(start 153.7 146.9)
		(end 156.1 144.5)
		(width 0.1)
		(layer "In9.Cu")
		(net 393)
	)
	(segment
		(start 140.625 152.125)
		(end 141 152.5)
		(width 0.1)
		(layer "In9.Cu")
		(net 393)
	)
	(segment
		(start 166.85 144.932621)
		(end 166.85 144.75)
		(width 0.1)
		(layer "In9.Cu")
		(net 393)
	)
	(segment
		(start 140.625 151.175)
		(end 140.625 152.125)
		(width 0.1)
		(layer "In9.Cu")
		(net 393)
	)
	(segment
		(start 167.35 144.75)
		(end 167.35 144.932621)
		(width 0.1)
		(layer "In9.Cu")
		(net 393)
	)
	(segment
		(start 172.65 144.5)
		(end 172.66 144.5)
		(width 0.1)
		(layer "In9.Cu")
		(net 393)
	)
	(segment
		(start 156.1 144.5)
		(end 165.1 144.5)
		(width 0.1)
		(layer "In9.Cu")
		(net 393)
	)
	(segment
		(start 141 152.5)
		(end 146.6 152.5)
		(width 0.1)
		(layer "In9.Cu")
		(net 393)
	)
	(arc
		(start 171.6 145.182621)
		(mid 171.776777 145.109398)
		(end 171.85 144.932621)
		(width 0.1)
		(layer "In9.Cu")
		(net 393)
	)
	(arc
		(start 167.85 144.75)
		(mid 167.923223 144.573223)
		(end 168.1 144.5)
		(width 0.1)
		(layer "In9.Cu")
		(net 393)
	)
	(arc
		(start 166.1 144.5)
		(mid 166.276777 144.573223)
		(end 166.35 144.75)
		(width 0.1)
		(layer "In9.Cu")
		(net 393)
	)
	(arc
		(start 168.85 144.75)
		(mid 168.923223 144.573223)
		(end 169.1 144.5)
		(width 0.1)
		(layer "In9.Cu")
		(net 393)
	)
	(arc
		(start 170.1 144.5)
		(mid 170.276777 144.573223)
		(end 170.35 144.75)
		(width 0.1)
		(layer "In9.Cu")
		(net 393)
	)
	(arc
		(start 169.35 144.932621)
		(mid 169.423223 145.109398)
		(end 169.6 145.182621)
		(width 0.1)
		(layer "In9.Cu")
		(net 393)
	)
	(arc
		(start 167.6 145.182621)
		(mid 167.776777 145.109398)
		(end 167.85 144.932621)
		(width 0.1)
		(layer "In9.Cu")
		(net 393)
	)
	(arc
		(start 166.85 144.75)
		(mid 166.923223 144.573223)
		(end 167.1 144.5)
		(width 0.1)
		(layer "In9.Cu")
		(net 393)
	)
	(arc
		(start 165.6 145.182621)
		(mid 165.776777 145.109398)
		(end 165.85 144.932621)
		(width 0.1)
		(layer "In9.Cu")
		(net 393)
	)
	(arc
		(start 170.35 144.932603)
		(mid 170.423223 145.10938)
		(end 170.6 145.182603)
		(width 0.1)
		(layer "In9.Cu")
		(net 393)
	)
	(arc
		(start 167.1 144.5)
		(mid 167.276777 144.573223)
		(end 167.35 144.75)
		(width 0.1)
		(layer "In9.Cu")
		(net 393)
	)
	(arc
		(start 166.6 145.182621)
		(mid 166.776777 145.109398)
		(end 166.85 144.932621)
		(width 0.1)
		(layer "In9.Cu")
		(net 393)
	)
	(arc
		(start 171.85 144.75)
		(mid 171.923223 144.573223)
		(end 172.1 144.5)
		(width 0.1)
		(layer "In9.Cu")
		(net 393)
	)
	(arc
		(start 169.1 144.5)
		(mid 169.276777 144.573223)
		(end 169.35 144.75)
		(width 0.1)
		(layer "In9.Cu")
		(net 393)
	)
	(arc
		(start 165.1 144.5)
		(mid 165.276777 144.573223)
		(end 165.35 144.75)
		(width 0.1)
		(layer "In9.Cu")
		(net 393)
	)
	(arc
		(start 170.6 145.182603)
		(mid 170.776777 145.10938)
		(end 170.85 144.932603)
		(width 0.1)
		(layer "In9.Cu")
		(net 393)
	)
	(arc
		(start 168.35 144.932621)
		(mid 168.423223 145.109398)
		(end 168.6 145.182621)
		(width 0.1)
		(layer "In9.Cu")
		(net 393)
	)
	(arc
		(start 168.1 144.5)
		(mid 168.276777 144.573223)
		(end 168.35 144.75)
		(width 0.1)
		(layer "In9.Cu")
		(net 393)
	)
	(arc
		(start 168.6 145.182621)
		(mid 168.776777 145.109398)
		(end 168.85 144.932621)
		(width 0.1)
		(layer "In9.Cu")
		(net 393)
	)
	(arc
		(start 169.6 145.182621)
		(mid 169.776777 145.109398)
		(end 169.85 144.932621)
		(width 0.1)
		(layer "In9.Cu")
		(net 393)
	)
	(arc
		(start 166.35 144.932621)
		(mid 166.423223 145.109398)
		(end 166.6 145.182621)
		(width 0.1)
		(layer "In9.Cu")
		(net 393)
	)
	(arc
		(start 165.85 144.75)
		(mid 165.923223 144.573223)
		(end 166.1 144.5)
		(width 0.1)
		(layer "In9.Cu")
		(net 393)
	)
	(arc
		(start 171.1 144.5)
		(mid 171.276777 144.573223)
		(end 171.35 144.75)
		(width 0.1)
		(layer "In9.Cu")
		(net 393)
	)
	(arc
		(start 165.35 144.932621)
		(mid 165.423223 145.109398)
		(end 165.6 145.182621)
		(width 0.1)
		(layer "In9.Cu")
		(net 393)
	)
	(arc
		(start 167.35 144.932621)
		(mid 167.423223 145.109398)
		(end 167.6 145.182621)
		(width 0.1)
		(layer "In9.Cu")
		(net 393)
	)
	(arc
		(start 171.35 144.932621)
		(mid 171.423223 145.109398)
		(end 171.6 145.182621)
		(width 0.1)
		(layer "In9.Cu")
		(net 393)
	)
	(arc
		(start 170.85 144.75)
		(mid 170.923223 144.573223)
		(end 171.1 144.5)
		(width 0.1)
		(layer "In9.Cu")
		(net 393)
	)
	(arc
		(start 169.85 144.75)
		(mid 169.923223 144.573223)
		(end 170.1 144.5)
		(width 0.1)
		(layer "In9.Cu")
		(net 393)
	)
	(segment
		(start 134.925 146.734)
		(end 134.925 149.099501)
		(width 0.256)
		(layer "F.Cu")
		(net 394)
	)
	(segment
		(start 134.925 149.099501)
		(end 135.745499 149.92)
		(width 0.256)
		(layer "F.Cu")
		(net 394)
	)
	(segment
		(start 138.32 149.92)
		(end 139.575 151.175)
		(width 0.256)
		(layer "F.Cu")
		(net 394)
	)
	(segment
		(start 176.9995 148.9995)
		(end 176.5 148.5)
		(width 0.256)
		(layer "F.Cu")
		(net 394)
	)
	(segment
		(start 135.745499 149.92)
		(end 138.32 149.92)
		(width 0.256)
		(layer "F.Cu")
		(net 394)
	)
	(via
		(at 139.575 151.175)
		(size 0.45)
		(drill 0.1)
		(layers "F.Cu" "B.Cu")
		(remove_unused_layers yes)
		(keep_end_layers yes)
		(zone_layer_connections)
		(net 394)
	)
	(via
		(at 176.5 148.5)
		(size 0.45)
		(drill 0.1)
		(layers "F.Cu" "B.Cu")
		(remove_unused_layers yes)
		(keep_end_layers yes)
		(zone_layer_connections)
		(net 394)
	)
	(segment
		(start 139.575 151.89)
		(end 139.6 151.915)
		(width 0.256)
		(layer "B.Cu")
		(net 394)
	)
	(segment
		(start 139.575 150.51)
		(end 139.575 151.89)
		(width 0.256)
		(layer "B.Cu")
		(net 394)
	)
	(segment
		(start 157.48 146.47)
		(end 157.69 146.47)
		(width 0.1)
		(layer "In9.Cu")
		(net 394)
	)
	(segment
		(start 155.05 148.9)
		(end 157.48 146.47)
		(width 0.1)
		(layer "In9.Cu")
		(net 394)
	)
	(segment
		(start 159.615 146.183392)
		(end 159.615 146.195)
		(width 0.1)
		(layer "In9.Cu")
		(net 394)
	)
	(segment
		(start 160.165 146.195)
		(end 160.165 146.183392)
		(width 0.1)
		(layer "In9.Cu")
		(net 394)
	)
	(segment
		(start 161.265 146.195)
		(end 161.265 146.183392)
		(width 0.1)
		(layer "In9.Cu")
		(net 394)
	)
	(segment
		(start 157.965 146.195)
		(end 157.965 146.183392)
		(width 0.1)
		(layer "In9.Cu")
		(net 394)
	)
	(segment
		(start 164.015 146.183408)
		(end 164.015 146.195)
		(width 0.1)
		(layer "In9.Cu")
		(net 394)
	)
	(segment
		(start 160.715 146.183392)
		(end 160.715 146.195)
		(width 0.1)
		(layer "In9.Cu")
		(net 394)
	)
	(segment
		(start 174.4 148)
		(end 176 148)
		(width 0.1)
		(layer "In9.Cu")
		(net 394)
	)
	(segment
		(start 140.5 153.5)
		(end 148.1 153.5)
		(width 0.1)
		(layer "In9.Cu")
		(net 394)
	)
	(segment
		(start 158.515 146.183392)
		(end 158.515 146.195)
		(width 0.1)
		(layer "In9.Cu")
		(net 394)
	)
	(segment
		(start 159.065 146.195)
		(end 159.065 146.183392)
		(width 0.1)
		(layer "In9.Cu")
		(net 394)
	)
	(segment
		(start 164.29 146.47)
		(end 165.950705 146.47)
		(width 0.1)
		(layer "In9.Cu")
		(net 394)
	)
	(segment
		(start 152.7 148.9)
		(end 155.05 148.9)
		(width 0.1)
		(layer "In9.Cu")
		(net 394)
	)
	(segment
		(start 165.950705 146.47)
		(end 172.87 146.47)
		(width 0.1)
		(layer "In9.Cu")
		(net 394)
	)
	(segment
		(start 161.815 146.183392)
		(end 161.815 146.195)
		(width 0.1)
		(layer "In9.Cu")
		(net 394)
	)
	(segment
		(start 148.1 153.5)
		(end 152.7 148.9)
		(width 0.1)
		(layer "In9.Cu")
		(net 394)
	)
	(segment
		(start 176 148)
		(end 176.5 148.5)
		(width 0.1)
		(layer "In9.Cu")
		(net 394)
	)
	(segment
		(start 139.575 151.175)
		(end 139.575 152.575)
		(width 0.1)
		(layer "In9.Cu")
		(net 394)
	)
	(segment
		(start 162.365 146.195)
		(end 162.365 146.183392)
		(width 0.1)
		(layer "In9.Cu")
		(net 394)
	)
	(segment
		(start 163.465 146.195)
		(end 163.465 146.183408)
		(width 0.1)
		(layer "In9.Cu")
		(net 394)
	)
	(segment
		(start 139.575 152.575)
		(end 140.5 153.5)
		(width 0.1)
		(layer "In9.Cu")
		(net 394)
	)
	(segment
		(start 172.87 146.47)
		(end 174.4 148)
		(width 0.1)
		(layer "In9.Cu")
		(net 394)
	)
	(segment
		(start 162.915 146.183392)
		(end 162.915 146.195)
		(width 0.1)
		(layer "In9.Cu")
		(net 394)
	)
	(arc
		(start 160.165 146.183392)
		(mid 160.245546 145.988938)
		(end 160.44 145.908392)
		(width 0.1)
		(layer "In9.Cu")
		(net 394)
	)
	(arc
		(start 161.54 145.908392)
		(mid 161.734454 145.988938)
		(end 161.815 146.183392)
		(width 0.1)
		(layer "In9.Cu")
		(net 394)
	)
	(arc
		(start 160.715 146.195)
		(mid 160.795546 146.389454)
		(end 160.99 146.47)
		(width 0.1)
		(layer "In9.Cu")
		(net 394)
	)
	(arc
		(start 162.09 146.47)
		(mid 162.284454 146.389454)
		(end 162.365 146.195)
		(width 0.1)
		(layer "In9.Cu")
		(net 394)
	)
	(arc
		(start 160.44 145.908392)
		(mid 160.634454 145.988938)
		(end 160.715 146.183392)
		(width 0.1)
		(layer "In9.Cu")
		(net 394)
	)
	(arc
		(start 158.515 146.195)
		(mid 158.595546 146.389454)
		(end 158.79 146.47)
		(width 0.1)
		(layer "In9.Cu")
		(net 394)
	)
	(arc
		(start 159.89 146.47)
		(mid 160.084454 146.389454)
		(end 160.165 146.195)
		(width 0.1)
		(layer "In9.Cu")
		(net 394)
	)
	(arc
		(start 157.965 146.183392)
		(mid 158.045546 145.988938)
		(end 158.24 145.908392)
		(width 0.1)
		(layer "In9.Cu")
		(net 394)
	)
	(arc
		(start 163.74 145.908408)
		(mid 163.934454 145.988954)
		(end 164.015 146.183408)
		(width 0.1)
		(layer "In9.Cu")
		(net 394)
	)
	(arc
		(start 161.265 146.183392)
		(mid 161.345546 145.988938)
		(end 161.54 145.908392)
		(width 0.1)
		(layer "In9.Cu")
		(net 394)
	)
	(arc
		(start 163.465 146.183408)
		(mid 163.545546 145.988954)
		(end 163.74 145.908408)
		(width 0.1)
		(layer "In9.Cu")
		(net 394)
	)
	(arc
		(start 161.815 146.195)
		(mid 161.895546 146.389454)
		(end 162.09 146.47)
		(width 0.1)
		(layer "In9.Cu")
		(net 394)
	)
	(arc
		(start 159.34 145.908392)
		(mid 159.534454 145.988938)
		(end 159.615 146.183392)
		(width 0.1)
		(layer "In9.Cu")
		(net 394)
	)
	(arc
		(start 158.24 145.908392)
		(mid 158.434454 145.988938)
		(end 158.515 146.183392)
		(width 0.1)
		(layer "In9.Cu")
		(net 394)
	)
	(arc
		(start 159.615 146.195)
		(mid 159.695546 146.389454)
		(end 159.89 146.47)
		(width 0.1)
		(layer "In9.Cu")
		(net 394)
	)
	(arc
		(start 164.015 146.195)
		(mid 164.095546 146.389454)
		(end 164.29 146.47)
		(width 0.1)
		(layer "In9.Cu")
		(net 394)
	)
	(arc
		(start 162.64 145.908392)
		(mid 162.834454 145.988938)
		(end 162.915 146.183392)
		(width 0.1)
		(layer "In9.Cu")
		(net 394)
	)
	(arc
		(start 157.69 146.47)
		(mid 157.884454 146.389454)
		(end 157.965 146.195)
		(width 0.1)
		(layer "In9.Cu")
		(net 394)
	)
	(arc
		(start 163.19 146.47)
		(mid 163.384454 146.389454)
		(end 163.465 146.195)
		(width 0.1)
		(layer "In9.Cu")
		(net 394)
	)
	(arc
		(start 159.065 146.183392)
		(mid 159.145546 145.988938)
		(end 159.34 145.908392)
		(width 0.1)
		(layer "In9.Cu")
		(net 394)
	)
	(arc
		(start 162.365 146.183392)
		(mid 162.445546 145.988938)
		(end 162.64 145.908392)
		(width 0.1)
		(layer "In9.Cu")
		(net 394)
	)
	(arc
		(start 160.99 146.47)
		(mid 161.184454 146.389454)
		(end 161.265 146.195)
		(width 0.1)
		(layer "In9.Cu")
		(net 394)
	)
	(arc
		(start 158.79 146.47)
		(mid 158.984454 146.389454)
		(end 159.065 146.195)
		(width 0.1)
		(layer "In9.Cu")
		(net 394)
	)
	(arc
		(start 162.915 146.195)
		(mid 162.995546 146.389454)
		(end 163.19 146.47)
		(width 0.1)
		(layer "In9.Cu")
		(net 394)
	)
	(segment
		(start 135.265499 150.54)
		(end 137.913553 150.54)
		(width 0.256)
		(layer "F.Cu")
		(net 395)
	)
	(segment
		(start 177.9995 148.9995)
		(end 177.5 148.5)
		(width 0.256)
		(layer "F.Cu")
		(net 395)
	)
	(segment
		(start 137.913553 150.54)
		(end 138.542351 151.168798)
		(width 0.256)
		(layer "F.Cu")
		(net 395)
	)
	(segment
		(start 133.426 146.734)
		(end 133.426 148.700501)
		(width 0.256)
		(layer "F.Cu")
		(net 395)
	)
	(segment
		(start 133.426 148.700501)
		(end 135.265499 150.54)
		(width 0.256)
		(layer "F.Cu")
		(net 395)
	)
	(via
		(at 138.542351 151.168798)
		(size 0.45)
		(drill 0.1)
		(layers "F.Cu" "B.Cu")
		(remove_unused_layers yes)
		(keep_end_layers yes)
		(zone_layer_connections)
		(net 395)
	)
	(via
		(at 177.5 148.5)
		(size 0.45)
		(drill 0.1)
		(layers "F.Cu" "B.Cu")
		(remove_unused_layers yes)
		(keep_end_layers yes)
		(zone_layer_connections)
		(net 395)
	)
	(segment
		(start 138.55 150.51)
		(end 138.55 151.915)
		(width 0.256)
		(layer "B.Cu")
		(net 395)
	)
	(segment
		(start 172.21 147.81)
		(end 159.79 147.81)
		(width 0.1)
		(layer "In9.Cu")
		(net 395)
	)
	(segment
		(start 149.2 154.5)
		(end 140 154.5)
		(width 0.1)
		(layer "In9.Cu")
		(net 395)
	)
	(segment
		(start 157.79535 150.155044)
		(end 157.510926 150.439469)
		(width 0.1)
		(layer "In9.Cu")
		(net 395)
	)
	(segment
		(start 158.25509 149.520349)
		(end 158.167372 149.432631)
		(width 0.1)
		(layer "In9.Cu")
		(net 395)
	)
	(segment
		(start 157.904302 149.34494)
		(end 157.620061 149.62918)
		(width 0.1)
		(layer "In9.Cu")
		(net 395)
	)
	(segment
		(start 152.85 150.85)
		(end 149.2 154.5)
		(width 0.1)
		(layer "In9.Cu")
		(net 395)
	)
	(segment
		(start 159.79 147.81)
		(end 159.175 148.425)
		(width 0.1)
		(layer "In9.Cu")
		(net 395)
	)
	(segment
		(start 140 154.5)
		(end 138.542351 153.042351)
		(width 0.1)
		(layer "In9.Cu")
		(net 395)
	)
	(segment
		(start 158.999828 148.425)
		(end 158.999827 148.424999)
		(width 0.1)
		(layer "In9.Cu")
		(net 395)
	)
	(segment
		(start 138.542351 153.042351)
		(end 138.542351 151.168798)
		(width 0.1)
		(layer "In9.Cu")
		(net 395)
	)
	(segment
		(start 176.98 149.02)
		(end 173.42 149.02)
		(width 0.1)
		(layer "In9.Cu")
		(net 395)
	)
	(segment
		(start 156.876899 150.723102)
		(end 156.75 150.85)
		(width 0.1)
		(layer "In9.Cu")
		(net 395)
	)
	(segment
		(start 157.620061 149.804558)
		(end 157.70775 149.892247)
		(width 0.1)
		(layer "In9.Cu")
		(net 395)
	)
	(segment
		(start 158.71471 149.236164)
		(end 158.430526 149.520349)
		(width 0.1)
		(layer "In9.Cu")
		(net 395)
	)
	(segment
		(start 157.160534 150.439469)
		(end 156.876899 150.723102)
		(width 0.1)
		(layer "In9.Cu")
		(net 395)
	)
	(segment
		(start 173.42 149.02)
		(end 172.21 147.81)
		(width 0.1)
		(layer "In9.Cu")
		(net 395)
	)
	(segment
		(start 158.824655 148.424999)
		(end 158.539404 148.710249)
		(width 0.1)
		(layer "In9.Cu")
		(net 395)
	)
	(segment
		(start 157.70775 149.892247)
		(end 157.79535 149.979848)
		(width 0.1)
		(layer "In9.Cu")
		(net 395)
	)
	(segment
		(start 158.539404 148.88542)
		(end 158.714711 149.060727)
		(width 0.1)
		(layer "In9.Cu")
		(net 395)
	)
	(segment
		(start 156.75 150.85)
		(end 152.85 150.85)
		(width 0.1)
		(layer "In9.Cu")
		(net 395)
	)
	(segment
		(start 177.5 148.5)
		(end 176.98 149.02)
		(width 0.1)
		(layer "In9.Cu")
		(net 395)
	)
	(segment
		(start 158.167372 149.432631)
		(end 158.079681 149.344939)
		(width 0.1)
		(layer "In9.Cu")
		(net 395)
	)
	(segment
		(start 158.539404 148.885421)
		(end 158.539404 148.88542)
		(width 0.1)
		(layer "In9.Cu")
		(net 395)
	)
	(segment
		(start 157.335731 150.43947)
		(end 157.33573 150.439469)
		(width 0.1)
		(layer "In9.Cu")
		(net 395)
	)
	(arc
		(start 159.175 148.425)
		(mid 159.087414 148.461279)
		(end 158.999828 148.425)
		(width 0.1)
		(layer "In9.Cu")
		(net 395)
	)
	(arc
		(start 158.539404 148.710249)
		(mid 158.503125 148.797835)
		(end 158.539404 148.885421)
		(width 0.1)
		(layer "In9.Cu")
		(net 395)
	)
	(arc
		(start 157.33573 150.439469)
		(mid 157.248132 150.403185)
		(end 157.160534 150.439469)
		(width 0.1)
		(layer "In9.Cu")
		(net 395)
	)
	(arc
		(start 157.79535 149.979848)
		(mid 157.831634 150.067446)
		(end 157.79535 150.155044)
		(width 0.1)
		(layer "In9.Cu")
		(net 395)
	)
	(arc
		(start 158.079681 149.344939)
		(mid 157.991991 149.308617)
		(end 157.904302 149.34494)
		(width 0.1)
		(layer "In9.Cu")
		(net 395)
	)
	(arc
		(start 157.510926 150.439469)
		(mid 157.423329 150.475754)
		(end 157.335731 150.43947)
		(width 0.1)
		(layer "In9.Cu")
		(net 395)
	)
	(arc
		(start 158.430526 149.520349)
		(mid 158.342808 149.556683)
		(end 158.25509 149.520349)
		(width 0.1)
		(layer "In9.Cu")
		(net 395)
	)
	(arc
		(start 157.620061 149.62918)
		(mid 157.583739 149.716869)
		(end 157.620061 149.804558)
		(width 0.1)
		(layer "In9.Cu")
		(net 395)
	)
	(arc
		(start 158.999827 148.424999)
		(mid 158.912241 148.38872)
		(end 158.824655 148.424999)
		(width 0.1)
		(layer "In9.Cu")
		(net 395)
	)
	(arc
		(start 158.714711 149.060727)
		(mid 158.751044 149.148447)
		(end 158.71471 149.236164)
		(width 0.1)
		(layer "In9.Cu")
		(net 395)
	)
	(segment
		(start 137.47 151.22)
		(end 137.475 151.225)
		(width 0.256)
		(layer "F.Cu")
		(net 396)
	)
	(segment
		(start 175.9995 150.999501)
		(end 175.5 150.5)
		(width 0.256)
		(layer "F.Cu")
		(net 396)
	)
	(segment
		(start 132.926 146.734)
		(end 132.926 149.350501)
		(width 0.256)
		(layer "F.Cu")
		(net 396)
	)
	(segment
		(start 132.926 149.350501)
		(end 134.795499 151.22)
		(width 0.256)
		(layer "F.Cu")
		(net 396)
	)
	(segment
		(start 134.795499 151.22)
		(end 137.47 151.22)
		(width 0.256)
		(layer "F.Cu")
		(net 396)
	)
	(via
		(at 137.475 151.225)
		(size 0.45)
		(drill 0.1)
		(layers "F.Cu" "B.Cu")
		(remove_unused_layers yes)
		(keep_end_layers yes)
		(zone_layer_connections)
		(net 396)
	)
	(via
		(at 175.5 150.5)
		(size 0.45)
		(drill 0.1)
		(layers "F.Cu" "B.Cu")
		(remove_unused_layers yes)
		(keep_end_layers yes)
		(zone_layer_connections)
		(net 396)
	)
	(segment
		(start 137.5 150.51)
		(end 137.5 151.915)
		(width 0.256)
		(layer "B.Cu")
		(net 396)
	)
	(segment
		(start 150.3 155.5)
		(end 153 152.8)
		(width 0.1)
		(layer "In9.Cu")
		(net 396)
	)
	(segment
		(start 139.575 155.5)
		(end 150.3 155.5)
		(width 0.1)
		(layer "In9.Cu")
		(net 396)
	)
	(segment
		(start 174.99 150.5)
		(end 175.5 150.5)
		(width 0.1)
		(layer "In9.Cu")
		(net 396)
	)
	(segment
		(start 157.7 152.8)
		(end 161.32 149.18)
		(width 0.1)
		(layer "In9.Cu")
		(net 396)
	)
	(segment
		(start 171.32 149.18)
		(end 172.8 150.66)
		(width 0.1)
		(layer "In9.Cu")
		(net 396)
	)
	(segment
		(start 174.83 150.66)
		(end 174.99 150.5)
		(width 0.1)
		(layer "In9.Cu")
		(net 396)
	)
	(segment
		(start 172.8 150.66)
		(end 174.83 150.66)
		(width 0.1)
		(layer "In9.Cu")
		(net 396)
	)
	(segment
		(start 153 152.8)
		(end 157.7 152.8)
		(width 0.1)
		(layer "In9.Cu")
		(net 396)
	)
	(segment
		(start 137.475 153.4)
		(end 139.575 155.5)
		(width 0.1)
		(layer "In9.Cu")
		(net 396)
	)
	(segment
		(start 161.32 149.18)
		(end 171.32 149.18)
		(width 0.1)
		(layer "In9.Cu")
		(net 396)
	)
	(segment
		(start 137.475 151.225)
		(end 137.475 153.4)
		(width 0.1)
		(layer "In9.Cu")
		(net 396)
	)
	(segment
		(start 135.925 148.05)
		(end 136.595 148.72)
		(width 0.256)
		(layer "F.Cu")
		(net 397)
	)
	(segment
		(start 142.103 151.8)
		(end 142.725 151.178)
		(width 0.256)
		(layer "F.Cu")
		(net 397)
	)
	(segment
		(start 139.445 148.72)
		(end 141.125 150.4)
		(width 0.256)
		(layer "F.Cu")
		(net 397)
	)
	(segment
		(start 136.595 148.72)
		(end 139.445 148.72)
		(width 0.256)
		(layer "F.Cu")
		(net 397)
	)
	(segment
		(start 135.925 146.734)
		(end 135.925 148.05)
		(width 0.256)
		(layer "F.Cu")
		(net 397)
	)
	(segment
		(start 141.125 151.575)
		(end 141.35 151.8)
		(width 0.256)
		(layer "F.Cu")
		(net 397)
	)
	(segment
		(start 141.125 150.4)
		(end 141.125 151.575)
		(width 0.256)
		(layer "F.Cu")
		(net 397)
	)
	(segment
		(start 142.725 151.178)
		(end 142.725 151.175)
		(width 0.256)
		(layer "F.Cu")
		(net 397)
	)
	(segment
		(start 141.35 151.8)
		(end 142.103 151.8)
		(width 0.256)
		(layer "F.Cu")
		(net 397)
	)
	(segment
		(start 177.9995 144.9995)
		(end 177.5 144.5)
		(width 0.256)
		(layer "F.Cu")
		(net 397)
	)
	(via
		(at 177.5 144.5)
		(size 0.45)
		(drill 0.1)
		(layers "F.Cu" "B.Cu")
		(remove_unused_layers yes)
		(keep_end_layers yes)
		(zone_layer_connections)
		(net 397)
	)
	(via
		(at 142.725 151.175)
		(size 0.45)
		(drill 0.1)
		(layers "F.Cu" "B.Cu")
		(remove_unused_layers yes)
		(keep_end_layers yes)
		(zone_layer_connections)
		(net 397)
	)
	(segment
		(start 142.75 151.915)
		(end 142.75 150.535)
		(width 0.256)
		(layer "B.Cu")
		(net 397)
	)
	(segment
		(start 155.813573 142.147853)
		(end 155.886427 142.147853)
		(width 0.1)
		(layer "In9.Cu")
		(net 397)
	)
	(segment
		(start 177.025 145)
		(end 177.5 144.525)
		(width 0.1)
		(layer "In9.Cu")
		(net 397)
	)
	(segment
		(start 145.325 151.175)
		(end 151.65 144.85)
		(width 0.1)
		(layer "In9.Cu")
		(net 397)
	)
	(segment
		(start 157.463573 143.102147)
		(end 157.536427 143.102147)
		(width 0.1)
		(layer "In9.Cu")
		(net 397)
	)
	(segment
		(start 152.275 144.85)
		(end 153.4 143.725)
		(width 0.1)
		(layer "In9.Cu")
		(net 397)
	)
	(segment
		(start 156.125 142.386426)
		(end 156.125 142.863574)
		(width 0.1)
		(layer "In9.Cu")
		(net 397)
	)
	(segment
		(start 142.725 151.175)
		(end 145.325 151.175)
		(width 0.1)
		(layer "In9.Cu")
		(net 397)
	)
	(segment
		(start 158.325 142.386426)
		(end 158.325 142.863574)
		(width 0.1)
		(layer "In9.Cu")
		(net 397)
	)
	(segment
		(start 156.913573 142.147853)
		(end 156.986427 142.147853)
		(width 0.1)
		(layer "In9.Cu")
		(net 397)
	)
	(segment
		(start 158.563573 143.102147)
		(end 158.636427 143.102147)
		(width 0.1)
		(layer "In9.Cu")
		(net 397)
	)
	(segment
		(start 159.661767 142.625)
		(end 160.15 142.625)
		(width 0.1)
		(layer "In9.Cu")
		(net 397)
	)
	(segment
		(start 153.4 143.725)
		(end 153.4 143.1)
		(width 0.1)
		(layer "In9.Cu")
		(net 397)
	)
	(segment
		(start 173.45 143.45)
		(end 175 145)
		(width 0.1)
		(layer "In9.Cu")
		(net 397)
	)
	(segment
		(start 158.875 142.863574)
		(end 158.875 142.388233)
		(width 0.1)
		(layer "In9.Cu")
		(net 397)
	)
	(segment
		(start 168.5 143.1)
		(end 168.85 143.45)
		(width 0.1)
		(layer "In9.Cu")
		(net 397)
	)
	(segment
		(start 157.775 142.863574)
		(end 157.775 142.386426)
		(width 0.1)
		(layer "In9.Cu")
		(net 397)
	)
	(segment
		(start 168.85 143.45)
		(end 173.45 143.45)
		(width 0.1)
		(layer "In9.Cu")
		(net 397)
	)
	(segment
		(start 153.4 143.1)
		(end 153.875 142.625)
		(width 0.1)
		(layer "In9.Cu")
		(net 397)
	)
	(segment
		(start 157.225 142.386426)
		(end 157.225 142.863574)
		(width 0.1)
		(layer "In9.Cu")
		(net 397)
	)
	(segment
		(start 175 145)
		(end 177.025 145)
		(width 0.1)
		(layer "In9.Cu")
		(net 397)
	)
	(segment
		(start 155.025 142.388233)
		(end 155.025 142.863574)
		(width 0.1)
		(layer "In9.Cu")
		(net 397)
	)
	(segment
		(start 159.111767 142.151466)
		(end 159.188233 142.151466)
		(width 0.1)
		(layer "In9.Cu")
		(net 397)
	)
	(segment
		(start 151.65 144.85)
		(end 152.275 144.85)
		(width 0.1)
		(layer "In9.Cu")
		(net 397)
	)
	(segment
		(start 177.5 144.525)
		(end 177.5 144.5)
		(width 0.1)
		(layer "In9.Cu")
		(net 397)
	)
	(segment
		(start 156.363573 143.102147)
		(end 156.436427 143.102147)
		(width 0.1)
		(layer "In9.Cu")
		(net 397)
	)
	(segment
		(start 156.675 142.863574)
		(end 156.675 142.386426)
		(width 0.1)
		(layer "In9.Cu")
		(net 397)
	)
	(segment
		(start 154.698534 142.151466)
		(end 154.788233 142.151466)
		(width 0.1)
		(layer "In9.Cu")
		(net 397)
	)
	(segment
		(start 153.875 142.625)
		(end 154.225 142.625)
		(width 0.1)
		(layer "In9.Cu")
		(net 397)
	)
	(segment
		(start 155.575 142.863574)
		(end 155.575 142.386426)
		(width 0.1)
		(layer "In9.Cu")
		(net 397)
	)
	(segment
		(start 160.625 143.1)
		(end 168.5 143.1)
		(width 0.1)
		(layer "In9.Cu")
		(net 397)
	)
	(segment
		(start 158.013573 142.147853)
		(end 158.086427 142.147853)
		(width 0.1)
		(layer "In9.Cu")
		(net 397)
	)
	(segment
		(start 160.15 142.625)
		(end 160.625 143.1)
		(width 0.1)
		(layer "In9.Cu")
		(net 397)
	)
	(segment
		(start 155.263573 143.102147)
		(end 155.336427 143.102147)
		(width 0.1)
		(layer "In9.Cu")
		(net 397)
	)
	(arc
		(start 156.986427 142.147853)
		(mid 157.155124 142.217729)
		(end 157.225 142.386426)
		(width 0.1)
		(layer "In9.Cu")
		(net 397)
	)
	(arc
		(start 155.886427 142.147853)
		(mid 156.055124 142.217729)
		(end 156.125 142.386426)
		(width 0.1)
		(layer "In9.Cu")
		(net 397)
	)
	(arc
		(start 155.575 142.386426)
		(mid 155.644876 142.217729)
		(end 155.813573 142.147853)
		(width 0.1)
		(layer "In9.Cu")
		(net 397)
	)
	(arc
		(start 158.325 142.863574)
		(mid 158.394876 143.032271)
		(end 158.563573 143.102147)
		(width 0.1)
		(layer "In9.Cu")
		(net 397)
	)
	(arc
		(start 155.336427 143.102147)
		(mid 155.505124 143.032271)
		(end 155.575 142.863574)
		(width 0.1)
		(layer "In9.Cu")
		(net 397)
	)
	(arc
		(start 158.875 142.388233)
		(mid 158.944347 142.220813)
		(end 159.111767 142.151466)
		(width 0.1)
		(layer "In9.Cu")
		(net 397)
	)
	(arc
		(start 155.025 142.863574)
		(mid 155.094876 143.032271)
		(end 155.263573 143.102147)
		(width 0.1)
		(layer "In9.Cu")
		(net 397)
	)
	(arc
		(start 154.788233 142.151466)
		(mid 154.955653 142.220813)
		(end 155.025 142.388233)
		(width 0.1)
		(layer "In9.Cu")
		(net 397)
	)
	(arc
		(start 157.775 142.386426)
		(mid 157.844876 142.217729)
		(end 158.013573 142.147853)
		(width 0.1)
		(layer "In9.Cu")
		(net 397)
	)
	(arc
		(start 158.086427 142.147853)
		(mid 158.255124 142.217729)
		(end 158.325 142.386426)
		(width 0.1)
		(layer "In9.Cu")
		(net 397)
	)
	(arc
		(start 158.636427 143.102147)
		(mid 158.805124 143.032271)
		(end 158.875 142.863574)
		(width 0.1)
		(layer "In9.Cu")
		(net 397)
	)
	(arc
		(start 159.425 142.388233)
		(mid 159.494347 142.555653)
		(end 159.661767 142.625)
		(width 0.1)
		(layer "In9.Cu")
		(net 397)
	)
	(arc
		(start 154.461767 142.388233)
		(mid 154.531114 142.220813)
		(end 154.698534 142.151466)
		(width 0.1)
		(layer "In9.Cu")
		(net 397)
	)
	(arc
		(start 157.536427 143.102147)
		(mid 157.705124 143.032271)
		(end 157.775 142.863574)
		(width 0.1)
		(layer "In9.Cu")
		(net 397)
	)
	(arc
		(start 157.225 142.863574)
		(mid 157.294876 143.032271)
		(end 157.463573 143.102147)
		(width 0.1)
		(layer "In9.Cu")
		(net 397)
	)
	(arc
		(start 159.188233 142.151466)
		(mid 159.355653 142.220813)
		(end 159.425 142.388233)
		(width 0.1)
		(layer "In9.Cu")
		(net 397)
	)
	(arc
		(start 156.675 142.386426)
		(mid 156.744876 142.217729)
		(end 156.913573 142.147853)
		(width 0.1)
		(layer "In9.Cu")
		(net 397)
	)
	(arc
		(start 156.125 142.863574)
		(mid 156.194876 143.032271)
		(end 156.363573 143.102147)
		(width 0.1)
		(layer "In9.Cu")
		(net 397)
	)
	(arc
		(start 154.225 142.625)
		(mid 154.39242 142.555653)
		(end 154.461767 142.388233)
		(width 0.1)
		(layer "In9.Cu")
		(net 397)
	)
	(arc
		(start 156.436427 143.102147)
		(mid 156.605124 143.032271)
		(end 156.675 142.863574)
		(width 0.1)
		(layer "In9.Cu")
		(net 397)
	)
	(segment
		(start 136.925 146.734)
		(end 136.925 147.8)
		(width 0.256)
		(layer "F.Cu")
		(net 398)
	)
	(segment
		(start 140.125 148.05)
		(end 141.625 149.55)
		(width 0.256)
		(layer "F.Cu")
		(net 398)
	)
	(segment
		(start 137.175 148.05)
		(end 140.125 148.05)
		(width 0.256)
		(layer "F.Cu")
		(net 398)
	)
	(segment
		(start 176.9995 144.9995)
		(end 176.5 144.5)
		(width 0.256)
		(layer "F.Cu")
		(net 398)
	)
	(segment
		(start 141.625 149.55)
		(end 141.625 151.2)
		(width 0.256)
		(layer "F.Cu")
		(net 398)
	)
	(segment
		(start 136.925 147.8)
		(end 137.175 148.05)
		(width 0.256)
		(layer "F.Cu")
		(net 398)
	)
	(via
		(at 176.5 144.5)
		(size 0.45)
		(drill 0.1)
		(layers "F.Cu" "B.Cu")
		(remove_unused_layers yes)
		(keep_end_layers yes)
		(zone_layer_connections)
		(net 398)
	)
	(via
		(at 141.625 151.2)
		(size 0.45)
		(drill 0.1)
		(layers "F.Cu" "B.Cu")
		(remove_unused_layers yes)
		(keep_end_layers yes)
		(zone_layer_connections)
		(net 398)
	)
	(segment
		(start 141.675 150.535)
		(end 141.65 150.51)
		(width 0.256)
		(layer "B.Cu")
		(net 398)
	)
	(segment
		(start 141.675 151.915)
		(end 141.675 150.535)
		(width 0.256)
		(layer "B.Cu")
		(net 398)
	)
	(segment
		(start 163.725 142.258806)
		(end 163.725 141.85)
		(width 0.1)
		(layer "In9.Cu")
		(net 398)
	)
	(segment
		(start 152.175 143.325)
		(end 145 150.5)
		(width 0.1)
		(layer "In9.Cu")
		(net 398)
	)
	(segment
		(start 176.175 144.525)
		(end 175.7 144.05)
		(width 0.1)
		(layer "In9.Cu")
		(net 398)
	)
	(segment
		(start 166.225 141.85)
		(end 166.225 142.258806)
		(width 0.1)
		(layer "In9.Cu")
		(net 398)
	)
	(segment
		(start 168.7 142.4)
		(end 167.475 142.4)
		(width 0.1)
		(layer "In9.Cu")
		(net 398)
	)
	(segment
		(start 169.25 142.95)
		(end 168.7 142.4)
		(width 0.1)
		(layer "In9.Cu")
		(net 398)
	)
	(segment
		(start 162.225 141.85)
		(end 162.225 142.258806)
		(width 0.1)
		(layer "In9.Cu")
		(net 398)
	)
	(segment
		(start 152.175 142.525)
		(end 152.175 143.325)
		(width 0.1)
		(layer "In9.Cu")
		(net 398)
	)
	(segment
		(start 160.725 142.258806)
		(end 160.725 141.85)
		(width 0.1)
		(layer "In9.Cu")
		(net 398)
	)
	(segment
		(start 176.5 144.5)
		(end 176.475 144.525)
		(width 0.1)
		(layer "In9.Cu")
		(net 398)
	)
	(segment
		(start 165.725 142.258806)
		(end 165.725 141.85)
		(width 0.1)
		(layer "In9.Cu")
		(net 398)
	)
	(segment
		(start 176.475 144.525)
		(end 176.175 144.525)
		(width 0.1)
		(layer "In9.Cu")
		(net 398)
	)
	(segment
		(start 161.225 141.85)
		(end 161.225 142.258806)
		(width 0.1)
		(layer "In9.Cu")
		(net 398)
	)
	(segment
		(start 167.475 142.4)
		(end 166.675 141.6)
		(width 0.1)
		(layer "In9.Cu")
		(net 398)
	)
	(segment
		(start 165.225 141.85)
		(end 165.225 142.258806)
		(width 0.1)
		(layer "In9.Cu")
		(net 398)
	)
	(segment
		(start 145 150.5)
		(end 142.325 150.5)
		(width 0.1)
		(layer "In9.Cu")
		(net 398)
	)
	(segment
		(start 174.85 144.05)
		(end 173.75 142.95)
		(width 0.1)
		(layer "In9.Cu")
		(net 398)
	)
	(segment
		(start 166.675 141.6)
		(end 166.475 141.6)
		(width 0.1)
		(layer "In9.Cu")
		(net 398)
	)
	(segment
		(start 162.725 142.258806)
		(end 162.725 141.85)
		(width 0.1)
		(layer "In9.Cu")
		(net 398)
	)
	(segment
		(start 160.475 141.6)
		(end 153.1 141.6)
		(width 0.1)
		(layer "In9.Cu")
		(net 398)
	)
	(segment
		(start 173.75 142.95)
		(end 169.25 142.95)
		(width 0.1)
		(layer "In9.Cu")
		(net 398)
	)
	(segment
		(start 175.7 144.05)
		(end 174.85 144.05)
		(width 0.1)
		(layer "In9.Cu")
		(net 398)
	)
	(segment
		(start 153.1 141.6)
		(end 152.175 142.525)
		(width 0.1)
		(layer "In9.Cu")
		(net 398)
	)
	(segment
		(start 142.325 150.5)
		(end 141.625 151.2)
		(width 0.1)
		(layer "In9.Cu")
		(net 398)
	)
	(segment
		(start 164.725 142.258806)
		(end 164.725 141.85)
		(width 0.1)
		(layer "In9.Cu")
		(net 398)
	)
	(segment
		(start 163.225 141.85)
		(end 163.225 142.258806)
		(width 0.1)
		(layer "In9.Cu")
		(net 398)
	)
	(segment
		(start 164.225 141.85)
		(end 164.225 142.258806)
		(width 0.1)
		(layer "In9.Cu")
		(net 398)
	)
	(segment
		(start 161.725 142.258806)
		(end 161.725 141.85)
		(width 0.1)
		(layer "In9.Cu")
		(net 398)
	)
	(arc
		(start 163.475 141.6)
		(mid 163.298223 141.673223)
		(end 163.225 141.85)
		(width 0.1)
		(layer "In9.Cu")
		(net 398)
	)
	(arc
		(start 163.975 142.508806)
		(mid 163.798223 142.435583)
		(end 163.725 142.258806)
		(width 0.1)
		(layer "In9.Cu")
		(net 398)
	)
	(arc
		(start 163.225 142.258806)
		(mid 163.151777 142.435583)
		(end 162.975 142.508806)
		(width 0.1)
		(layer "In9.Cu")
		(net 398)
	)
	(arc
		(start 166.225 142.258806)
		(mid 166.151777 142.435583)
		(end 165.975 142.508806)
		(width 0.1)
		(layer "In9.Cu")
		(net 398)
	)
	(arc
		(start 165.225 142.258806)
		(mid 165.151777 142.435583)
		(end 164.975 142.508806)
		(width 0.1)
		(layer "In9.Cu")
		(net 398)
	)
	(arc
		(start 164.225 142.258806)
		(mid 164.151777 142.435583)
		(end 163.975 142.508806)
		(width 0.1)
		(layer "In9.Cu")
		(net 398)
	)
	(arc
		(start 162.225 142.258806)
		(mid 162.151777 142.435583)
		(end 161.975 142.508806)
		(width 0.1)
		(layer "In9.Cu")
		(net 398)
	)
	(arc
		(start 161.725 141.85)
		(mid 161.651777 141.673223)
		(end 161.475 141.6)
		(width 0.1)
		(layer "In9.Cu")
		(net 398)
	)
	(arc
		(start 161.975 142.508806)
		(mid 161.798223 142.435583)
		(end 161.725 142.258806)
		(width 0.1)
		(layer "In9.Cu")
		(net 398)
	)
	(arc
		(start 160.975 142.508806)
		(mid 160.798223 142.435583)
		(end 160.725 142.258806)
		(width 0.1)
		(layer "In9.Cu")
		(net 398)
	)
	(arc
		(start 165.725 141.85)
		(mid 165.651777 141.673223)
		(end 165.475 141.6)
		(width 0.1)
		(layer "In9.Cu")
		(net 398)
	)
	(arc
		(start 165.975 142.508806)
		(mid 165.798223 142.435583)
		(end 165.725 142.258806)
		(width 0.1)
		(layer "In9.Cu")
		(net 398)
	)
	(arc
		(start 162.475 141.6)
		(mid 162.298223 141.673223)
		(end 162.225 141.85)
		(width 0.1)
		(layer "In9.Cu")
		(net 398)
	)
	(arc
		(start 162.725 141.85)
		(mid 162.651777 141.673223)
		(end 162.475 141.6)
		(width 0.1)
		(layer "In9.Cu")
		(net 398)
	)
	(arc
		(start 166.475 141.6)
		(mid 166.298223 141.673223)
		(end 166.225 141.85)
		(width 0.1)
		(layer "In9.Cu")
		(net 398)
	)
	(arc
		(start 161.475 141.6)
		(mid 161.298223 141.673223)
		(end 161.225 141.85)
		(width 0.1)
		(layer "In9.Cu")
		(net 398)
	)
	(arc
		(start 162.975 142.508806)
		(mid 162.798223 142.435583)
		(end 162.725 142.258806)
		(width 0.1)
		(layer "In9.Cu")
		(net 398)
	)
	(arc
		(start 163.725 141.85)
		(mid 163.651777 141.673223)
		(end 163.475 141.6)
		(width 0.1)
		(layer "In9.Cu")
		(net 398)
	)
	(arc
		(start 164.475 141.6)
		(mid 164.298223 141.673223)
		(end 164.225 141.85)
		(width 0.1)
		(layer "In9.Cu")
		(net 398)
	)
	(arc
		(start 161.225 142.258806)
		(mid 161.151777 142.435583)
		(end 160.975 142.508806)
		(width 0.1)
		(layer "In9.Cu")
		(net 398)
	)
	(arc
		(start 165.475 141.6)
		(mid 165.298223 141.673223)
		(end 165.225 141.85)
		(width 0.1)
		(layer "In9.Cu")
		(net 398)
	)
	(arc
		(start 164.725 141.85)
		(mid 164.651777 141.673223)
		(end 164.475 141.6)
		(width 0.1)
		(layer "In9.Cu")
		(net 398)
	)
	(arc
		(start 164.975 142.508806)
		(mid 164.798223 142.435583)
		(end 164.725 142.258806)
		(width 0.1)
		(layer "In9.Cu")
		(net 398)
	)
	(arc
		(start 160.725 141.85)
		(mid 160.651777 141.673223)
		(end 160.475 141.6)
		(width 0.1)
		(layer "In9.Cu")
		(net 398)
	)
	(segment
		(start 138.175 143.983)
		(end 137.251187 143.983)
		(width 0.256)
		(layer "F.Cu")
		(net 399)
	)
	(segment
		(start 137.251187 143.983)
		(end 137.216328 144.017859)
		(width 0.256)
		(layer "F.Cu")
		(net 399)
	)
	(segment
		(start 176.999499 141.9995)
		(end 176.5 141.5)
		(width 0.256)
		(layer "F.Cu")
		(net 399)
	)
	(via
		(at 137.216328 144.017859)
		(size 0.45)
		(drill 0.1)
		(layers "F.Cu" "B.Cu")
		(remove_unused_layers yes)
		(keep_end_layers yes)
		(zone_layer_connections)
		(net 399)
	)
	(via
		(at 176.5 141.5)
		(size 0.45)
		(drill 0.1)
		(layers "F.Cu" "B.Cu")
		(remove_unused_layers yes)
		(keep_end_layers yes)
		(zone_layer_connections)
		(net 399)
	)
	(segment
		(start 137.197469 143.999)
		(end 137.216328 144.017859)
		(width 0.201)
		(layer "B.Cu")
		(net 399)
	)
	(segment
		(start 135.383171 143.884)
		(end 136.433171 143.884)
		(width 0.256)
		(layer "B.Cu")
		(net 399)
	)
	(segment
		(start 136.433171 143.884)
		(end 137.082469 143.884)
		(width 0.256)
		(layer "B.Cu")
		(net 399)
	)
	(segment
		(start 137.082469 143.884)
		(end 137.216328 144.017859)
		(width 0.256)
		(layer "B.Cu")
		(net 399)
	)
	(segment
		(start 148.9 142.6)
		(end 148.9 140.15)
		(width 0.1)
		(layer "In9.Cu")
		(net 399)
	)
	(segment
		(start 170.9 141)
		(end 176 141)
		(width 0.1)
		(layer "In9.Cu")
		(net 399)
	)
	(segment
		(start 148.9 140.15)
		(end 151.1 137.95)
		(width 0.1)
		(layer "In9.Cu")
		(net 399)
	)
	(segment
		(start 137.216328 144.017859)
		(end 138.25 145.051531)
		(width 0.1)
		(layer "In9.Cu")
		(net 399)
	)
	(segment
		(start 139.375 146.575)
		(end 144.925 146.575)
		(width 0.1)
		(layer "In9.Cu")
		(net 399)
	)
	(segment
		(start 138.25 145.051531)
		(end 138.25 145.45)
		(width 0.1)
		(layer "In9.Cu")
		(net 399)
	)
	(segment
		(start 138.25 145.45)
		(end 139.375 146.575)
		(width 0.1)
		(layer "In9.Cu")
		(net 399)
	)
	(segment
		(start 176 141)
		(end 176.5 141.5)
		(width 0.1)
		(layer "In9.Cu")
		(net 399)
	)
	(segment
		(start 167.85 137.95)
		(end 170.9 141)
		(width 0.1)
		(layer "In9.Cu")
		(net 399)
	)
	(segment
		(start 151.1 137.95)
		(end 167.85 137.95)
		(width 0.1)
		(layer "In9.Cu")
		(net 399)
	)
	(segment
		(start 144.925 146.575)
		(end 148.9 142.6)
		(width 0.1)
		(layer "In9.Cu")
		(net 399)
	)
	(segment
		(start 175.9995 141.999501)
		(end 175.5 141.5)
		(width 0.256)
		(layer "F.Cu")
		(net 400)
	)
	(segment
		(start 138.175 145.984)
		(end 138.434 145.984)
		(width 0.256)
		(layer "F.Cu")
		(net 400)
	)
	(segment
		(start 138.434 145.984)
		(end 139.76 147.31)
		(width 0.256)
		(layer "F.Cu")
		(net 400)
	)
	(via
		(at 139.76 147.31)
		(size 0.45)
		(drill 0.1)
		(layers "F.Cu" "B.Cu")
		(remove_unused_layers yes)
		(keep_end_layers yes)
		(zone_layer_connections)
		(net 400)
	)
	(via
		(at 175.5 141.5)
		(size 0.45)
		(drill 0.1)
		(layers "F.Cu" "B.Cu")
		(remove_unused_layers yes)
		(keep_end_layers yes)
		(zone_layer_connections)
		(net 400)
	)
	(segment
		(start 139.7 148.17)
		(end 139.76 148.11)
		(width 0.256)
		(layer "B.Cu")
		(net 400)
	)
	(segment
		(start 139.76 148.11)
		(end 139.76 147.31)
		(width 0.256)
		(layer "B.Cu")
		(net 400)
	)
	(segment
		(start 157.529542 138.604542)
		(end 157.2 138.604542)
		(width 0.1)
		(layer "In9.Cu")
		(net 400)
	)
	(segment
		(start 152.65 138.925)
		(end 151.6 138.925)
		(width 0.1)
		(layer "In9.Cu")
		(net 400)
	)
	(segment
		(start 156.879542 138.925)
		(end 156.55 138.925)
		(width 0.1)
		(layer "In9.Cu")
		(net 400)
	)
	(segment
		(start 168.95 140.3)
		(end 167.575 138.925)
		(width 0.1)
		(layer "In9.Cu")
		(net 400)
	)
	(segment
		(start 160.129552 138.604551)
		(end 159.8 138.604551)
		(width 0.1)
		(layer "In9.Cu")
		(net 400)
	)
	(segment
		(start 162.729552 138.604551)
		(end 162.4 138.604551)
		(width 0.1)
		(layer "In9.Cu")
		(net 400)
	)
	(segment
		(start 163.379552 138.925)
		(end 163.05 138.925)
		(width 0.1)
		(layer "In9.Cu")
		(net 400)
	)
	(segment
		(start 175.5 141.5)
		(end 170.5 141.5)
		(width 0.1)
		(layer "In9.Cu")
		(net 400)
	)
	(segment
		(start 170.5 141.5)
		(end 169.3 140.3)
		(width 0.1)
		(layer "In9.Cu")
		(net 400)
	)
	(segment
		(start 152.979542 138.925)
		(end 152.65 138.925)
		(width 0.1)
		(layer "In9.Cu")
		(net 400)
	)
	(segment
		(start 155.579542 138.925)
		(end 155.25 138.925)
		(width 0.1)
		(layer "In9.Cu")
		(net 400)
	)
	(segment
		(start 164.679552 138.925)
		(end 164.35 138.925)
		(width 0.1)
		(layer "In9.Cu")
		(net 400)
	)
	(segment
		(start 166.789776 138.764776)
		(end 166.789776 138.764775)
		(width 0.1)
		(layer "In9.Cu")
		(net 400)
	)
	(segment
		(start 161.429542 138.604542)
		(end 161.1 138.604542)
		(width 0.1)
		(layer "In9.Cu")
		(net 400)
	)
	(segment
		(start 153.629542 138.604542)
		(end 153.3 138.604542)
		(width 0.1)
		(layer "In9.Cu")
		(net 400)
	)
	(segment
		(start 162.239776 138.764775)
		(end 162.239776 138.764776)
		(width 0.1)
		(layer "In9.Cu")
		(net 400)
	)
	(segment
		(start 139.799 147.349)
		(end 139.76 147.31)
		(width 0.1)
		(layer "In9.Cu")
		(net 400)
	)
	(segment
		(start 149.7 140.825)
		(end 149.7 142.8)
		(width 0.1)
		(layer "In9.Cu")
		(net 400)
	)
	(segment
		(start 166.629552 138.604551)
		(end 166.3 138.604551)
		(width 0.1)
		(layer "In9.Cu")
		(net 400)
	)
	(segment
		(start 156.229542 138.604542)
		(end 155.9 138.604542)
		(width 0.1)
		(layer "In9.Cu")
		(net 400)
	)
	(segment
		(start 164.839776 138.764775)
		(end 164.839776 138.764776)
		(width 0.1)
		(layer "In9.Cu")
		(net 400)
	)
	(segment
		(start 164.189776 138.764776)
		(end 164.189776 138.764775)
		(width 0.1)
		(layer "In9.Cu")
		(net 400)
	)
	(segment
		(start 158.179542 138.925)
		(end 157.85 138.925)
		(width 0.1)
		(layer "In9.Cu")
		(net 400)
	)
	(segment
		(start 154.929542 138.604542)
		(end 154.6 138.604542)
		(width 0.1)
		(layer "In9.Cu")
		(net 400)
	)
	(segment
		(start 141.549 147.05)
		(end 141.25 147.349)
		(width 0.1)
		(layer "In9.Cu")
		(net 400)
	)
	(segment
		(start 165.489776 138.764776)
		(end 165.489776 138.764775)
		(width 0.1)
		(layer "In9.Cu")
		(net 400)
	)
	(segment
		(start 169.3 140.3)
		(end 168.95 140.3)
		(width 0.1)
		(layer "In9.Cu")
		(net 400)
	)
	(segment
		(start 166.139776 138.764775)
		(end 166.139776 138.764776)
		(width 0.1)
		(layer "In9.Cu")
		(net 400)
	)
	(segment
		(start 158.829542 138.604542)
		(end 158.5 138.604542)
		(width 0.1)
		(layer "In9.Cu")
		(net 400)
	)
	(segment
		(start 154.279542 138.925)
		(end 153.95 138.925)
		(width 0.1)
		(layer "In9.Cu")
		(net 400)
	)
	(segment
		(start 141.25 147.349)
		(end 139.799 147.349)
		(width 0.1)
		(layer "In9.Cu")
		(net 400)
	)
	(segment
		(start 151.6 138.925)
		(end 149.7 140.825)
		(width 0.1)
		(layer "In9.Cu")
		(net 400)
	)
	(segment
		(start 162.889776 138.764776)
		(end 162.889776 138.764775)
		(width 0.1)
		(layer "In9.Cu")
		(net 400)
	)
	(segment
		(start 145.45 147.05)
		(end 141.549 147.05)
		(width 0.1)
		(layer "In9.Cu")
		(net 400)
	)
	(segment
		(start 165.979552 138.925)
		(end 165.65 138.925)
		(width 0.1)
		(layer "In9.Cu")
		(net 400)
	)
	(segment
		(start 164.029552 138.604551)
		(end 163.7 138.604551)
		(width 0.1)
		(layer "In9.Cu")
		(net 400)
	)
	(segment
		(start 160.289776 138.764776)
		(end 160.289776 138.764775)
		(width 0.1)
		(layer "In9.Cu")
		(net 400)
	)
	(segment
		(start 159.479552 138.925)
		(end 159.15 138.925)
		(width 0.1)
		(layer "In9.Cu")
		(net 400)
	)
	(segment
		(start 165.329552 138.604551)
		(end 165 138.604551)
		(width 0.1)
		(layer "In9.Cu")
		(net 400)
	)
	(segment
		(start 159.639776 138.764775)
		(end 159.639776 138.764776)
		(width 0.1)
		(layer "In9.Cu")
		(net 400)
	)
	(segment
		(start 160.779542 138.925)
		(end 160.45 138.925)
		(width 0.1)
		(layer "In9.Cu")
		(net 400)
	)
	(segment
		(start 163.539776 138.764775)
		(end 163.539776 138.764776)
		(width 0.1)
		(layer "In9.Cu")
		(net 400)
	)
	(segment
		(start 167.575 138.925)
		(end 166.95 138.925)
		(width 0.1)
		(layer "In9.Cu")
		(net 400)
	)
	(segment
		(start 162.079552 138.925)
		(end 161.75 138.925)
		(width 0.1)
		(layer "In9.Cu")
		(net 400)
	)
	(segment
		(start 149.7 142.8)
		(end 145.45 147.05)
		(width 0.1)
		(layer "In9.Cu")
		(net 400)
	)
	(arc
		(start 161.1 138.604542)
		(mid 160.986701 138.651472)
		(end 160.939771 138.764771)
		(width 0.1)
		(layer "In9.Cu")
		(net 400)
	)
	(arc
		(start 153.95 138.925)
		(mid 153.836701 138.87807)
		(end 153.789771 138.764771)
		(width 0.1)
		(layer "In9.Cu")
		(net 400)
	)
	(arc
		(start 159.15 138.925)
		(mid 159.036701 138.87807)
		(end 158.989771 138.764771)
		(width 0.1)
		(layer "In9.Cu")
		(net 400)
	)
	(arc
		(start 164.189776 138.764775)
		(mid 164.142847 138.65148)
		(end 164.029552 138.604551)
		(width 0.1)
		(layer "In9.Cu")
		(net 400)
	)
	(arc
		(start 162.239776 138.764776)
		(mid 162.192847 138.878071)
		(end 162.079552 138.925)
		(width 0.1)
		(layer "In9.Cu")
		(net 400)
	)
	(arc
		(start 165.65 138.925)
		(mid 165.536705 138.878071)
		(end 165.489776 138.764776)
		(width 0.1)
		(layer "In9.Cu")
		(net 400)
	)
	(arc
		(start 161.589771 138.764771)
		(mid 161.542841 138.651472)
		(end 161.429542 138.604542)
		(width 0.1)
		(layer "In9.Cu")
		(net 400)
	)
	(arc
		(start 161.75 138.925)
		(mid 161.636701 138.87807)
		(end 161.589771 138.764771)
		(width 0.1)
		(layer "In9.Cu")
		(net 400)
	)
	(arc
		(start 165.489776 138.764775)
		(mid 165.442847 138.65148)
		(end 165.329552 138.604551)
		(width 0.1)
		(layer "In9.Cu")
		(net 400)
	)
	(arc
		(start 160.45 138.925)
		(mid 160.336705 138.878071)
		(end 160.289776 138.764776)
		(width 0.1)
		(layer "In9.Cu")
		(net 400)
	)
	(arc
		(start 160.289776 138.764775)
		(mid 160.242847 138.65148)
		(end 160.129552 138.604551)
		(width 0.1)
		(layer "In9.Cu")
		(net 400)
	)
	(arc
		(start 156.389771 138.764771)
		(mid 156.342841 138.651472)
		(end 156.229542 138.604542)
		(width 0.1)
		(layer "In9.Cu")
		(net 400)
	)
	(arc
		(start 166.789776 138.764775)
		(mid 166.742847 138.65148)
		(end 166.629552 138.604551)
		(width 0.1)
		(layer "In9.Cu")
		(net 400)
	)
	(arc
		(start 154.6 138.604542)
		(mid 154.486701 138.651472)
		(end 154.439771 138.764771)
		(width 0.1)
		(layer "In9.Cu")
		(net 400)
	)
	(arc
		(start 155.089771 138.764771)
		(mid 155.042841 138.651472)
		(end 154.929542 138.604542)
		(width 0.1)
		(layer "In9.Cu")
		(net 400)
	)
	(arc
		(start 163.539776 138.764776)
		(mid 163.492847 138.878071)
		(end 163.379552 138.925)
		(width 0.1)
		(layer "In9.Cu")
		(net 400)
	)
	(arc
		(start 157.039771 138.764771)
		(mid 156.992841 138.87807)
		(end 156.879542 138.925)
		(width 0.1)
		(layer "In9.Cu")
		(net 400)
	)
	(arc
		(start 162.4 138.604551)
		(mid 162.286705 138.65148)
		(end 162.239776 138.764775)
		(width 0.1)
		(layer "In9.Cu")
		(net 400)
	)
	(arc
		(start 153.3 138.604542)
		(mid 153.186701 138.651472)
		(end 153.139771 138.764771)
		(width 0.1)
		(layer "In9.Cu")
		(net 400)
	)
	(arc
		(start 153.139771 138.764771)
		(mid 153.092841 138.87807)
		(end 152.979542 138.925)
		(width 0.1)
		(layer "In9.Cu")
		(net 400)
	)
	(arc
		(start 159.639776 138.764776)
		(mid 159.592847 138.878071)
		(end 159.479552 138.925)
		(width 0.1)
		(layer "In9.Cu")
		(net 400)
	)
	(arc
		(start 157.2 138.604542)
		(mid 157.086701 138.651472)
		(end 157.039771 138.764771)
		(width 0.1)
		(layer "In9.Cu")
		(net 400)
	)
	(arc
		(start 155.25 138.925)
		(mid 155.136701 138.87807)
		(end 155.089771 138.764771)
		(width 0.1)
		(layer "In9.Cu")
		(net 400)
	)
	(arc
		(start 166.95 138.925)
		(mid 166.836705 138.878071)
		(end 166.789776 138.764776)
		(width 0.1)
		(layer "In9.Cu")
		(net 400)
	)
	(arc
		(start 162.889776 138.764775)
		(mid 162.842847 138.65148)
		(end 162.729552 138.604551)
		(width 0.1)
		(layer "In9.Cu")
		(net 400)
	)
	(arc
		(start 157.689771 138.764771)
		(mid 157.642841 138.651472)
		(end 157.529542 138.604542)
		(width 0.1)
		(layer "In9.Cu")
		(net 400)
	)
	(arc
		(start 158.5 138.604542)
		(mid 158.386701 138.651472)
		(end 158.339771 138.764771)
		(width 0.1)
		(layer "In9.Cu")
		(net 400)
	)
	(arc
		(start 158.339771 138.764771)
		(mid 158.292841 138.87807)
		(end 158.179542 138.925)
		(width 0.1)
		(layer "In9.Cu")
		(net 400)
	)
	(arc
		(start 158.989771 138.764771)
		(mid 158.942841 138.651472)
		(end 158.829542 138.604542)
		(width 0.1)
		(layer "In9.Cu")
		(net 400)
	)
	(arc
		(start 165 138.604551)
		(mid 164.886705 138.65148)
		(end 164.839776 138.764775)
		(width 0.1)
		(layer "In9.Cu")
		(net 400)
	)
	(arc
		(start 157.85 138.925)
		(mid 157.736701 138.87807)
		(end 157.689771 138.764771)
		(width 0.1)
		(layer "In9.Cu")
		(net 400)
	)
	(arc
		(start 159.8 138.604551)
		(mid 159.686705 138.65148)
		(end 159.639776 138.764775)
		(width 0.1)
		(layer "In9.Cu")
		(net 400)
	)
	(arc
		(start 160.939771 138.764771)
		(mid 160.892841 138.87807)
		(end 160.779542 138.925)
		(width 0.1)
		(layer "In9.Cu")
		(net 400)
	)
	(arc
		(start 164.35 138.925)
		(mid 164.236705 138.878071)
		(end 164.189776 138.764776)
		(width 0.1)
		(layer "In9.Cu")
		(net 400)
	)
	(arc
		(start 156.55 138.925)
		(mid 156.436701 138.87807)
		(end 156.389771 138.764771)
		(width 0.1)
		(layer "In9.Cu")
		(net 400)
	)
	(arc
		(start 166.139776 138.764776)
		(mid 166.092847 138.878071)
		(end 165.979552 138.925)
		(width 0.1)
		(layer "In9.Cu")
		(net 400)
	)
	(arc
		(start 163.7 138.604551)
		(mid 163.586705 138.65148)
		(end 163.539776 138.764775)
		(width 0.1)
		(layer "In9.Cu")
		(net 400)
	)
	(arc
		(start 164.839776 138.764776)
		(mid 164.792847 138.878071)
		(end 164.679552 138.925)
		(width 0.1)
		(layer "In9.Cu")
		(net 400)
	)
	(arc
		(start 155.739771 138.764771)
		(mid 155.692841 138.87807)
		(end 155.579542 138.925)
		(width 0.1)
		(layer "In9.Cu")
		(net 400)
	)
	(arc
		(start 154.439771 138.764771)
		(mid 154.392841 138.87807)
		(end 154.279542 138.925)
		(width 0.1)
		(layer "In9.Cu")
		(net 400)
	)
	(arc
		(start 163.05 138.925)
		(mid 162.936705 138.878071)
		(end 162.889776 138.764776)
		(width 0.1)
		(layer "In9.Cu")
		(net 400)
	)
	(arc
		(start 153.789771 138.764771)
		(mid 153.742841 138.651472)
		(end 153.629542 138.604542)
		(width 0.1)
		(layer "In9.Cu")
		(net 400)
	)
	(arc
		(start 155.9 138.604542)
		(mid 155.786701 138.651472)
		(end 155.739771 138.764771)
		(width 0.1)
		(layer "In9.Cu")
		(net 400)
	)
	(arc
		(start 166.3 138.604551)
		(mid 166.186705 138.65148)
		(end 166.139776 138.764775)
		(width 0.1)
		(layer "In9.Cu")
		(net 400)
	)
	(segment
		(start 138.175 143.483)
		(end 138.714149 143.483)
		(width 0.256)
		(layer "F.Cu")
		(net 401)
	)
	(segment
		(start 177.9995 142.9995)
		(end 177.5 142.5)
		(width 0.256)
		(layer "F.Cu")
		(net 401)
	)
	(segment
		(start 138.714149 143.483)
		(end 139.225 142.972149)
		(width 0.256)
		(layer "F.Cu")
		(net 401)
	)
	(via
		(at 177.5 142.5)
		(size 0.45)
		(drill 0.1)
		(layers "F.Cu" "B.Cu")
		(remove_unused_layers yes)
		(keep_end_layers yes)
		(zone_layer_connections)
		(net 401)
	)
	(via
		(at 139.225 142.972149)
		(size 0.45)
		(drill 0.1)
		(layers "F.Cu" "B.Cu")
		(remove_unused_layers yes)
		(keep_end_layers yes)
		(zone_layer_connections)
		(net 401)
	)
	(segment
		(start 139.225 142.849501)
		(end 139.225 142.972149)
		(width 0.2)
		(layer "B.Cu")
		(net 401)
	)
	(segment
		(start 138.709499 142.334)
		(end 139.225 142.849501)
		(width 0.2)
		(layer "B.Cu")
		(net 401)
	)
	(segment
		(start 138.709499 142.299)
		(end 138.709499 142.334)
		(width 0.2)
		(layer "B.Cu")
		(net 401)
	)
	(segment
		(start 171.7 139.8)
		(end 174.8 139.8)
		(width 0.1)
		(layer "In9.Cu")
		(net 401)
	)
	(segment
		(start 149.475 135.9)
		(end 167.8 135.9)
		(width 0.1)
		(layer "In9.Cu")
		(net 401)
	)
	(segment
		(start 139.847149 142.972149)
		(end 140 143.125)
		(width 0.1)
		(layer "In9.Cu")
		(net 401)
	)
	(segment
		(start 177 142)
		(end 177.5 142.5)
		(width 0.1)
		(layer "In9.Cu")
		(net 401)
	)
	(segment
		(start 139.225 142.972149)
		(end 139.847149 142.972149)
		(width 0.1)
		(layer "In9.Cu")
		(net 401)
	)
	(segment
		(start 167.8 135.9)
		(end 171.7 139.8)
		(width 0.1)
		(layer "In9.Cu")
		(net 401)
	)
	(segment
		(start 177 140.25)
		(end 177 142)
		(width 0.1)
		(layer "In9.Cu")
		(net 401)
	)
	(segment
		(start 174.8 139.8)
		(end 175 140)
		(width 0.1)
		(layer "In9.Cu")
		(net 401)
	)
	(segment
		(start 140.65 143.45)
		(end 140.65 144.430557)
		(width 0.1)
		(layer "In9.Cu")
		(net 401)
	)
	(segment
		(start 175 140)
		(end 176.75 140)
		(width 0.1)
		(layer "In9.Cu")
		(net 401)
	)
	(segment
		(start 176.75 140)
		(end 177 140.25)
		(width 0.1)
		(layer "In9.Cu")
		(net 401)
	)
	(segment
		(start 142.25 143.125)
		(end 149.475 135.9)
		(width 0.1)
		(layer "In9.Cu")
		(net 401)
	)
	(segment
		(start 141.625 143.125)
		(end 142.25 143.125)
		(width 0.1)
		(layer "In9.Cu")
		(net 401)
	)
	(segment
		(start 141.3 144.430557)
		(end 141.3 143.45)
		(width 0.1)
		(layer "In9.Cu")
		(net 401)
	)
	(segment
		(start 140 143.125)
		(end 140.325 143.125)
		(width 0.1)
		(layer "In9.Cu")
		(net 401)
	)
	(arc
		(start 140.975 144.755557)
		(mid 141.20481 144.660367)
		(end 141.3 144.430557)
		(width 0.1)
		(layer "In9.Cu")
		(net 401)
	)
	(arc
		(start 140.65 144.430557)
		(mid 140.74519 144.660367)
		(end 140.975 144.755557)
		(width 0.1)
		(layer "In9.Cu")
		(net 401)
	)
	(arc
		(start 140.325 143.125)
		(mid 140.55481 143.22019)
		(end 140.65 143.45)
		(width 0.1)
		(layer "In9.Cu")
		(net 401)
	)
	(arc
		(start 141.3 143.45)
		(mid 141.39519 143.22019)
		(end 141.625 143.125)
		(width 0.1)
		(layer "In9.Cu")
		(net 401)
	)
	(segment
		(start 164.93 164.034999)
		(end 164.955 164.034999)
		(width 0.16)
		(layer "F.Cu")
		(net 402)
	)
	(segment
		(start 189.0005 159.0005)
		(end 189.5 159.500001)
		(width 0.256)
		(layer "F.Cu")
		(net 402)
	)
	(segment
		(start 165.285 163.704999)
		(end 166.1745 163.705)
		(width 0.16)
		(layer "F.Cu")
		(net 402)
	)
	(segment
		(start 166.1745 163.705)
		(end 166.319499 163.849999)
		(width 0.16)
		(layer "F.Cu")
		(net 402)
	)
	(segment
		(start 164.955 164.034999)
		(end 165.285 163.704999)
		(width 0.16)
		(layer "F.Cu")
		(net 402)
	)
	(via
		(at 166.319499 163.849999)
		(size 0.45)
		(drill 0.1)
		(layers "F.Cu" "B.Cu")
		(remove_unused_layers yes)
		(keep_end_layers yes)
		(zone_layer_connections)
		(net 402)
	)
	(via
		(at 189.5 159.500001)
		(size 0.45)
		(drill 0.1)
		(layers "F.Cu" "B.Cu")
		(remove_unused_layers yes)
		(keep_end_layers yes)
		(zone_layer_connections)
		(net 402)
	)
	(segment
		(start 165.603163 162.205415)
		(end 167.908578 159.9)
		(width 0.1)
		(layer "In6.Cu")
		(net 402)
	)
	(segment
		(start 165.603163 163.294585)
		(end 165.603163 162.205415)
		(width 0.1)
		(layer "In6.Cu")
		(net 402)
	)
	(segment
		(start 189.100001 159.9)
		(end 189.5 159.500001)
		(width 0.1)
		(layer "In6.Cu")
		(net 402)
	)
	(segment
		(start 167.908578 159.9)
		(end 189.100001 159.9)
		(width 0.1)
		(layer "In6.Cu")
		(net 402)
	)
	(segment
		(start 165.958577 163.649999)
		(end 165.603163 163.294585)
		(width 0.1)
		(layer "In6.Cu")
		(net 402)
	)
	(segment
		(start 166.119499 163.649999)
		(end 165.958577 163.649999)
		(width 0.1)
		(layer "In6.Cu")
		(net 402)
	)
	(segment
		(start 166.319499 163.849999)
		(end 166.119499 163.649999)
		(width 0.1)
		(layer "In6.Cu")
		(net 402)
	)
	(segment
		(start 178.5 146.5)
		(end 178.9995 146.9995)
		(width 0.256)
		(layer "F.Cu")
		(net 403)
	)
	(via
		(at 178.5 146.5)
		(size 0.45)
		(drill 0.1)
		(layers "F.Cu" "B.Cu")
		(remove_unused_layers yes)
		(keep_end_layers yes)
		(zone_layer_connections)
		(net 403)
	)
	(segment
		(start 177.401325 146.975)
		(end 177.401325 147.01235)
		(width 0.1)
		(layer "B.Cu")
		(net 403)
	)
	(segment
		(start 174.72059 148.162311)
		(end 174.883155 148.162311)
		(width 0.16)
		(layer "B.Cu")
		(net 403)
	)
	(segment
		(start 178.502 146.5)
		(end 178.5 146.5)
		(width 0.256)
		(layer "B.Cu")
		(net 403)
	)
	(segment
		(start 177.221325 146.843675)
		(end 177.27 146.843675)
		(width 0.1)
		(layer "B.Cu")
		(net 403)
	)
	(segment
		(start 174.333446 148.335757)
		(end 174.355785 148.313417)
		(width 0.16)
		(layer "B.Cu")
		(net 403)
	)
	(segment
		(start 177.890933 146.099999)
		(end 177.416777 146.099999)
		(width 0.1)
		(layer "B.Cu")
		(net 403)
	)
	(segment
		(start 174.16 149.183723)
		(end 174.16 148.754494)
		(width 0.16)
		(layer "B.Cu")
		(net 403)
	)
	(segment
		(start 178.5 146.499999)
		(end 178.247833 146.247832)
		(width 0.1)
		(layer "B.Cu")
		(net 403)
	)
	(segment
		(start 177.09 146.426776)
		(end 177.09 146.71235)
		(width 0.1)
		(layer "B.Cu")
		(net 403)
	)
	(segment
		(start 177.09 147.648578)
		(end 177.09 147.275)
		(width 0.1)
		(layer "B.Cu")
		(net 403)
	)
	(segment
		(start 174.48 149.870656)
		(end 174.48 150.209999)
		(width 0.16)
		(layer "B.Cu")
		(net 403)
	)
	(segment
		(start 175.057732 148.089999)
		(end 176.648579 148.089999)
		(width 0.1)
		(layer "B.Cu")
		(net 403)
	)
	(segment
		(start 178.505414 146.498585)
		(end 179 146.004)
		(width 0.256)
		(layer "B.Cu")
		(net 403)
	)
	(segment
		(start 174.32 149.569998)
		(end 174.38054 149.630538)
		(width 0.16)
		(layer "B.Cu")
		(net 403)
	)
	(segment
		(start 177.27 147.143675)
		(end 177.221325 147.143675)
		(width 0.1)
		(layer "B.Cu")
		(net 403)
	)
	(arc
		(start 174.72059 148.162311)
		(mid 174.523159 148.201582)
		(end 174.355785 148.313417)
		(width 0.16)
		(layer "B.Cu")
		(net 403)
	)
	(arc
		(start 174.333446 148.335757)
		(mid 174.205077 148.527875)
		(end 174.16 148.754494)
		(width 0.16)
		(layer "B.Cu")
		(net 403)
	)
	(arc
		(start 176.648579 148.089999)
		(mid 176.817503 148.056397)
		(end 176.960711 147.96071)
		(width 0.1)
		(layer "B.Cu")
		(net 403)
	)
	(arc
		(start 177.27 146.843675)
		(mid 177.362861 146.882139)
		(end 177.401325 146.975)
		(width 0.1)
		(layer "B.Cu")
		(net 403)
	)
	(arc
		(start 174.883155 148.162311)
		(mid 174.930395 148.152914)
		(end 174.970444 148.126155)
		(width 0.1)
		(layer "B.Cu")
		(net 403)
	)
	(arc
		(start 174.970444 148.126155)
		(mid 175.010492 148.099395)
		(end 175.057732 148.089999)
		(width 0.1)
		(layer "B.Cu")
		(net 403)
	)
	(arc
		(start 177.185711 146.19571)
		(mid 177.114874 146.301724)
		(end 177.09 146.426776)
		(width 0.1)
		(layer "B.Cu")
		(net 403)
	)
	(arc
		(start 177.09 146.71235)
		(mid 177.128464 146.805211)
		(end 177.221325 146.843675)
		(width 0.1)
		(layer "B.Cu")
		(net 403)
	)
	(arc
		(start 177.09 147.275)
		(mid 177.128464 147.182139)
		(end 177.221325 147.143675)
		(width 0.1)
		(layer "B.Cu")
		(net 403)
	)
	(arc
		(start 178.502 146.5)
		(mid 178.503847 146.499632)
		(end 178.505414 146.498585)
		(width 0.256)
		(layer "B.Cu")
		(net 403)
	)
	(arc
		(start 177.401325 147.01235)
		(mid 177.362861 147.105211)
		(end 177.27 147.143675)
		(width 0.1)
		(layer "B.Cu")
		(net 403)
	)
	(arc
		(start 176.960711 147.96071)
		(mid 177.056398 147.817502)
		(end 177.09 147.648578)
		(width 0.1)
		(layer "B.Cu")
		(net 403)
	)
	(arc
		(start 174.16 149.183723)
		(mid 174.201582 149.392773)
		(end 174.32 149.569998)
		(width 0.16)
		(layer "B.Cu")
		(net 403)
	)
	(arc
		(start 174.48 149.870656)
		(mid 174.454151 149.740705)
		(end 174.38054 149.630538)
		(width 0.16)
		(layer "B.Cu")
		(net 403)
	)
	(arc
		(start 178.247833 146.247832)
		(mid 178.084086 146.13842)
		(end 177.890933 146.099999)
		(width 0.1)
		(layer "B.Cu")
		(net 403)
	)
	(arc
		(start 177.416777 146.099999)
		(mid 177.291725 146.124873)
		(end 177.185711 146.19571)
		(width 0.1)
		(layer "B.Cu")
		(net 403)
	)
	(segment
		(start 241.924499 182.999)
		(end 241.918499 183.005)
		(width 0.177)
		(layer "F.Cu")
		(net 404)
	)
	(segment
		(start 241.918499 183.005)
		(end 240.651499 183.005)
		(width 0.177)
		(layer "F.Cu")
		(net 404)
	)
	(segment
		(start 241.001 140.101)
		(end 240 140.101)
		(width 0.256)
		(layer "F.Cu")
		(net 404)
	)
	(segment
		(start 241.930499 186.755)
		(end 240.651499 186.755)
		(width 0.177)
		(layer "F.Cu")
		(net 404)
	)
	(segment
		(start 242.374499 187.199)
		(end 241.930499 186.755)
		(width 0.177)
		(layer "F.Cu")
		(net 404)
	)
	(via
		(at 240 140.101)
		(size 0.45)
		(drill 0.1)
		(layers "F.Cu" "B.Cu")
		(remove_unused_layers yes)
		(keep_end_layers yes)
		(zone_layer_connections)
		(net 404)
	)
	(via
		(at 242.374499 187.199)
		(size 0.45)
		(drill 0.1)
		(layers "F.Cu" "B.Cu")
		(remove_unused_layers yes)
		(keep_end_layers yes)
		(zone_layer_connections)
		(net 404)
	)
	(via
		(at 241.924499 182.999)
		(size 0.45)
		(drill 0.1)
		(layers "F.Cu" "B.Cu")
		(remove_unused_layers yes)
		(keep_end_layers yes)
		(zone_layer_connections)
		(net 404)
	)
	(segment
		(start 260.775499 143.2)
		(end 252.525 143.2)
		(width 0.1)
		(layer "B.Cu")
		(net 404)
	)
	(segment
		(start 264.05 146.474501)
		(end 260.775499 143.2)
		(width 0.1)
		(layer "B.Cu")
		(net 404)
	)
	(segment
		(start 264.05 170.871752)
		(end 264.05 146.474501)
		(width 0.1)
		(layer "B.Cu")
		(net 404)
	)
	(segment
		(start 260.274499 180.849)
		(end 263.874499 177.249)
		(width 0.1)
		(layer "B.Cu")
		(net 404)
	)
	(segment
		(start 242.799499 183.575501)
		(end 245.526 180.849)
		(width 0.1)
		(layer "B.Cu")
		(net 404)
	)
	(segment
		(start 239.2595 140.0975)
		(end 239.9965 140.0975)
		(width 0.4)
		(layer "B.Cu")
		(net 404)
	)
	(segment
		(start 242.374499 187.199)
		(end 242.799499 186.774)
		(width 0.1)
		(layer "B.Cu")
		(net 404)
	)
	(segment
		(start 245.526 180.849)
		(end 260.274499 180.849)
		(width 0.1)
		(layer "B.Cu")
		(net 404)
	)
	(segment
		(start 242.799499 186.774)
		(end 242.799499 183.575501)
		(width 0.1)
		(layer "B.Cu")
		(net 404)
	)
	(segment
		(start 250.8395 141.5145)
		(end 241.4135 141.5145)
		(width 0.1)
		(layer "B.Cu")
		(net 404)
	)
	(segment
		(start 241.4135 141.5145)
		(end 240 140.101)
		(width 0.1)
		(layer "B.Cu")
		(net 404)
	)
	(segment
		(start 263.874499 177.249)
		(end 263.874499 171.047253)
		(width 0.1)
		(layer "B.Cu")
		(net 404)
	)
	(segment
		(start 239.9965 140.0975)
		(end 240 140.101)
		(width 0.4)
		(layer "B.Cu")
		(net 404)
	)
	(segment
		(start 263.874499 171.047253)
		(end 264.05 170.871752)
		(width 0.1)
		(layer "B.Cu")
		(net 404)
	)
	(segment
		(start 252.525 143.2)
		(end 250.8395 141.5145)
		(width 0.1)
		(layer "B.Cu")
		(net 404)
	)
	(segment
		(start 241.924499 186.749)
		(end 241.924499 182.999)
		(width 0.15)
		(layer "In4.Cu")
		(net 404)
	)
	(segment
		(start 242.374499 187.199)
		(end 241.924499 186.749)
		(width 0.15)
		(layer "In4.Cu")
		(net 404)
	)
	(segment
		(start 241.418499 187.256)
		(end 241.424499 187.25)
		(width 0.177)
		(layer "F.Cu")
		(net 405)
	)
	(segment
		(start 241.001 141.101)
		(end 240 141.101)
		(width 0.256)
		(layer "F.Cu")
		(net 405)
	)
	(segment
		(start 240.651499 183.506)
		(end 241.418499 183.506)
		(width 0.177)
		(layer "F.Cu")
		(net 405)
	)
	(segment
		(start 241.418499 183.506)
		(end 241.424499 183.5)
		(width 0.177)
		(layer "F.Cu")
		(net 405)
	)
	(segment
		(start 240.651499 187.256)
		(end 241.418499 187.256)
		(width 0.177)
		(layer "F.Cu")
		(net 405)
	)
	(via
		(at 240 141.101)
		(size 0.45)
		(drill 0.1)
		(layers "F.Cu" "B.Cu")
		(remove_unused_layers yes)
		(keep_end_layers yes)
		(zone_layer_connections)
		(net 405)
	)
	(via
		(at 241.424499 187.25)
		(size 0.45)
		(drill 0.1)
		(layers "F.Cu" "B.Cu")
		(remove_unused_layers yes)
		(keep_end_layers yes)
		(zone_layer_connections)
		(net 405)
	)
	(via
		(at 241.424499 183.5)
		(size 0.45)
		(drill 0.1)
		(layers "F.Cu" "B.Cu")
		(remove_unused_layers yes)
		(keep_end_layers yes)
		(zone_layer_connections)
		(net 405)
	)
	(segment
		(start 263.024499 146.149499)
		(end 261.825 144.95)
		(width 0.1)
		(layer "B.Cu")
		(net 405)
	)
	(segment
		(start 248.511778 144.95)
		(end 248.075278 144.5135)
		(width 0.1)
		(layer "B.Cu")
		(net 405)
	)
	(segment
		(start 263.024499 174.858314)
		(end 263.05 174.832813)
		(width 0.1)
		(layer "B.Cu")
		(net 405)
	)
	(segment
		(start 242.2875 183.5375)
		(end 245.476 180.349)
		(width 0.1)
		(layer "B.Cu")
		(net 405)
	)
	(segment
		(start 241.424499 187.25)
		(end 241.45 187.25)
		(width 0.1)
		(layer "B.Cu")
		(net 405)
	)
	(segment
		(start 244.5905 144.5135)
		(end 243.9245 143.8475)
		(width 0.1)
		(layer "B.Cu")
		(net 405)
	)
	(segment
		(start 261.825 144.95)
		(end 248.511778 144.95)
		(width 0.1)
		(layer "B.Cu")
		(net 405)
	)
	(segment
		(start 248.075278 144.5135)
		(end 244.5905 144.5135)
		(width 0.1)
		(layer "B.Cu")
		(net 405)
	)
	(segment
		(start 245.476 180.349)
		(end 259.473497 180.349)
		(width 0.1)
		(layer "B.Cu")
		(net 405)
	)
	(segment
		(start 263.024499 176.797998)
		(end 263.024499 174.858314)
		(width 0.1)
		(layer "B.Cu")
		(net 405)
	)
	(segment
		(start 241.461999 183.5375)
		(end 241.424499 183.5)
		(width 0.1)
		(layer "B.Cu")
		(net 405)
	)
	(segment
		(start 263.05 159.540187)
		(end 263.024499 159.514686)
		(width 0.1)
		(layer "B.Cu")
		(net 405)
	)
	(segment
		(start 243.9245 143.8475)
		(end 242.7465 143.8475)
		(width 0.1)
		(layer "B.Cu")
		(net 405)
	)
	(segment
		(start 242.7465 143.8475)
		(end 240 141.101)
		(width 0.1)
		(layer "B.Cu")
		(net 405)
	)
	(segment
		(start 239.313001 141.101)
		(end 240 141.101)
		(width 0.4)
		(layer "B.Cu")
		(net 405)
	)
	(segment
		(start 263.05 174.832813)
		(end 263.05 159.540187)
		(width 0.1)
		(layer "B.Cu")
		(net 405)
	)
	(segment
		(start 242.2875 183.5375)
		(end 241.461999 183.5375)
		(width 0.1)
		(layer "B.Cu")
		(net 405)
	)
	(segment
		(start 263.024499 159.514686)
		(end 263.024499 146.149499)
		(width 0.1)
		(layer "B.Cu")
		(net 405)
	)
	(segment
		(start 259.473497 180.349)
		(end 263.024499 176.797998)
		(width 0.1)
		(layer "B.Cu")
		(net 405)
	)
	(segment
		(start 241.624499 183.7)
		(end 241.624499 185.174)
		(width 0.15)
		(layer "In4.Cu")
		(net 405)
	)
	(segment
		(start 241.624499 185.174)
		(end 240.949499 185.849)
		(width 0.15)
		(layer "In4.Cu")
		(net 405)
	)
	(segment
		(start 240.949499 185.849)
		(end 240.949499 186.775)
		(width 0.15)
		(layer "In4.Cu")
		(net 405)
	)
	(segment
		(start 240.949499 186.775)
		(end 241.424499 187.25)
		(width 0.15)
		(layer "In4.Cu")
		(net 405)
	)
	(segment
		(start 241.424499 183.5)
		(end 241.624499 183.7)
		(width 0.15)
		(layer "In4.Cu")
		(net 405)
	)
	(segment
		(start 175.9995 157.0005)
		(end 175.5 157.5)
		(width 0.256)
		(layer "F.Cu")
		(net 406)
	)
	(via
		(at 175.5 157.5)
		(size 0.45)
		(drill 0.1)
		(layers "F.Cu" "B.Cu")
		(remove_unused_layers yes)
		(keep_end_layers yes)
		(zone_layer_connections)
		(net 406)
	)
	(via
		(at 142.349499 170.674)
		(size 0.45)
		(drill 0.1)
		(layers "F.Cu" "B.Cu")
		(remove_unused_layers yes)
		(keep_end_layers yes)
		(zone_layer_connections)
		(net 406)
	)
	(segment
		(start 143.224499 169.884)
		(end 143.224499 170.324)
		(width 0.15)
		(layer "B.Cu")
		(net 406)
	)
	(segment
		(start 142.874499 170.674)
		(end 142.349499 170.674)
		(width 0.15)
		(layer "B.Cu")
		(net 406)
	)
	(segment
		(start 143.224499 170.324)
		(end 142.874499 170.674)
		(width 0.15)
		(layer "B.Cu")
		(net 406)
	)
	(segment
		(start 143.5 174)
		(end 142.349499 172.849499)
		(width 0.1)
		(layer "In9.Cu")
		(net 406)
	)
	(segment
		(start 166.05 165.45)
		(end 163.05 165.45)
		(width 0.1)
		(layer "In9.Cu")
		(net 406)
	)
	(segment
		(start 163.05 165.45)
		(end 154.5 174)
		(width 0.1)
		(layer "In9.Cu")
		(net 406)
	)
	(segment
		(start 174 157.5)
		(end 166.05 165.45)
		(width 0.1)
		(layer "In9.Cu")
		(net 406)
	)
	(segment
		(start 142.349499 172.849499)
		(end 142.349499 170.674)
		(width 0.1)
		(layer "In9.Cu")
		(net 406)
	)
	(segment
		(start 154.5 174)
		(end 143.5 174)
		(width 0.1)
		(layer "In9.Cu")
		(net 406)
	)
	(segment
		(start 175.5 157.5)
		(end 174 157.5)
		(width 0.1)
		(layer "In9.Cu")
		(net 406)
	)
	(segment
		(start 143.724499 167.949)
		(end 143.424499 167.649)
		(width 0.15)
		(layer "F.Cu")
		(net 407)
	)
	(segment
		(start 143.724499 169.414)
		(end 143.724499 167.949)
		(width 0.15)
		(layer "F.Cu")
		(net 407)
	)
	(segment
		(start 143.433 166.772)
		(end 143.433 167.640499)
		(width 0.15)
		(layer "F.Cu")
		(net 407)
	)
	(segment
		(start 143.433 167.640499)
		(end 143.424499 167.649)
		(width 0.15)
		(layer "F.Cu")
		(net 407)
	)
	(via
		(at 143.424499 167.649)
		(size 0.45)
		(drill 0.1)
		(layers "F.Cu" "B.Cu")
		(remove_unused_layers yes)
		(keep_end_layers yes)
		(zone_layer_connections)
		(net 407)
	)
	(segment
		(start 143.424499 168.064)
		(end 144.274499 168.914)
		(width 0.15)
		(layer "B.Cu")
		(net 407)
	)
	(segment
		(start 143.424499 167.649)
		(end 143.424499 168.064)
		(width 0.15)
		(layer "B.Cu")
		(net 407)
	)
	(segment
		(start 178.9995 157.0005)
		(end 178.500001 157.5)
		(width 0.256)
		(layer "F.Cu")
		(net 408)
	)
	(via
		(at 143.049499 171.074)
		(size 0.45)
		(drill 0.1)
		(layers "F.Cu" "B.Cu")
		(remove_unused_layers yes)
		(keep_end_layers yes)
		(zone_layer_connections)
		(net 408)
	)
	(via
		(at 178.500001 157.5)
		(size 0.45)
		(drill 0.1)
		(layers "F.Cu" "B.Cu")
		(remove_unused_layers yes)
		(keep_end_layers yes)
		(zone_layer_connections)
		(net 408)
	)
	(segment
		(start 144.274499 169.884)
		(end 144.274499 170.424)
		(width 0.15)
		(layer "B.Cu")
		(net 408)
	)
	(segment
		(start 144.274499 170.424)
		(end 143.624499 171.074)
		(width 0.15)
		(layer "B.Cu")
		(net 408)
	)
	(segment
		(start 143.624499 171.074)
		(end 143.049499 171.074)
		(width 0.15)
		(layer "B.Cu")
		(net 408)
	)
	(segment
		(start 142.2 175.4)
		(end 156.1 175.4)
		(width 0.1)
		(layer "In9.Cu")
		(net 408)
	)
	(segment
		(start 164 167.5)
		(end 167 167.5)
		(width 0.1)
		(layer "In9.Cu")
		(net 408)
	)
	(segment
		(start 177.99 159.71)
		(end 177.99 158.010001)
		(width 0.1)
		(layer "In9.Cu")
		(net 408)
	)
	(segment
		(start 140.749499 173.949499)
		(end 142.2 175.4)
		(width 0.1)
		(layer "In9.Cu")
		(net 408)
	)
	(segment
		(start 142.66 170.08)
		(end 140.98 170.08)
		(width 0.1)
		(layer "In9.Cu")
		(net 408)
	)
	(segment
		(start 143.049499 171.074)
		(end 143.049499 170.469499)
		(width 0.1)
		(layer "In9.Cu")
		(net 408)
	)
	(segment
		(start 156.1 175.4)
		(end 164 167.5)
		(width 0.1)
		(layer "In9.Cu")
		(net 408)
	)
	(segment
		(start 177.99 158.010001)
		(end 178.500001 157.5)
		(width 0.1)
		(layer "In9.Cu")
		(net 408)
	)
	(segment
		(start 174.5 160)
		(end 177.7 160)
		(width 0.1)
		(layer "In9.Cu")
		(net 408)
	)
	(segment
		(start 177.7 160)
		(end 177.99 159.71)
		(width 0.1)
		(layer "In9.Cu")
		(net 408)
	)
	(segment
		(start 140.749499 170.310501)
		(end 140.749499 173.949499)
		(width 0.1)
		(layer "In9.Cu")
		(net 408)
	)
	(segment
		(start 140.98 170.08)
		(end 140.749499 170.310501)
		(width 0.1)
		(layer "In9.Cu")
		(net 408)
	)
	(segment
		(start 167 167.5)
		(end 174.5 160)
		(width 0.1)
		(layer "In9.Cu")
		(net 408)
	)
	(segment
		(start 143.049499 170.469499)
		(end 142.66 170.08)
		(width 0.1)
		(layer "In9.Cu")
		(net 408)
	)
	(segment
		(start 130.35 146.15)
		(end 130.504992 145.995008)
		(width 0.256)
		(layer "F.Cu")
		(net 409)
	)
	(segment
		(start 179.9995 144.9995)
		(end 179.499999 144.5)
		(width 0.256)
		(layer "F.Cu")
		(net 409)
	)
	(segment
		(start 130.504992 145.995008)
		(end 131.239179 145.995008)
		(width 0.256)
		(layer "F.Cu")
		(net 409)
	)
	(via
		(at 130.35 146.15)
		(size 0.45)
		(drill 0.1)
		(layers "F.Cu" "B.Cu")
		(remove_unused_layers yes)
		(keep_end_layers yes)
		(zone_layer_connections)
		(net 409)
	)
	(via
		(at 179.499999 144.5)
		(size 0.45)
		(drill 0.1)
		(layers "F.Cu" "B.Cu")
		(remove_unused_layers yes)
		(keep_end_layers yes)
		(zone_layer_connections)
		(net 409)
	)
	(segment
		(start 157.6 134.308949)
		(end 157.6 134.425)
		(width 0.1)
		(layer "In9.Cu")
		(net 409)
	)
	(segment
		(start 135.943168 141.5)
		(end 142.55 141.5)
		(width 0.1)
		(layer "In9.Cu")
		(net 409)
	)
	(segment
		(start 178.979999 143.98)
		(end 179.499999 144.5)
		(width 0.1)
		(layer "In9.Cu")
		(net 409)
	)
	(segment
		(start 176.975 139.65)
		(end 177.375 140.05)
		(width 0.1)
		(layer "In9.Cu")
		(net 409)
	)
	(segment
		(start 158.45 134.425)
		(end 158.45 134.308963)
		(width 0.1)
		(layer "In9.Cu")
		(net 409)
	)
	(segment
		(start 172 139)
		(end 176.75 139)
		(width 0.1)
		(layer "In9.Cu")
		(net 409)
	)
	(segment
		(start 178 143.65)
		(end 178.33 143.98)
		(width 0.1)
		(layer "In9.Cu")
		(net 409)
	)
	(segment
		(start 160.15 134.425)
		(end 160.15 134.308949)
		(width 0.1)
		(layer "In9.Cu")
		(net 409)
	)
	(segment
		(start 156.75 134.425)
		(end 156.75 134.308949)
		(width 0.1)
		(layer "In9.Cu")
		(net 409)
	)
	(segment
		(start 177.725 140.05)
		(end 178 140.325)
		(width 0.1)
		(layer "In9.Cu")
		(net 409)
	)
	(segment
		(start 150.8 134.308949)
		(end 150.8 134.425)
		(width 0.1)
		(layer "In9.Cu")
		(net 409)
	)
	(segment
		(start 162.7 134.308977)
		(end 162.7 134.425)
		(width 0.1)
		(layer "In9.Cu")
		(net 409)
	)
	(segment
		(start 153.35 134.425)
		(end 153.35 134.308949)
		(width 0.1)
		(layer "In9.Cu")
		(net 409)
	)
	(segment
		(start 155.05 134.425)
		(end 155.05 134.308949)
		(width 0.1)
		(layer "In9.Cu")
		(net 409)
	)
	(segment
		(start 178 140.325)
		(end 178 143.65)
		(width 0.1)
		(layer "In9.Cu")
		(net 409)
	)
	(segment
		(start 142.55 141.5)
		(end 149.2 134.85)
		(width 0.1)
		(layer "In9.Cu")
		(net 409)
	)
	(segment
		(start 131.293168 146.15)
		(end 135.943168 141.5)
		(width 0.1)
		(layer "In9.Cu")
		(net 409)
	)
	(segment
		(start 149.95 134.425)
		(end 149.95 134.308949)
		(width 0.1)
		(layer "In9.Cu")
		(net 409)
	)
	(segment
		(start 149.2 134.85)
		(end 149.525 134.85)
		(width 0.1)
		(layer "In9.Cu")
		(net 409)
	)
	(segment
		(start 177.375 140.05)
		(end 177.725 140.05)
		(width 0.1)
		(layer "In9.Cu")
		(net 409)
	)
	(segment
		(start 178.33 143.98)
		(end 178.979999 143.98)
		(width 0.1)
		(layer "In9.Cu")
		(net 409)
	)
	(segment
		(start 176.75 139)
		(end 176.975 139.225)
		(width 0.1)
		(layer "In9.Cu")
		(net 409)
	)
	(segment
		(start 152.5 134.308949)
		(end 152.5 134.425)
		(width 0.1)
		(layer "In9.Cu")
		(net 409)
	)
	(segment
		(start 161.85 134.425)
		(end 161.85 134.308977)
		(width 0.1)
		(layer "In9.Cu")
		(net 409)
	)
	(segment
		(start 130.35 146.15)
		(end 131.293168 146.15)
		(width 0.1)
		(layer "In9.Cu")
		(net 409)
	)
	(segment
		(start 176.975 139.225)
		(end 176.975 139.65)
		(width 0.1)
		(layer "In9.Cu")
		(net 409)
	)
	(segment
		(start 151.65 134.425)
		(end 151.65 134.308949)
		(width 0.1)
		(layer "In9.Cu")
		(net 409)
	)
	(segment
		(start 163.125 134.85)
		(end 167.85 134.85)
		(width 0.1)
		(layer "In9.Cu")
		(net 409)
	)
	(segment
		(start 155.9 134.308949)
		(end 155.9 134.425)
		(width 0.1)
		(layer "In9.Cu")
		(net 409)
	)
	(segment
		(start 167.85 134.85)
		(end 172 139)
		(width 0.1)
		(layer "In9.Cu")
		(net 409)
	)
	(segment
		(start 154.2 134.308949)
		(end 154.2 134.425)
		(width 0.1)
		(layer "In9.Cu")
		(net 409)
	)
	(segment
		(start 161 134.308949)
		(end 161 134.425)
		(width 0.1)
		(layer "In9.Cu")
		(net 409)
	)
	(segment
		(start 159.3 134.308963)
		(end 159.3 134.425)
		(width 0.1)
		(layer "In9.Cu")
		(net 409)
	)
	(arc
		(start 162.275 133.883977)
		(mid 162.57552 134.008457)
		(end 162.7 134.308977)
		(width 0.1)
		(layer "In9.Cu")
		(net 409)
	)
	(arc
		(start 158.45 134.308963)
		(mid 158.57448 134.008443)
		(end 158.875 133.883963)
		(width 0.1)
		(layer "In9.Cu")
		(net 409)
	)
	(arc
		(start 151.225 134.85)
		(mid 151.52552 134.72552)
		(end 151.65 134.425)
		(width 0.1)
		(layer "In9.Cu")
		(net 409)
	)
	(arc
		(start 154.2 134.425)
		(mid 154.32448 134.72552)
		(end 154.625 134.85)
		(width 0.1)
		(layer "In9.Cu")
		(net 409)
	)
	(arc
		(start 159.3 134.425)
		(mid 159.42448 134.72552)
		(end 159.725 134.85)
		(width 0.1)
		(layer "In9.Cu")
		(net 409)
	)
	(arc
		(start 153.35 134.308949)
		(mid 153.47448 134.008429)
		(end 153.775 133.883949)
		(width 0.1)
		(layer "In9.Cu")
		(net 409)
	)
	(arc
		(start 161.425 134.85)
		(mid 161.72552 134.72552)
		(end 161.85 134.425)
		(width 0.1)
		(layer "In9.Cu")
		(net 409)
	)
	(arc
		(start 152.075 133.883949)
		(mid 152.37552 134.008429)
		(end 152.5 134.308949)
		(width 0.1)
		(layer "In9.Cu")
		(net 409)
	)
	(arc
		(start 160.575 133.883949)
		(mid 160.87552 134.008429)
		(end 161 134.308949)
		(width 0.1)
		(layer "In9.Cu")
		(net 409)
	)
	(arc
		(start 149.95 134.308949)
		(mid 150.07448 134.008429)
		(end 150.375 133.883949)
		(width 0.1)
		(layer "In9.Cu")
		(net 409)
	)
	(arc
		(start 150.8 134.425)
		(mid 150.92448 134.72552)
		(end 151.225 134.85)
		(width 0.1)
		(layer "In9.Cu")
		(net 409)
	)
	(arc
		(start 157.175 133.883949)
		(mid 157.47552 134.008429)
		(end 157.6 134.308949)
		(width 0.1)
		(layer "In9.Cu")
		(net 409)
	)
	(arc
		(start 155.9 134.425)
		(mid 156.02448 134.72552)
		(end 156.325 134.85)
		(width 0.1)
		(layer "In9.Cu")
		(net 409)
	)
	(arc
		(start 161.85 134.308977)
		(mid 161.97448 134.008457)
		(end 162.275 133.883977)
		(width 0.1)
		(layer "In9.Cu")
		(net 409)
	)
	(arc
		(start 152.925 134.85)
		(mid 153.22552 134.72552)
		(end 153.35 134.425)
		(width 0.1)
		(layer "In9.Cu")
		(net 409)
	)
	(arc
		(start 161 134.425)
		(mid 161.12448 134.72552)
		(end 161.425 134.85)
		(width 0.1)
		(layer "In9.Cu")
		(net 409)
	)
	(arc
		(start 156.325 134.85)
		(mid 156.62552 134.72552)
		(end 156.75 134.425)
		(width 0.1)
		(layer "In9.Cu")
		(net 409)
	)
	(arc
		(start 153.775 133.883949)
		(mid 154.07552 134.008429)
		(end 154.2 134.308949)
		(width 0.1)
		(layer "In9.Cu")
		(net 409)
	)
	(arc
		(start 156.75 134.308949)
		(mid 156.87448 134.008429)
		(end 157.175 133.883949)
		(width 0.1)
		(layer "In9.Cu")
		(net 409)
	)
	(arc
		(start 150.375 133.883949)
		(mid 150.67552 134.008429)
		(end 150.8 134.308949)
		(width 0.1)
		(layer "In9.Cu")
		(net 409)
	)
	(arc
		(start 159.725 134.85)
		(mid 160.02552 134.72552)
		(end 160.15 134.425)
		(width 0.1)
		(layer "In9.Cu")
		(net 409)
	)
	(arc
		(start 158.025 134.85)
		(mid 158.32552 134.72552)
		(end 158.45 134.425)
		(width 0.1)
		(layer "In9.Cu")
		(net 409)
	)
	(arc
		(start 154.625 134.85)
		(mid 154.92552 134.72552)
		(end 155.05 134.425)
		(width 0.1)
		(layer "In9.Cu")
		(net 409)
	)
	(arc
		(start 158.875 133.883963)
		(mid 159.17552 134.008443)
		(end 159.3 134.308963)
		(width 0.1)
		(layer "In9.Cu")
		(net 409)
	)
	(arc
		(start 157.6 134.425)
		(mid 157.72448 134.72552)
		(end 158.025 134.85)
		(width 0.1)
		(layer "In9.Cu")
		(net 409)
	)
	(arc
		(start 151.65 134.308949)
		(mid 151.77448 134.008429)
		(end 152.075 133.883949)
		(width 0.1)
		(layer "In9.Cu")
		(net 409)
	)
	(arc
		(start 152.5 134.425)
		(mid 152.62448 134.72552)
		(end 152.925 134.85)
		(width 0.1)
		(layer "In9.Cu")
		(net 409)
	)
	(arc
		(start 155.05 134.308949)
		(mid 155.17448 134.008429)
		(end 155.475 133.883949)
		(width 0.1)
		(layer "In9.Cu")
		(net 409)
	)
	(arc
		(start 149.525 134.85)
		(mid 149.82552 134.72552)
		(end 149.95 134.425)
		(width 0.1)
		(layer "In9.Cu")
		(net 409)
	)
	(arc
		(start 155.475 133.883949)
		(mid 155.77552 134.008429)
		(end 155.9 134.308949)
		(width 0.1)
		(layer "In9.Cu")
		(net 409)
	)
	(arc
		(start 160.15 134.308949)
		(mid 160.27448 134.008429)
		(end 160.575 133.883949)
		(width 0.1)
		(layer "In9.Cu")
		(net 409)
	)
	(arc
		(start 162.7 134.425)
		(mid 162.82448 134.72552)
		(end 163.125 134.85)
		(width 0.1)
		(layer "In9.Cu")
		(net 409)
	)
	(segment
		(start 137.425 147.15)
		(end 137.8 147.525)
		(width 0.256)
		(layer "F.Cu")
		(net 410)
	)
	(segment
		(start 177.9995 143.9995)
		(end 177.5 143.5)
		(width 0.256)
		(layer "F.Cu")
		(net 410)
	)
	(segment
		(start 137.425 146.734)
		(end 137.425 147.15)
		(width 0.256)
		(layer "F.Cu")
		(net 410)
	)
	(via
		(at 137.8 147.525)
		(size 0.45)
		(drill 0.1)
		(layers "F.Cu" "B.Cu")
		(remove_unused_layers yes)
		(keep_end_layers yes)
		(zone_layer_connections)
		(net 410)
	)
	(via
		(at 177.5 143.5)
		(size 0.45)
		(drill 0.1)
		(layers "F.Cu" "B.Cu")
		(remove_unused_layers yes)
		(keep_end_layers yes)
		(zone_layer_connections)
		(net 410)
	)
	(segment
		(start 160.635035 139.585035)
		(end 160.635035 139.585034)
		(width 0.1)
		(layer "In9.Cu")
		(net 410)
	)
	(segment
		(start 138.324 148.049)
		(end 137.8 147.525)
		(width 0.1)
		(layer "In9.Cu")
		(net 410)
	)
	(segment
		(start 165.24507 139.395069)
		(end 165.025 139.395069)
		(width 0.1)
		(layer "In9.Cu")
		(net 410)
	)
	(segment
		(start 164.04507 139.395069)
		(end 163.825 139.395069)
		(width 0.1)
		(layer "In9.Cu")
		(net 410)
	)
	(segment
		(start 152.075 139.775)
		(end 150.5125 141.3375)
		(width 0.1)
		(layer "In9.Cu")
		(net 410)
	)
	(segment
		(start 162.84507 139.395069)
		(end 162.625 139.395069)
		(width 0.1)
		(layer "In9.Cu")
		(net 410)
	)
	(segment
		(start 177.5 143.5)
		(end 177 143)
		(width 0.1)
		(layer "In9.Cu")
		(net 410)
	)
	(segment
		(start 175.85 142)
		(end 170.1 142)
		(width 0.1)
		(layer "In9.Cu")
		(net 410)
	)
	(segment
		(start 163.635035 139.585034)
		(end 163.635035 139.585035)
		(width 0.1)
		(layer "In9.Cu")
		(net 410)
	)
	(segment
		(start 166.035035 139.585034)
		(end 166.035035 139.585035)
		(width 0.1)
		(layer "In9.Cu")
		(net 410)
	)
	(segment
		(start 169.1 141)
		(end 168.625 141)
		(width 0.1)
		(layer "In9.Cu")
		(net 410)
	)
	(segment
		(start 166.635035 139.585035)
		(end 166.635035 139.585034)
		(width 0.1)
		(layer "In9.Cu")
		(net 410)
	)
	(segment
		(start 157.635035 139.585034)
		(end 157.635035 139.585035)
		(width 0.1)
		(layer "In9.Cu")
		(net 410)
	)
	(segment
		(start 158.235035 139.585035)
		(end 158.235035 139.585034)
		(width 0.1)
		(layer "In9.Cu")
		(net 410)
	)
	(segment
		(start 150.5125 141.3375)
		(end 150.5125 142.9875)
		(width 0.1)
		(layer "In9.Cu")
		(net 410)
	)
	(segment
		(start 168.625 141)
		(end 167.4 139.775)
		(width 0.1)
		(layer "In9.Cu")
		(net 410)
	)
	(segment
		(start 141.4 148.049)
		(end 138.324 148.049)
		(width 0.1)
		(layer "In9.Cu")
		(net 410)
	)
	(segment
		(start 159.245152 139.395151)
		(end 159.025 139.395151)
		(width 0.1)
		(layer "In9.Cu")
		(net 410)
	)
	(segment
		(start 164.235035 139.585035)
		(end 164.235035 139.585034)
		(width 0.1)
		(layer "In9.Cu")
		(net 410)
	)
	(segment
		(start 162.24507 139.775)
		(end 162.025 139.775)
		(width 0.1)
		(layer "In9.Cu")
		(net 410)
	)
	(segment
		(start 155.235035 139.585034)
		(end 155.235035 139.585035)
		(width 0.1)
		(layer "In9.Cu")
		(net 410)
	)
	(segment
		(start 161.64507 139.395069)
		(end 161.425 139.395069)
		(width 0.1)
		(layer "In9.Cu")
		(net 410)
	)
	(segment
		(start 158.835076 139.585075)
		(end 158.835076 139.585076)
		(width 0.1)
		(layer "In9.Cu")
		(net 410)
	)
	(segment
		(start 164.64507 139.775)
		(end 164.425 139.775)
		(width 0.1)
		(layer "In9.Cu")
		(net 410)
	)
	(segment
		(start 170.1 142)
		(end 169.1 141)
		(width 0.1)
		(layer "In9.Cu")
		(net 410)
	)
	(segment
		(start 156.24507 139.775)
		(end 156.025 139.775)
		(width 0.1)
		(layer "In9.Cu")
		(net 410)
	)
	(segment
		(start 155.04507 139.775)
		(end 154.825 139.775)
		(width 0.1)
		(layer "In9.Cu")
		(net 410)
	)
	(segment
		(start 159.435076 139.585076)
		(end 159.435076 139.585075)
		(width 0.1)
		(layer "In9.Cu")
		(net 410)
	)
	(segment
		(start 156.435035 139.585034)
		(end 156.435035 139.585035)
		(width 0.1)
		(layer "In9.Cu")
		(net 410)
	)
	(segment
		(start 176 142.15)
		(end 175.85 142)
		(width 0.1)
		(layer "In9.Cu")
		(net 410)
	)
	(segment
		(start 141.799 147.65)
		(end 141.4 148.049)
		(width 0.1)
		(layer "In9.Cu")
		(net 410)
	)
	(segment
		(start 154.035035 139.585034)
		(end 154.035035 139.585035)
		(width 0.1)
		(layer "In9.Cu")
		(net 410)
	)
	(segment
		(start 156.84507 139.395069)
		(end 156.625 139.395069)
		(width 0.1)
		(layer "In9.Cu")
		(net 410)
	)
	(segment
		(start 161.235035 139.585034)
		(end 161.235035 139.585035)
		(width 0.1)
		(layer "In9.Cu")
		(net 410)
	)
	(segment
		(start 160.035035 139.585034)
		(end 160.035035 139.585035)
		(width 0.1)
		(layer "In9.Cu")
		(net 410)
	)
	(segment
		(start 161.835035 139.585035)
		(end 161.835035 139.585034)
		(width 0.1)
		(layer "In9.Cu")
		(net 410)
	)
	(segment
		(start 159.84507 139.775)
		(end 159.625 139.775)
		(width 0.1)
		(layer "In9.Cu")
		(net 410)
	)
	(segment
		(start 155.64507 139.395069)
		(end 155.425 139.395069)
		(width 0.1)
		(layer "In9.Cu")
		(net 410)
	)
	(segment
		(start 166.44507 139.395069)
		(end 166.225 139.395069)
		(width 0.1)
		(layer "In9.Cu")
		(net 410)
	)
	(segment
		(start 158.645152 139.775)
		(end 158.425 139.775)
		(width 0.1)
		(layer "In9.Cu")
		(net 410)
	)
	(segment
		(start 165.435035 139.585035)
		(end 165.435035 139.585034)
		(width 0.1)
		(layer "In9.Cu")
		(net 410)
	)
	(segment
		(start 158.04507 139.395069)
		(end 157.825 139.395069)
		(width 0.1)
		(layer "In9.Cu")
		(net 410)
	)
	(segment
		(start 177 143)
		(end 176.3 143)
		(width 0.1)
		(layer "In9.Cu")
		(net 410)
	)
	(segment
		(start 162.435035 139.585034)
		(end 162.435035 139.585035)
		(width 0.1)
		(layer "In9.Cu")
		(net 410)
	)
	(segment
		(start 176 142.7)
		(end 176 142.15)
		(width 0.1)
		(layer "In9.Cu")
		(net 410)
	)
	(segment
		(start 165.84507 139.775)
		(end 165.625 139.775)
		(width 0.1)
		(layer "In9.Cu")
		(net 410)
	)
	(segment
		(start 164.835035 139.585034)
		(end 164.835035 139.585035)
		(width 0.1)
		(layer "In9.Cu")
		(net 410)
	)
	(segment
		(start 153.84507 139.775)
		(end 152.075 139.775)
		(width 0.1)
		(layer "In9.Cu")
		(net 410)
	)
	(segment
		(start 157.44507 139.775)
		(end 157.225 139.775)
		(width 0.1)
		(layer "In9.Cu")
		(net 410)
	)
	(segment
		(start 160.44507 139.395069)
		(end 160.225 139.395069)
		(width 0.1)
		(layer "In9.Cu")
		(net 410)
	)
	(segment
		(start 145.85 147.65)
		(end 141.799 147.65)
		(width 0.1)
		(layer "In9.Cu")
		(net 410)
	)
	(segment
		(start 150.5125 142.9875)
		(end 145.85 147.65)
		(width 0.1)
		(layer "In9.Cu")
		(net 410)
	)
	(segment
		(start 163.44507 139.775)
		(end 163.225 139.775)
		(width 0.1)
		(layer "In9.Cu")
		(net 410)
	)
	(segment
		(start 155.835035 139.585035)
		(end 155.835035 139.585034)
		(width 0.1)
		(layer "In9.Cu")
		(net 410)
	)
	(segment
		(start 167.4 139.775)
		(end 166.825 139.775)
		(width 0.1)
		(layer "In9.Cu")
		(net 410)
	)
	(segment
		(start 154.635035 139.585035)
		(end 154.635035 139.585034)
		(width 0.1)
		(layer "In9.Cu")
		(net 410)
	)
	(segment
		(start 154.44507 139.395069)
		(end 154.225 139.395069)
		(width 0.1)
		(layer "In9.Cu")
		(net 410)
	)
	(segment
		(start 161.04507 139.775)
		(end 160.825 139.775)
		(width 0.1)
		(layer "In9.Cu")
		(net 410)
	)
	(segment
		(start 176.3 143)
		(end 176 142.7)
		(width 0.1)
		(layer "In9.Cu")
		(net 410)
	)
	(segment
		(start 163.035035 139.585035)
		(end 163.035035 139.585034)
		(width 0.1)
		(layer "In9.Cu")
		(net 410)
	)
	(segment
		(start 157.035035 139.585035)
		(end 157.035035 139.585034)
		(width 0.1)
		(layer "In9.Cu")
		(net 410)
	)
	(arc
		(start 166.635035 139.585034)
		(mid 166.579396 139.450708)
		(end 166.44507 139.395069)
		(width 0.1)
		(layer "In9.Cu")
		(net 410)
	)
	(arc
		(start 159.025 139.395151)
		(mid 158.890703 139.450778)
		(end 158.835076 139.585075)
		(width 0.1)
		(layer "In9.Cu")
		(net 410)
	)
	(arc
		(start 160.825 139.775)
		(mid 160.690674 139.719361)
		(end 160.635035 139.585035)
		(width 0.1)
		(layer "In9.Cu")
		(net 410)
	)
	(arc
		(start 158.835076 139.585076)
		(mid 158.779449 139.719373)
		(end 158.645152 139.775)
		(width 0.1)
		(layer "In9.Cu")
		(net 410)
	)
	(arc
		(start 163.035035 139.585034)
		(mid 162.979396 139.450708)
		(end 162.84507 139.395069)
		(width 0.1)
		(layer "In9.Cu")
		(net 410)
	)
	(arc
		(start 161.425 139.395069)
		(mid 161.290674 139.450708)
		(end 161.235035 139.585034)
		(width 0.1)
		(layer "In9.Cu")
		(net 410)
	)
	(arc
		(start 163.225 139.775)
		(mid 163.090674 139.719361)
		(end 163.035035 139.585035)
		(width 0.1)
		(layer "In9.Cu")
		(net 410)
	)
	(arc
		(start 163.825 139.395069)
		(mid 163.690674 139.450708)
		(end 163.635035 139.585034)
		(width 0.1)
		(layer "In9.Cu")
		(net 410)
	)
	(arc
		(start 162.625 139.395069)
		(mid 162.490674 139.450708)
		(end 162.435035 139.585034)
		(width 0.1)
		(layer "In9.Cu")
		(net 410)
	)
	(arc
		(start 154.035035 139.585035)
		(mid 153.979396 139.719361)
		(end 153.84507 139.775)
		(width 0.1)
		(layer "In9.Cu")
		(net 410)
	)
	(arc
		(start 157.825 139.395069)
		(mid 157.690674 139.450708)
		(end 157.635035 139.585034)
		(width 0.1)
		(layer "In9.Cu")
		(net 410)
	)
	(arc
		(start 163.635035 139.585035)
		(mid 163.579396 139.719361)
		(end 163.44507 139.775)
		(width 0.1)
		(layer "In9.Cu")
		(net 410)
	)
	(arc
		(start 157.635035 139.585035)
		(mid 157.579396 139.719361)
		(end 157.44507 139.775)
		(width 0.1)
		(layer "In9.Cu")
		(net 410)
	)
	(arc
		(start 155.835035 139.585034)
		(mid 155.779396 139.450708)
		(end 155.64507 139.395069)
		(width 0.1)
		(layer "In9.Cu")
		(net 410)
	)
	(arc
		(start 160.225 139.395069)
		(mid 160.090674 139.450708)
		(end 160.035035 139.585034)
		(width 0.1)
		(layer "In9.Cu")
		(net 410)
	)
	(arc
		(start 157.035035 139.585034)
		(mid 156.979396 139.450708)
		(end 156.84507 139.395069)
		(width 0.1)
		(layer "In9.Cu")
		(net 410)
	)
	(arc
		(start 158.235035 139.585034)
		(mid 158.179396 139.450708)
		(end 158.04507 139.395069)
		(width 0.1)
		(layer "In9.Cu")
		(net 410)
	)
	(arc
		(start 166.035035 139.585035)
		(mid 165.979396 139.719361)
		(end 165.84507 139.775)
		(width 0.1)
		(layer "In9.Cu")
		(net 410)
	)
	(arc
		(start 154.225 139.395069)
		(mid 154.090674 139.450708)
		(end 154.035035 139.585034)
		(width 0.1)
		(layer "In9.Cu")
		(net 410)
	)
	(arc
		(start 164.235035 139.585034)
		(mid 164.179396 139.450708)
		(end 164.04507 139.395069)
		(width 0.1)
		(layer "In9.Cu")
		(net 410)
	)
	(arc
		(start 160.035035 139.585035)
		(mid 159.979396 139.719361)
		(end 159.84507 139.775)
		(width 0.1)
		(layer "In9.Cu")
		(net 410)
	)
	(arc
		(start 164.425 139.775)
		(mid 164.290674 139.719361)
		(end 164.235035 139.585035)
		(width 0.1)
		(layer "In9.Cu")
		(net 410)
	)
	(arc
		(start 160.635035 139.585034)
		(mid 160.579396 139.450708)
		(end 160.44507 139.395069)
		(width 0.1)
		(layer "In9.Cu")
		(net 410)
	)
	(arc
		(start 164.835035 139.585035)
		(mid 164.779396 139.719361)
		(end 164.64507 139.775)
		(width 0.1)
		(layer "In9.Cu")
		(net 410)
	)
	(arc
		(start 166.225 139.395069)
		(mid 166.090674 139.450708)
		(end 166.035035 139.585034)
		(width 0.1)
		(layer "In9.Cu")
		(net 410)
	)
	(arc
		(start 165.625 139.775)
		(mid 165.490674 139.719361)
		(end 165.435035 139.585035)
		(width 0.1)
		(layer "In9.Cu")
		(net 410)
	)
	(arc
		(start 162.025 139.775)
		(mid 161.890674 139.719361)
		(end 161.835035 139.585035)
		(width 0.1)
		(layer "In9.Cu")
		(net 410)
	)
	(arc
		(start 165.025 139.395069)
		(mid 164.890674 139.450708)
		(end 164.835035 139.585034)
		(width 0.1)
		(layer "In9.Cu")
		(net 410)
	)
	(arc
		(start 154.825 139.775)
		(mid 154.690674 139.719361)
		(end 154.635035 139.585035)
		(width 0.1)
		(layer "In9.Cu")
		(net 410)
	)
	(arc
		(start 156.625 139.395069)
		(mid 156.490674 139.450708)
		(end 156.435035 139.585034)
		(width 0.1)
		(layer "In9.Cu")
		(net 410)
	)
	(arc
		(start 156.025 139.775)
		(mid 155.890674 139.719361)
		(end 155.835035 139.585035)
		(width 0.1)
		(layer "In9.Cu")
		(net 410)
	)
	(arc
		(start 166.825 139.775)
		(mid 166.690674 139.719361)
		(end 166.635035 139.585035)
		(width 0.1)
		(layer "In9.Cu")
		(net 410)
	)
	(arc
		(start 155.425 139.395069)
		(mid 155.290674 139.450708)
		(end 155.235035 139.585034)
		(width 0.1)
		(layer "In9.Cu")
		(net 410)
	)
	(arc
		(start 157.225 139.775)
		(mid 157.090674 139.719361)
		(end 157.035035 139.585035)
		(width 0.1)
		(layer "In9.Cu")
		(net 410)
	)
	(arc
		(start 162.435035 139.585035)
		(mid 162.379396 139.719361)
		(end 162.24507 139.775)
		(width 0.1)
		(layer "In9.Cu")
		(net 410)
	)
	(arc
		(start 154.635035 139.585034)
		(mid 154.579396 139.450708)
		(end 154.44507 139.395069)
		(width 0.1)
		(layer "In9.Cu")
		(net 410)
	)
	(arc
		(start 156.435035 139.585035)
		(mid 156.379396 139.719361)
		(end 156.24507 139.775)
		(width 0.1)
		(layer "In9.Cu")
		(net 410)
	)
	(arc
		(start 159.625 139.775)
		(mid 159.490703 139.719373)
		(end 159.435076 139.585076)
		(width 0.1)
		(layer "In9.Cu")
		(net 410)
	)
	(arc
		(start 165.435035 139.585034)
		(mid 165.379396 139.450708)
		(end 165.24507 139.395069)
		(width 0.1)
		(layer "In9.Cu")
		(net 410)
	)
	(arc
		(start 159.435076 139.585075)
		(mid 159.379449 139.450778)
		(end 159.245152 139.395151)
		(width 0.1)
		(layer "In9.Cu")
		(net 410)
	)
	(arc
		(start 155.235035 139.585035)
		(mid 155.179396 139.719361)
		(end 155.04507 139.775)
		(width 0.1)
		(layer "In9.Cu")
		(net 410)
	)
	(arc
		(start 161.835035 139.585034)
		(mid 161.779396 139.450708)
		(end 161.64507 139.395069)
		(width 0.1)
		(layer "In9.Cu")
		(net 410)
	)
	(arc
		(start 161.235035 139.585035)
		(mid 161.179396 139.719361)
		(end 161.04507 139.775)
		(width 0.1)
		(layer "In9.Cu")
		(net 410)
	)
	(arc
		(start 158.425 139.775)
		(mid 158.290674 139.719361)
		(end 158.235035 139.585035)
		(width 0.1)
		(layer "In9.Cu")
		(net 410)
	)
	(segment
		(start 178.999499 144.9995)
		(end 178.5 144.500001)
		(width 0.256)
		(layer "F.Cu")
		(net 435)
	)
	(segment
		(start 131.926 146.734)
		(end 131.926 148.074)
		(width 0.256)
		(layer "F.Cu")
		(net 435)
	)
	(segment
		(start 131.926 148.074)
		(end 131.9 148.1)
		(width 0.256)
		(layer "F.Cu")
		(net 435)
	)
	(via
		(at 131.9 148.1)
		(size 0.45)
		(drill 0.1)
		(layers "F.Cu" "B.Cu")
		(remove_unused_layers yes)
		(keep_end_layers yes)
		(zone_layer_connections)
		(net 435)
	)
	(via
		(at 178.5 144.500001)
		(size 0.45)
		(drill 0.1)
		(layers "F.Cu" "B.Cu")
		(remove_unused_layers yes)
		(keep_end_layers yes)
		(zone_layer_connections)
		(net 435)
	)
	(segment
		(start 132.85 146.525)
		(end 132.85 146.775)
		(width 0.1)
		(layer "In9.Cu")
		(net 435)
	)
	(segment
		(start 157.875 140.675)
		(end 157.875 140.485337)
		(width 0.1)
		(layer "In9.Cu")
		(net 435)
	)
	(segment
		(start 135.1 146.775)
		(end 135.1 146.525)
		(width 0.1)
		(layer "In9.Cu")
		(net 435)
	)
	(segment
		(start 176 143.775)
		(end 176.275 144.05)
		(width 0.1)
		(layer "In9.Cu")
		(net 435)
	)
	(segment
		(start 156.075 140.485327)
		(end 156.075 140.675)
		(width 0.1)
		(layer "In9.Cu")
		(net 435)
	)
	(segment
		(start 156.075 140.675)
		(end 156.075 140.864663)
		(width 0.1)
		(layer "In9.Cu")
		(net 435)
	)
	(segment
		(start 131.9 148.1)
		(end 131.9 146.925)
		(width 0.1)
		(layer "In9.Cu")
		(net 435)
	)
	(segment
		(start 155.064672 141.054345)
		(end 155.285328 141.054345)
		(width 0.1)
		(layer "In9.Cu")
		(net 435)
	)
	(segment
		(start 158.664663 141.054326)
		(end 158.885337 141.054326)
		(width 0.1)
		(layer "In9.Cu")
		(net 435)
	)
	(segment
		(start 163.275 140.486975)
		(end 163.275 140.486976)
		(width 0.1)
		(layer "In9.Cu")
		(net 435)
	)
	(segment
		(start 137.15 148)
		(end 137.65 148.5)
		(width 0.1)
		(layer "In9.Cu")
		(net 435)
	)
	(segment
		(start 158.475 140.675)
		(end 158.475 140.864663)
		(width 0.1)
		(layer "In9.Cu")
		(net 435)
	)
	(segment
		(start 159.675 140.485327)
		(end 159.675 140.675)
		(width 0.1)
		(layer "In9.Cu")
		(net 435)
	)
	(segment
		(start 153.675 140.486971)
		(end 153.675 140.675)
		(width 0.1)
		(layer "In9.Cu")
		(net 435)
	)
	(segment
		(start 168.9 141.7)
		(end 169.65 142.45)
		(width 0.1)
		(layer "In9.Cu")
		(net 435)
	)
	(segment
		(start 132.525 146.3)
		(end 132.625 146.3)
		(width 0.1)
		(layer "In9.Cu")
		(net 435)
	)
	(segment
		(start 156.675 140.675)
		(end 156.675 140.485337)
		(width 0.1)
		(layer "In9.Cu")
		(net 435)
	)
	(segment
		(start 155.664672 140.295655)
		(end 155.885328 140.295655)
		(width 0.1)
		(layer "In9.Cu")
		(net 435)
	)
	(segment
		(start 162.675 140.864663)
		(end 162.675 140.675)
		(width 0.1)
		(layer "In9.Cu")
		(net 435)
	)
	(segment
		(start 136.225 146.3)
		(end 136.35 146.3)
		(width 0.1)
		(layer "In9.Cu")
		(net 435)
	)
	(segment
		(start 153.251058 140.298942)
		(end 153.486971 140.298942)
		(width 0.1)
		(layer "In9.Cu")
		(net 435)
	)
	(segment
		(start 159.675 140.675)
		(end 159.675 140.864663)
		(width 0.1)
		(layer "In9.Cu")
		(net 435)
	)
	(segment
		(start 154.875 140.675)
		(end 154.875 140.864673)
		(width 0.1)
		(layer "In9.Cu")
		(net 435)
	)
	(segment
		(start 178.160001 144.500001)
		(end 178.5 144.500001)
		(width 0.1)
		(layer "In9.Cu")
		(net 435)
	)
	(segment
		(start 157.875 140.864673)
		(end 157.875 140.675)
		(width 0.1)
		(layer "In9.Cu")
		(net 435)
	)
	(segment
		(start 157.464672 141.054345)
		(end 157.685328 141.054345)
		(width 0.1)
		(layer "In9.Cu")
		(net 435)
	)
	(segment
		(start 167.225 140.675)
		(end 168.25 141.7)
		(width 0.1)
		(layer "In9.Cu")
		(net 435)
	)
	(segment
		(start 133.75 146.525)
		(end 133.75 146.775)
		(width 0.1)
		(layer "In9.Cu")
		(net 435)
	)
	(segment
		(start 153.675 140.675)
		(end 153.675 140.864673)
		(width 0.1)
		(layer "In9.Cu")
		(net 435)
	)
	(segment
		(start 168.25 141.7)
		(end 168.9 141.7)
		(width 0.1)
		(layer "In9.Cu")
		(net 435)
	)
	(segment
		(start 160.275 140.675)
		(end 160.275 140.485337)
		(width 0.1)
		(layer "In9.Cu")
		(net 435)
	)
	(segment
		(start 131.9 146.925)
		(end 132.525 146.3)
		(width 0.1)
		(layer "In9.Cu")
		(net 435)
	)
	(segment
		(start 162.264663 141.054326)
		(end 162.485337 141.054326)
		(width 0.1)
		(layer "In9.Cu")
		(net 435)
	)
	(segment
		(start 162.675 140.675)
		(end 162.675 140.486975)
		(width 0.1)
		(layer "In9.Cu")
		(net 435)
	)
	(segment
		(start 151.425 141.85)
		(end 152.6 140.675)
		(width 0.1)
		(layer "In9.Cu")
		(net 435)
	)
	(segment
		(start 161.475 140.675)
		(end 161.475 140.485337)
		(width 0.1)
		(layer "In9.Cu")
		(net 435)
	)
	(segment
		(start 174.5 143)
		(end 175.75 143)
		(width 0.1)
		(layer "In9.Cu")
		(net 435)
	)
	(segment
		(start 159.864663 141.054326)
		(end 160.085337 141.054326)
		(width 0.1)
		(layer "In9.Cu")
		(net 435)
	)
	(segment
		(start 156.675 140.864663)
		(end 156.675 140.675)
		(width 0.1)
		(layer "In9.Cu")
		(net 435)
	)
	(segment
		(start 175.75 143)
		(end 176 143.25)
		(width 0.1)
		(layer "In9.Cu")
		(net 435)
	)
	(segment
		(start 154.275 140.864673)
		(end 154.275 140.675)
		(width 0.1)
		(layer "In9.Cu")
		(net 435)
	)
	(segment
		(start 155.475 140.864673)
		(end 155.475 140.675)
		(width 0.1)
		(layer "In9.Cu")
		(net 435)
	)
	(segment
		(start 161.664663 140.295674)
		(end 161.885337 140.295674)
		(width 0.1)
		(layer "In9.Cu")
		(net 435)
	)
	(segment
		(start 176.275 144.05)
		(end 177.71 144.05)
		(width 0.1)
		(layer "In9.Cu")
		(net 435)
	)
	(segment
		(start 162.075 140.485337)
		(end 162.075 140.675)
		(width 0.1)
		(layer "In9.Cu")
		(net 435)
	)
	(segment
		(start 159.075 140.864663)
		(end 159.075 140.675)
		(width 0.1)
		(layer "In9.Cu")
		(net 435)
	)
	(segment
		(start 154.464672 140.295655)
		(end 154.685328 140.295655)
		(width 0.1)
		(layer "In9.Cu")
		(net 435)
	)
	(segment
		(start 157.275 140.485337)
		(end 157.275 140.675)
		(width 0.1)
		(layer "In9.Cu")
		(net 435)
	)
	(segment
		(start 163.675 140.675)
		(end 167.225 140.675)
		(width 0.1)
		(layer "In9.Cu")
		(net 435)
	)
	(segment
		(start 176 143.25)
		(end 176 143.775)
		(width 0.1)
		(layer "In9.Cu")
		(net 435)
	)
	(segment
		(start 152.6 140.675)
		(end 152.875 140.675)
		(width 0.1)
		(layer "In9.Cu")
		(net 435)
	)
	(segment
		(start 158.475 140.485337)
		(end 158.475 140.675)
		(width 0.1)
		(layer "In9.Cu")
		(net 435)
	)
	(segment
		(start 156.864663 140.295674)
		(end 157.085337 140.295674)
		(width 0.1)
		(layer "In9.Cu")
		(net 435)
	)
	(segment
		(start 154.275 140.675)
		(end 154.275 140.485327)
		(width 0.1)
		(layer "In9.Cu")
		(net 435)
	)
	(segment
		(start 161.064672 141.054345)
		(end 161.285328 141.054345)
		(width 0.1)
		(layer "In9.Cu")
		(net 435)
	)
	(segment
		(start 133.3 146.775)
		(end 133.3 146.525)
		(width 0.1)
		(layer "In9.Cu")
		(net 435)
	)
	(segment
		(start 154.875 140.485327)
		(end 154.875 140.675)
		(width 0.1)
		(layer "In9.Cu")
		(net 435)
	)
	(segment
		(start 136 146.775)
		(end 136 146.525)
		(width 0.1)
		(layer "In9.Cu")
		(net 435)
	)
	(segment
		(start 135.55 146.525)
		(end 135.55 146.775)
		(width 0.1)
		(layer "In9.Cu")
		(net 435)
	)
	(segment
		(start 160.464663 140.295674)
		(end 160.685337 140.295674)
		(width 0.1)
		(layer "In9.Cu")
		(net 435)
	)
	(segment
		(start 173.95 142.45)
		(end 174.5 143)
		(width 0.1)
		(layer "In9.Cu")
		(net 435)
	)
	(segment
		(start 160.875 140.485337)
		(end 160.875 140.675)
		(width 0.1)
		(layer "In9.Cu")
		(net 435)
	)
	(segment
		(start 159.264672 140.295655)
		(end 159.485328 140.295655)
		(width 0.1)
		(layer "In9.Cu")
		(net 435)
	)
	(segment
		(start 163.463024 140.675)
		(end 163.675 140.675)
		(width 0.1)
		(layer "In9.Cu")
		(net 435)
	)
	(segment
		(start 142.05 148.25)
		(end 146.25 148.25)
		(width 0.1)
		(layer "In9.Cu")
		(net 435)
	)
	(segment
		(start 134.2 146.775)
		(end 134.2 146.525)
		(width 0.1)
		(layer "In9.Cu")
		(net 435)
	)
	(segment
		(start 161.475 140.864673)
		(end 161.475 140.675)
		(width 0.1)
		(layer "In9.Cu")
		(net 435)
	)
	(segment
		(start 177.71 144.05)
		(end 178.160001 144.500001)
		(width 0.1)
		(layer "In9.Cu")
		(net 435)
	)
	(segment
		(start 169.65 142.45)
		(end 173.95 142.45)
		(width 0.1)
		(layer "In9.Cu")
		(net 435)
	)
	(segment
		(start 146.25 148.25)
		(end 151.425 143.075)
		(width 0.1)
		(layer "In9.Cu")
		(net 435)
	)
	(segment
		(start 160.275 140.864663)
		(end 160.275 140.675)
		(width 0.1)
		(layer "In9.Cu")
		(net 435)
	)
	(segment
		(start 153.864672 141.054345)
		(end 154.085328 141.054345)
		(width 0.1)
		(layer "In9.Cu")
		(net 435)
	)
	(segment
		(start 155.475 140.675)
		(end 155.475 140.485327)
		(width 0.1)
		(layer "In9.Cu")
		(net 435)
	)
	(segment
		(start 157.275 140.675)
		(end 157.275 140.864673)
		(width 0.1)
		(layer "In9.Cu")
		(net 435)
	)
	(segment
		(start 162.863024 140.298951)
		(end 163.086976 140.298951)
		(width 0.1)
		(layer "In9.Cu")
		(net 435)
	)
	(segment
		(start 158.064663 140.295674)
		(end 158.285337 140.295674)
		(width 0.1)
		(layer "In9.Cu")
		(net 435)
	)
	(segment
		(start 151.425 143.075)
		(end 151.425 141.85)
		(width 0.1)
		(layer "In9.Cu")
		(net 435)
	)
	(segment
		(start 137.15 147.1)
		(end 137.15 148)
		(width 0.1)
		(layer "In9.Cu")
		(net 435)
	)
	(segment
		(start 141.8 148.5)
		(end 142.05 148.25)
		(width 0.1)
		(layer "In9.Cu")
		(net 435)
	)
	(segment
		(start 162.075 140.675)
		(end 162.075 140.864663)
		(width 0.1)
		(layer "In9.Cu")
		(net 435)
	)
	(segment
		(start 134.65 146.525)
		(end 134.65 146.775)
		(width 0.1)
		(layer "In9.Cu")
		(net 435)
	)
	(segment
		(start 136.35 146.3)
		(end 137.15 147.1)
		(width 0.1)
		(layer "In9.Cu")
		(net 435)
	)
	(segment
		(start 160.875 140.675)
		(end 160.875 140.864673)
		(width 0.1)
		(layer "In9.Cu")
		(net 435)
	)
	(segment
		(start 156.264663 141.054326)
		(end 156.485337 141.054326)
		(width 0.1)
		(layer "In9.Cu")
		(net 435)
	)
	(segment
		(start 159.075 140.675)
		(end 159.075 140.485327)
		(width 0.1)
		(layer "In9.Cu")
		(net 435)
	)
	(segment
		(start 137.65 148.5)
		(end 141.8 148.5)
		(width 0.1)
		(layer "In9.Cu")
		(net 435)
	)
	(arc
		(start 135.325 146.3)
		(mid 135.484099 146.365901)
		(end 135.55 146.525)
		(width 0.1)
		(layer "In9.Cu")
		(net 435)
	)
	(arc
		(start 133.075 147)
		(mid 133.234099 146.934099)
		(end 133.3 146.775)
		(width 0.1)
		(layer "In9.Cu")
		(net 435)
	)
	(arc
		(start 134.65 146.775)
		(mid 134.715901 146.934099)
		(end 134.875 147)
		(width 0.1)
		(layer "In9.Cu")
		(net 435)
	)
	(arc
		(start 158.885337 141.054326)
		(mid 159.019449 140.998775)
		(end 159.075 140.864663)
		(width 0.1)
		(layer "In9.Cu")
		(net 435)
	)
	(arc
		(start 155.885328 140.295655)
		(mid 156.019446 140.351209)
		(end 156.075 140.485327)
		(width 0.1)
		(layer "In9.Cu")
		(net 435)
	)
	(arc
		(start 133.975 147)
		(mid 134.134099 146.934099)
		(end 134.2 146.775)
		(width 0.1)
		(layer "In9.Cu")
		(net 435)
	)
	(arc
		(start 160.085337 141.054326)
		(mid 160.219449 140.998775)
		(end 160.275 140.864663)
		(width 0.1)
		(layer "In9.Cu")
		(net 435)
	)
	(arc
		(start 163.086976 140.298951)
		(mid 163.219929 140.354022)
		(end 163.275 140.486975)
		(width 0.1)
		(layer "In9.Cu")
		(net 435)
	)
	(arc
		(start 162.675 140.486975)
		(mid 162.730071 140.354022)
		(end 162.863024 140.298951)
		(width 0.1)
		(layer "In9.Cu")
		(net 435)
	)
	(arc
		(start 136 146.525)
		(mid 136.065901 146.365901)
		(end 136.225 146.3)
		(width 0.1)
		(layer "In9.Cu")
		(net 435)
	)
	(arc
		(start 134.875 147)
		(mid 135.034099 146.934099)
		(end 135.1 146.775)
		(width 0.1)
		(layer "In9.Cu")
		(net 435)
	)
	(arc
		(start 157.685328 141.054345)
		(mid 157.819446 140.998791)
		(end 157.875 140.864673)
		(width 0.1)
		(layer "In9.Cu")
		(net 435)
	)
	(arc
		(start 132.85 146.775)
		(mid 132.915901 146.934099)
		(end 133.075 147)
		(width 0.1)
		(layer "In9.Cu")
		(net 435)
	)
	(arc
		(start 154.875 140.864673)
		(mid 154.930554 140.998791)
		(end 155.064672 141.054345)
		(width 0.1)
		(layer "In9.Cu")
		(net 435)
	)
	(arc
		(start 132.625 146.3)
		(mid 132.784099 146.365901)
		(end 132.85 146.525)
		(width 0.1)
		(layer "In9.Cu")
		(net 435)
	)
	(arc
		(start 135.55 146.775)
		(mid 135.615901 146.934099)
		(end 135.775 147)
		(width 0.1)
		(layer "In9.Cu")
		(net 435)
	)
	(arc
		(start 134.425 146.3)
		(mid 134.584099 146.365901)
		(end 134.65 146.525)
		(width 0.1)
		(layer "In9.Cu")
		(net 435)
	)
	(arc
		(start 156.675 140.485337)
		(mid 156.730551 140.351225)
		(end 156.864663 140.295674)
		(width 0.1)
		(layer "In9.Cu")
		(net 435)
	)
	(arc
		(start 153.675 140.864673)
		(mid 153.730554 140.998791)
		(end 153.864672 141.054345)
		(width 0.1)
		(layer "In9.Cu")
		(net 435)
	)
	(arc
		(start 159.485328 140.295655)
		(mid 159.619446 140.351209)
		(end 159.675 140.485327)
		(width 0.1)
		(layer "In9.Cu")
		(net 435)
	)
	(arc
		(start 134.2 146.525)
		(mid 134.265901 146.365901)
		(end 134.425 146.3)
		(width 0.1)
		(layer "In9.Cu")
		(net 435)
	)
	(arc
		(start 156.075 140.864663)
		(mid 156.130551 140.998775)
		(end 156.264663 141.054326)
		(width 0.1)
		(layer "In9.Cu")
		(net 435)
	)
	(arc
		(start 133.3 146.525)
		(mid 133.365901 146.365901)
		(end 133.525 146.3)
		(width 0.1)
		(layer "In9.Cu")
		(net 435)
	)
	(arc
		(start 133.525 146.3)
		(mid 133.684099 146.365901)
		(end 133.75 146.525)
		(width 0.1)
		(layer "In9.Cu")
		(net 435)
	)
	(arc
		(start 159.075 140.485327)
		(mid 159.130554 140.351209)
		(end 159.264672 140.295655)
		(width 0.1)
		(layer "In9.Cu")
		(net 435)
	)
	(arc
		(start 157.085337 140.295674)
		(mid 157.219449 140.351225)
		(end 157.275 140.485337)
		(width 0.1)
		(layer "In9.Cu")
		(net 435)
	)
	(arc
		(start 161.285328 141.054345)
		(mid 161.419446 140.998791)
		(end 161.475 140.864673)
		(width 0.1)
		(layer "In9.Cu")
		(net 435)
	)
	(arc
		(start 154.275 140.485327)
		(mid 154.330554 140.351209)
		(end 154.464672 140.295655)
		(width 0.1)
		(layer "In9.Cu")
		(net 435)
	)
	(arc
		(start 163.275 140.486976)
		(mid 163.330071 140.619929)
		(end 163.463024 140.675)
		(width 0.1)
		(layer "In9.Cu")
		(net 435)
	)
	(arc
		(start 159.675 140.864663)
		(mid 159.730551 140.998775)
		(end 159.864663 141.054326)
		(width 0.1)
		(layer "In9.Cu")
		(net 435)
	)
	(arc
		(start 161.475 140.485337)
		(mid 161.530551 140.351225)
		(end 161.664663 140.295674)
		(width 0.1)
		(layer "In9.Cu")
		(net 435)
	)
	(arc
		(start 160.685337 140.295674)
		(mid 160.819449 140.351225)
		(end 160.875 140.485337)
		(width 0.1)
		(layer "In9.Cu")
		(net 435)
	)
	(arc
		(start 153.063029 140.486971)
		(mid 153.118101 140.354014)
		(end 153.251058 140.298942)
		(width 0.1)
		(layer "In9.Cu")
		(net 435)
	)
	(arc
		(start 162.075 140.864663)
		(mid 162.130551 140.998775)
		(end 162.264663 141.054326)
		(width 0.1)
		(layer "In9.Cu")
		(net 435)
	)
	(arc
		(start 158.285337 140.295674)
		(mid 158.419449 140.351225)
		(end 158.475 140.485337)
		(width 0.1)
		(layer "In9.Cu")
		(net 435)
	)
	(arc
		(start 153.486971 140.298942)
		(mid 153.619928 140.354014)
		(end 153.675 140.486971)
		(width 0.1)
		(layer "In9.Cu")
		(net 435)
	)
	(arc
		(start 155.285328 141.054345)
		(mid 155.419446 140.998791)
		(end 155.475 140.864673)
		(width 0.1)
		(layer "In9.Cu")
		(net 435)
	)
	(arc
		(start 135.775 147)
		(mid 135.934099 146.934099)
		(end 136 146.775)
		(width 0.1)
		(layer "In9.Cu")
		(net 435)
	)
	(arc
		(start 160.875 140.864673)
		(mid 160.930554 140.998791)
		(end 161.064672 141.054345)
		(width 0.1)
		(layer "In9.Cu")
		(net 435)
	)
	(arc
		(start 161.885337 140.295674)
		(mid 162.019449 140.351225)
		(end 162.075 140.485337)
		(width 0.1)
		(layer "In9.Cu")
		(net 435)
	)
	(arc
		(start 155.475 140.485327)
		(mid 155.530554 140.351209)
		(end 155.664672 140.295655)
		(width 0.1)
		(layer "In9.Cu")
		(net 435)
	)
	(arc
		(start 160.275 140.485337)
		(mid 160.330551 140.351225)
		(end 160.464663 140.295674)
		(width 0.1)
		(layer "In9.Cu")
		(net 435)
	)
	(arc
		(start 135.1 146.525)
		(mid 135.165901 146.365901)
		(end 135.325 146.3)
		(width 0.1)
		(layer "In9.Cu")
		(net 435)
	)
	(arc
		(start 162.485337 141.054326)
		(mid 162.619449 140.998775)
		(end 162.675 140.864663)
		(width 0.1)
		(layer "In9.Cu")
		(net 435)
	)
	(arc
		(start 152.875 140.675)
		(mid 153.007957 140.619928)
		(end 153.063029 140.486971)
		(width 0.1)
		(layer "In9.Cu")
		(net 435)
	)
	(arc
		(start 133.75 146.775)
		(mid 133.815901 146.934099)
		(end 133.975 147)
		(width 0.1)
		(layer "In9.Cu")
		(net 435)
	)
	(arc
		(start 154.685328 140.295655)
		(mid 154.819446 140.351209)
		(end 154.875 140.485327)
		(width 0.1)
		(layer "In9.Cu")
		(net 435)
	)
	(arc
		(start 157.875 140.485337)
		(mid 157.930551 140.351225)
		(end 158.064663 140.295674)
		(width 0.1)
		(layer "In9.Cu")
		(net 435)
	)
	(arc
		(start 158.475 140.864663)
		(mid 158.530551 140.998775)
		(end 158.664663 141.054326)
		(width 0.1)
		(layer "In9.Cu")
		(net 435)
	)
	(arc
		(start 154.085328 141.054345)
		(mid 154.219446 140.998791)
		(end 154.275 140.864673)
		(width 0.1)
		(layer "In9.Cu")
		(net 435)
	)
	(arc
		(start 157.275 140.864673)
		(mid 157.330554 140.998791)
		(end 157.464672 141.054345)
		(width 0.1)
		(layer "In9.Cu")
		(net 435)
	)
	(arc
		(start 156.485337 141.054326)
		(mid 156.619449 140.998775)
		(end 156.675 140.864663)
		(width 0.1)
		(layer "In9.Cu")
		(net 435)
	)
	(segment
		(start 130.279245 143.435074)
		(end 130.279245 143.406657)
		(width 0.15)
		(layer "F.Cu")
		(net 436)
	)
	(segment
		(start 130.355588 143.483)
		(end 131.176 143.483)
		(width 0.256)
		(layer "F.Cu")
		(net 436)
	)
	(segment
		(start 176.9995 150.999501)
		(end 176.5 150.5)
		(width 0.256)
		(layer "F.Cu")
		(net 436)
	)
	(segment
		(start 130.339179 143.495008)
		(end 130.279245 143.435074)
		(width 0.15)
		(layer "F.Cu")
		(net 436)
	)
	(segment
		(start 130.279245 143.406657)
		(end 130.355588 143.483)
		(width 0.256)
		(layer "F.Cu")
		(net 436)
	)
	(via
		(at 130.279245 143.406657)
		(size 0.45)
		(drill 0.1)
		(layers "F.Cu" "B.Cu")
		(remove_unused_layers yes)
		(keep_end_layers yes)
		(zone_layer_connections)
		(net 436)
	)
	(via
		(at 176.5 150.5)
		(size 0.45)
		(drill 0.1)
		(layers "F.Cu" "B.Cu")
		(remove_unused_layers yes)
		(keep_end_layers yes)
		(zone_layer_connections)
		(net 436)
	)
	(segment
		(start 130.35 150.7)
		(end 137.7 150.7)
		(width 0.1)
		(layer "In9.Cu")
		(net 436)
	)
	(segment
		(start 138 151)
		(end 138 153.2)
		(width 0.1)
		(layer "In9.Cu")
		(net 436)
	)
	(segment
		(start 137.7 150.7)
		(end 138 151)
		(width 0.1)
		(layer "In9.Cu")
		(net 436)
	)
	(segment
		(start 153 151.8)
		(end 157.4 151.8)
		(width 0.1)
		(layer "In9.Cu")
		(net 436)
	)
	(segment
		(start 171.82 148.5)
		(end 173.32 150)
		(width 0.1)
		(layer "In9.Cu")
		(net 436)
	)
	(segment
		(start 176 150)
		(end 176.5 150.5)
		(width 0.1)
		(layer "In9.Cu")
		(net 436)
	)
	(segment
		(start 127.9 148.25)
		(end 130.35 150.7)
		(width 0.1)
		(layer "In9.Cu")
		(net 436)
	)
	(segment
		(start 157.4 151.8)
		(end 160.7 148.5)
		(width 0.1)
		(layer "In9.Cu")
		(net 436)
	)
	(segment
		(start 149.8 155)
		(end 153 151.8)
		(width 0.1)
		(layer "In9.Cu")
		(net 436)
	)
	(segment
		(start 139.8 155)
		(end 149.8 155)
		(width 0.1)
		(layer "In9.Cu")
		(net 436)
	)
	(segment
		(start 127.9 143.97)
		(end 127.9 148.25)
		(width 0.1)
		(layer "In9.Cu")
		(net 436)
	)
	(segment
		(start 128.463343 143.406657)
		(end 127.9 143.97)
		(width 0.1)
		(layer "In9.Cu")
		(net 436)
	)
	(segment
		(start 173.32 150)
		(end 176 150)
		(width 0.1)
		(layer "In9.Cu")
		(net 436)
	)
	(segment
		(start 138 153.2)
		(end 139.8 155)
		(width 0.1)
		(layer "In9.Cu")
		(net 436)
	)
	(segment
		(start 130.279245 143.406657)
		(end 128.463343 143.406657)
		(width 0.1)
		(layer "In9.Cu")
		(net 436)
	)
	(segment
		(start 160.7 148.5)
		(end 171.82 148.5)
		(width 0.1)
		(layer "In9.Cu")
		(net 436)
	)
	(segment
		(start 175.9995 140.9995)
		(end 175.5 140.5)
		(width 0.256)
		(layer "F.Cu")
		(net 437)
	)
	(segment
		(start 140.456 145.484)
		(end 138.175 145.484)
		(width 0.256)
		(layer "F.Cu")
		(net 437)
	)
	(segment
		(start 140.47 145.47)
		(end 140.456 145.484)
		(width 0.256)
		(layer "F.Cu")
		(net 437)
	)
	(via
		(at 140.47 145.47)
		(size 0.45)
		(drill 0.1)
		(layers "F.Cu" "B.Cu")
		(remove_unused_layers yes)
		(keep_end_layers yes)
		(zone_layer_connections)
		(net 437)
	)
	(via
		(at 175.5 140.5)
		(size 0.45)
		(drill 0.1)
		(layers "F.Cu" "B.Cu")
		(remove_unused_layers yes)
		(keep_end_layers yes)
		(zone_layer_connections)
		(net 437)
	)
	(segment
		(start 144.978549 144.711213)
		(end 143.763476 143.49614)
		(width 0.1)
		(layer "In9.Cu")
		(net 437)
	)
	(segment
		(start 143.352176 145.382939)
		(end 143.352177 145.382938)
		(width 0.1)
		(layer "In9.Cu")
		(net 437)
	)
	(segment
		(start 144.311217 142.488783)
		(end 149.875 136.925)
		(width 0.1)
		(layer "In9.Cu")
		(net 437)
	)
	(segment
		(start 140.47 145.47)
		(end 141.33 145.47)
		(width 0.1)
		(layer "In9.Cu")
		(net 437)
	)
	(segment
		(start 144.97855 145.170833)
		(end 144.978549 145.170833)
		(width 0.1)
		(layer "In9.Cu")
		(net 437)
	)
	(segment
		(start 142.384619 144.875)
		(end 142.892557 145.382938)
		(width 0.1)
		(layer "In9.Cu")
		(net 437)
	)
	(segment
		(start 167.825 136.925)
		(end 171.4 140.5)
		(width 0.1)
		(layer "In9.Cu")
		(net 437)
	)
	(segment
		(start 143.763476 143.03652)
		(end 143.763476 143.036521)
		(width 0.1)
		(layer "In9.Cu")
		(net 437)
	)
	(segment
		(start 142.384618 144.875)
		(end 142.384619 144.875)
		(width 0.1)
		(layer "In9.Cu")
		(net 437)
	)
	(segment
		(start 142.844238 143.955759)
		(end 142.844239 143.955761)
		(width 0.1)
		(layer "In9.Cu")
		(net 437)
	)
	(segment
		(start 143.303858 143.955761)
		(end 144.51893 145.170833)
		(width 0.1)
		(layer "In9.Cu")
		(net 437)
	)
	(segment
		(start 143.763476 143.036521)
		(end 144.311217 142.488783)
		(width 0.1)
		(layer "In9.Cu")
		(net 437)
	)
	(segment
		(start 142.844237 143.95576)
		(end 142.844238 143.955759)
		(width 0.1)
		(layer "In9.Cu")
		(net 437)
	)
	(segment
		(start 143.303857 143.955761)
		(end 143.303858 143.955761)
		(width 0.1)
		(layer "In9.Cu")
		(net 437)
	)
	(segment
		(start 171.4 140.5)
		(end 175.5 140.5)
		(width 0.1)
		(layer "In9.Cu")
		(net 437)
	)
	(segment
		(start 141.33 145.47)
		(end 141.925 144.875)
		(width 0.1)
		(layer "In9.Cu")
		(net 437)
	)
	(segment
		(start 143.352177 144.923318)
		(end 142.844238 144.415379)
		(width 0.1)
		(layer "In9.Cu")
		(net 437)
	)
	(segment
		(start 149.875 136.925)
		(end 167.825 136.925)
		(width 0.1)
		(layer "In9.Cu")
		(net 437)
	)
	(arc
		(start 142.844239 143.955761)
		(mid 143.074048 143.860571)
		(end 143.303857 143.955761)
		(width 0.1)
		(layer "In9.Cu")
		(net 437)
	)
	(arc
		(start 144.51893 145.170833)
		(mid 144.74874 145.266023)
		(end 144.97855 145.170833)
		(width 0.1)
		(layer "In9.Cu")
		(net 437)
	)
	(arc
		(start 141.925 144.875)
		(mid 142.154809 144.77981)
		(end 142.384618 144.875)
		(width 0.1)
		(layer "In9.Cu")
		(net 437)
	)
	(arc
		(start 143.352177 145.382938)
		(mid 143.447367 145.153128)
		(end 143.352177 144.923318)
		(width 0.1)
		(layer "In9.Cu")
		(net 437)
	)
	(arc
		(start 142.844238 144.415379)
		(mid 142.749047 144.18557)
		(end 142.844237 143.95576)
		(width 0.1)
		(layer "In9.Cu")
		(net 437)
	)
	(arc
		(start 143.763476 143.49614)
		(mid 143.668286 143.26633)
		(end 143.763476 143.03652)
		(width 0.1)
		(layer "In9.Cu")
		(net 437)
	)
	(arc
		(start 144.978549 145.170833)
		(mid 145.073739 144.941023)
		(end 144.978549 144.711213)
		(width 0.1)
		(layer "In9.Cu")
		(net 437)
	)
	(arc
		(start 142.892557 145.382938)
		(mid 143.122366 145.478129)
		(end 143.352176 145.382939)
		(width 0.1)
		(layer "In9.Cu")
		(net 437)
	)
	(segment
		(start 175.9995 148.9995)
		(end 175.5 148.5)
		(width 0.256)
		(layer "F.Cu")
		(net 438)
	)
	(segment
		(start 129.644 144.984)
		(end 129.22 144.56)
		(width 0.256)
		(layer "F.Cu")
		(net 438)
	)
	(segment
		(start 129.22 144.56)
		(end 128.56 144.56)
		(width 0.256)
		(layer "F.Cu")
		(net 438)
	)
	(segment
		(start 131.176 144.984)
		(end 129.644 144.984)
		(width 0.256)
		(layer "F.Cu")
		(net 438)
	)
	(via
		(at 128.56 144.56)
		(size 0.45)
		(drill 0.1)
		(layers "F.Cu" "B.Cu")
		(remove_unused_layers yes)
		(keep_end_layers yes)
		(zone_layer_connections)
		(net 438)
	)
	(via
		(at 175.5 148.5)
		(size 0.45)
		(drill 0.1)
		(layers "F.Cu" "B.Cu")
		(remove_unused_layers yes)
		(keep_end_layers yes)
		(zone_layer_connections)
		(net 438)
	)
	(segment
		(start 139.1 150.575)
		(end 138.675 150.15)
		(width 0.1)
		(layer "In9.Cu")
		(net 438)
	)
	(segment
		(start 148.6 154)
		(end 140.25 154)
		(width 0.1)
		(layer "In9.Cu")
		(net 438)
	)
	(segment
		(start 130.82 150.15)
		(end 128.56 147.89)
		(width 0.1)
		(layer "In9.Cu")
		(net 438)
	)
	(segment
		(start 157.564683 148.796003)
		(end 157.564682 148.796003)
		(width 0.1)
		(layer "In9.Cu")
		(net 438)
	)
	(segment
		(start 157.71467 147.88533)
		(end 157.511143 147.681803)
		(width 0.1)
		(layer "In9.Cu")
		(net 438)
	)
	(segment
		(start 156.12368 149.476323)
		(end 156.123679 149.476322)
		(width 0.1)
		(layer "In9.Cu")
		(net 438)
	)
	(segment
		(start 155.7 149.9)
		(end 152.7 149.9)
		(width 0.1)
		(layer "In9.Cu")
		(net 438)
	)
	(segment
		(start 158.245 147.708554)
		(end 158.27177 147.735324)
		(width 0.1)
		(layer "In9.Cu")
		(net 438)
	)
	(segment
		(start 156.450484 148.742461)
		(end 156.450484 148.742462)
		(width 0.1)
		(layer "In9.Cu")
		(net 438)
	)
	(segment
		(start 158.45 147.15)
		(end 158.245 147.355)
		(width 0.1)
		(layer "In9.Cu")
		(net 438)
	)
	(segment
		(start 156.504003 149.503091)
		(end 156.504003 149.503092)
		(width 0.1)
		(layer "In9.Cu")
		(net 438)
	)
	(segment
		(start 156.123679 149.476322)
		(end 155.7 149.9)
		(width 0.1)
		(layer "In9.Cu")
		(net 438)
	)
	(segment
		(start 157.21113 148.796002)
		(end 156.804037 148.388909)
		(width 0.1)
		(layer "In9.Cu")
		(net 438)
	)
	(segment
		(start 140.25 154)
		(end 139.1 152.85)
		(width 0.1)
		(layer "In9.Cu")
		(net 438)
	)
	(segment
		(start 156.857557 149.50309)
		(end 156.857557 149.503091)
		(width 0.1)
		(layer "In9.Cu")
		(net 438)
	)
	(segment
		(start 156.450483 148.388909)
		(end 156.450484 148.388909)
		(width 0.1)
		(layer "In9.Cu")
		(net 438)
	)
	(segment
		(start 173.96 148.5)
		(end 172.61 147.15)
		(width 0.1)
		(layer "In9.Cu")
		(net 438)
	)
	(segment
		(start 156.857558 149.50309)
		(end 156.857557 149.50309)
		(width 0.1)
		(layer "In9.Cu")
		(net 438)
	)
	(segment
		(start 156.450484 148.742462)
		(end 156.857558 149.149536)
		(width 0.1)
		(layer "In9.Cu")
		(net 438)
	)
	(segment
		(start 157.15759 148.035355)
		(end 157.15759 148.035356)
		(width 0.1)
		(layer "In9.Cu")
		(net 438)
	)
	(segment
		(start 157.21113 148.796003)
		(end 157.21113 148.796002)
		(width 0.1)
		(layer "In9.Cu")
		(net 438)
	)
	(segment
		(start 128.56 147.89)
		(end 128.56 144.56)
		(width 0.1)
		(layer "In9.Cu")
		(net 438)
	)
	(segment
		(start 172.61 147.15)
		(end 158.45 147.15)
		(width 0.1)
		(layer "In9.Cu")
		(net 438)
	)
	(segment
		(start 157.918216 148.088879)
		(end 157.71467 147.885333)
		(width 0.1)
		(layer "In9.Cu")
		(net 438)
	)
	(segment
		(start 138.675 150.15)
		(end 130.82 150.15)
		(width 0.1)
		(layer "In9.Cu")
		(net 438)
	)
	(segment
		(start 157.15759 148.035356)
		(end 157.564683 148.442449)
		(width 0.1)
		(layer "In9.Cu")
		(net 438)
	)
	(segment
		(start 152.7 149.9)
		(end 148.6 154)
		(width 0.1)
		(layer "In9.Cu")
		(net 438)
	)
	(segment
		(start 157.918218 148.088878)
		(end 157.918216 148.088879)
		(width 0.1)
		(layer "In9.Cu")
		(net 438)
	)
	(segment
		(start 157.157589 147.681803)
		(end 157.15759 147.681803)
		(width 0.1)
		(layer "In9.Cu")
		(net 438)
	)
	(segment
		(start 139.1 152.85)
		(end 139.1 150.575)
		(width 0.1)
		(layer "In9.Cu")
		(net 438)
	)
	(segment
		(start 156.504003 149.503092)
		(end 156.477234 149.476323)
		(width 0.1)
		(layer "In9.Cu")
		(net 438)
	)
	(segment
		(start 175.5 148.5)
		(end 173.96 148.5)
		(width 0.1)
		(layer "In9.Cu")
		(net 438)
	)
	(segment
		(start 157.71467 147.885333)
		(end 157.71467 147.88533)
		(width 0.1)
		(layer "In9.Cu")
		(net 438)
	)
	(arc
		(start 156.857557 149.503091)
		(mid 156.68078 149.576314)
		(end 156.504003 149.503091)
		(width 0.1)
		(layer "In9.Cu")
		(net 438)
	)
	(arc
		(start 156.450484 148.388909)
		(mid 156.377261 148.565685)
		(end 156.450484 148.742461)
		(width 0.1)
		(layer "In9.Cu")
		(net 438)
	)
	(arc
		(start 157.15759 147.681803)
		(mid 157.084367 147.858579)
		(end 157.15759 148.035355)
		(width 0.1)
		(layer "In9.Cu")
		(net 438)
	)
	(arc
		(start 157.564682 148.796003)
		(mid 157.387907 148.869225)
		(end 157.21113 148.796003)
		(width 0.1)
		(layer "In9.Cu")
		(net 438)
	)
	(arc
		(start 156.804037 148.388909)
		(mid 156.62726 148.315686)
		(end 156.450483 148.388909)
		(width 0.1)
		(layer "In9.Cu")
		(net 438)
	)
	(arc
		(start 158.27177 147.735324)
		(mid 158.344993 147.912101)
		(end 158.27177 148.088878)
		(width 0.1)
		(layer "In9.Cu")
		(net 438)
	)
	(arc
		(start 158.27177 148.088878)
		(mid 158.094993 148.162102)
		(end 157.918218 148.088878)
		(width 0.1)
		(layer "In9.Cu")
		(net 438)
	)
	(arc
		(start 158.245 147.355)
		(mid 158.171777 147.531777)
		(end 158.245 147.708554)
		(width 0.1)
		(layer "In9.Cu")
		(net 438)
	)
	(arc
		(start 156.857558 149.149536)
		(mid 156.930781 149.326313)
		(end 156.857558 149.50309)
		(width 0.1)
		(layer "In9.Cu")
		(net 438)
	)
	(arc
		(start 156.477234 149.476323)
		(mid 156.300457 149.4031)
		(end 156.12368 149.476323)
		(width 0.1)
		(layer "In9.Cu")
		(net 438)
	)
	(arc
		(start 157.564683 148.442449)
		(mid 157.637906 148.619226)
		(end 157.564683 148.796003)
		(width 0.1)
		(layer "In9.Cu")
		(net 438)
	)
	(arc
		(start 157.511143 147.681803)
		(mid 157.334366 147.60858)
		(end 157.157589 147.681803)
		(width 0.1)
		(layer "In9.Cu")
		(net 438)
	)
	(segment
		(start 175.9995 145.9995)
		(end 175.5 145.5)
		(width 0.256)
		(layer "F.Cu")
		(net 439)
	)
	(segment
		(start 130.250186 144.484)
		(end 131.176 144.484)
		(width 0.256)
		(layer "F.Cu")
		(net 439)
	)
	(via
		(at 130.250186 144.484)
		(size 0.45)
		(drill 0.1)
		(layers "F.Cu" "B.Cu")
		(remove_unused_layers yes)
		(keep_end_layers yes)
		(zone_layer_connections)
		(net 439)
	)
	(via
		(at 175.5 145.5)
		(size 0.45)
		(drill 0.1)
		(layers "F.Cu" "B.Cu")
		(remove_unused_layers yes)
		(keep_end_layers yes)
		(zone_layer_connections)
		(net 439)
	)
	(segment
		(start 141.5 152)
		(end 141.15 151.65)
		(width 0.1)
		(layer "In9.Cu")
		(net 439)
	)
	(segment
		(start 144.625 152)
		(end 144.525 152)
		(width 0.1)
		(layer "In9.Cu")
		(net 439)
	)
	(segment
		(start 154.407968 144.370408)
		(end 154.407967 144.370408)
		(width 0.1)
		(layer "In9.Cu")
		(net 439)
	)
	(segment
		(start 141.275 149.4)
		(end 141.275 149.2)
		(width 0.1)
		(layer "In9.Cu")
		(net 439)
	)
	(segment
		(start 142.5625 149.4125)
		(end 142.15 149)
		(width 0.1)
		(layer "In9.Cu")
		(net 439)
	)
	(segment
		(start 154.407125 144.864545)
		(end 154.160478 144.617898)
		(width 0.1)
		(layer "In9.Cu")
		(net 439)
	)
	(segment
		(start 154.654613 144.863721)
		(end 154.653789 144.864546)
		(width 0.1)
		(layer "In9.Cu")
		(net 439)
	)
	(segment
		(start 145.8 152)
		(end 145.525 152)
		(width 0.1)
		(layer "In9.Cu")
		(net 439)
	)
	(segment
		(start 153.912139 145.359514)
		(end 153.788814 145.236189)
		(width 0.1)
		(layer "In9.Cu")
		(net 439)
	)
	(segment
		(start 129.87 147.02)
		(end 129.87 144.864186)
		(width 0.1)
		(layer "In9.Cu")
		(net 439)
	)
	(segment
		(start 168.4 143.95)
		(end 168.25 143.8)
		(width 0.1)
		(layer "In9.Cu")
		(net 439)
	)
	(segment
		(start 142.15 149)
		(end 141.875 149)
		(width 0.1)
		(layer "In9.Cu")
		(net 439)
	)
	(segment
		(start 155.225 143.8)
		(end 155.15 143.875)
		(width 0.1)
		(layer "In9.Cu")
		(net 439)
	)
	(segment
		(start 140.475 149.4)
		(end 140.475 149.2)
		(width 0.1)
		(layer "In9.Cu")
		(net 439)
	)
	(segment
		(start 139.475 149)
		(end 131.85 149)
		(width 0.1)
		(layer "In9.Cu")
		(net 439)
	)
	(segment
		(start 175.5 145.5)
		(end 174.6 145.5)
		(width 0.1)
		(layer "In9.Cu")
		(net 439)
	)
	(segment
		(start 141.4 150.025)
		(end 142.25 150.025)
		(width 0.1)
		(layer "In9.Cu")
		(net 439)
	)
	(segment
		(start 139.675 149.4)
		(end 139.675 149.2)
		(width 0.1)
		(layer "In9.Cu")
		(net 439)
	)
	(segment
		(start 143.125 151.6)
		(end 143.025 151.6)
		(width 0.1)
		(layer "In9.Cu")
		(net 439)
	)
	(segment
		(start 155.15 144.367998)
		(end 155.148515 144.369484)
		(width 0.1)
		(layer "In9.Cu")
		(net 439)
	)
	(segment
		(start 155.15 144.367999)
		(end 155.15 144.367998)
		(width 0.1)
		(layer "In9.Cu")
		(net 439)
	)
	(segment
		(start 153.175 145.85)
		(end 151.95 145.85)
		(width 0.1)
		(layer "In9.Cu")
		(net 439)
	)
	(segment
		(start 153.913854 144.617898)
		(end 153.913855 144.617898)
		(width 0.1)
		(layer "In9.Cu")
		(net 439)
	)
	(segment
		(start 155.15 144.1215)
		(end 155.149999 144.1215)
		(width 0.1)
		(layer "In9.Cu")
		(net 439)
	)
	(segment
		(start 141.15 150.275)
		(end 141.4 150.025)
		(width 0.1)
		(layer "In9.Cu")
		(net 439)
	)
	(segment
		(start 153.912991 144.865385)
		(end 153.91299 144.865385)
		(width 0.1)
		(layer "In9.Cu")
		(net 439)
	)
	(segment
		(start 153.91299 144.865385)
		(end 154.159628 145.112024)
		(width 0.1)
		(layer "In9.Cu")
		(net 439)
	)
	(segment
		(start 140.875 149.2)
		(end 140.875 149.4)
		(width 0.1)
		(layer "In9.Cu")
		(net 439)
	)
	(segment
		(start 142.625 152)
		(end 142.525 152)
		(width 0.1)
		(layer "In9.Cu")
		(net 439)
	)
	(segment
		(start 154.407124 144.864545)
		(end 154.407125 144.864545)
		(width 0.1)
		(layer "In9.Cu")
		(net 439)
	)
	(segment
		(start 129.87 144.864186)
		(end 130.250186 144.484)
		(width 0.1)
		(layer "In9.Cu")
		(net 439)
	)
	(segment
		(start 154.902017 144.369483)
		(end 154.655455 144.122921)
		(width 0.1)
		(layer "In9.Cu")
		(net 439)
	)
	(segment
		(start 143.625 152)
		(end 143.525 152)
		(width 0.1)
		(layer "In9.Cu")
		(net 439)
	)
	(segment
		(start 168.25 143.8)
		(end 155.225 143.8)
		(width 0.1)
		(layer "In9.Cu")
		(net 439)
	)
	(segment
		(start 173.05 143.95)
		(end 168.4 143.95)
		(width 0.1)
		(layer "In9.Cu")
		(net 439)
	)
	(segment
		(start 153.418044 145.606953)
		(end 153.418045 145.606952)
		(width 0.1)
		(layer "In9.Cu")
		(net 439)
	)
	(segment
		(start 145.125 151.6)
		(end 145.025 151.6)
		(width 0.1)
		(layer "In9.Cu")
		(net 439)
	)
	(segment
		(start 141.625 152)
		(end 141.5 152)
		(width 0.1)
		(layer "In9.Cu")
		(net 439)
	)
	(segment
		(start 154.408832 144.122921)
		(end 154.407967 144.123785)
		(width 0.1)
		(layer "In9.Cu")
		(net 439)
	)
	(segment
		(start 174.6 145.5)
		(end 173.05 143.95)
		(width 0.1)
		(layer "In9.Cu")
		(net 439)
	)
	(segment
		(start 153.913855 144.617898)
		(end 153.91299 144.618762)
		(width 0.1)
		(layer "In9.Cu")
		(net 439)
	)
	(segment
		(start 144.125 151.6)
		(end 144.025 151.6)
		(width 0.1)
		(layer "In9.Cu")
		(net 439)
	)
	(segment
		(start 151.95 145.85)
		(end 145.8 152)
		(width 0.1)
		(layer "In9.Cu")
		(net 439)
	)
	(segment
		(start 142.125 151.6)
		(end 142.025 151.6)
		(width 0.1)
		(layer "In9.Cu")
		(net 439)
	)
	(segment
		(start 142.25 150.025)
		(end 142.5625 149.7125)
		(width 0.1)
		(layer "In9.Cu")
		(net 439)
	)
	(segment
		(start 154.407967 144.370408)
		(end 154.654613 144.617055)
		(width 0.1)
		(layer "In9.Cu")
		(net 439)
	)
	(segment
		(start 153.788814 145.236189)
		(end 153.665533 145.112907)
		(width 0.1)
		(layer "In9.Cu")
		(net 439)
	)
	(segment
		(start 154.159628 145.358674)
		(end 154.158789 145.359514)
		(width 0.1)
		(layer "In9.Cu")
		(net 439)
	)
	(segment
		(start 142.5625 149.7125)
		(end 142.5625 149.4125)
		(width 0.1)
		(layer "In9.Cu")
		(net 439)
	)
	(segment
		(start 140.075 149.2)
		(end 140.075 149.4)
		(width 0.1)
		(layer "In9.Cu")
		(net 439)
	)
	(segment
		(start 153.418974 145.112908)
		(end 153.418045 145.113836)
		(width 0.1)
		(layer "In9.Cu")
		(net 439)
	)
	(segment
		(start 154.408831 144.122921)
		(end 154.408832 144.122921)
		(width 0.1)
		(layer "In9.Cu")
		(net 439)
	)
	(segment
		(start 154.902016 144.369483)
		(end 154.902017 144.369483)
		(width 0.1)
		(layer "In9.Cu")
		(net 439)
	)
	(segment
		(start 153.418045 145.606952)
		(end 153.175 145.85)
		(width 0.1)
		(layer "In9.Cu")
		(net 439)
	)
	(segment
		(start 131.85 149)
		(end 129.87 147.02)
		(width 0.1)
		(layer "In9.Cu")
		(net 439)
	)
	(segment
		(start 141.15 151.65)
		(end 141.15 150.275)
		(width 0.1)
		(layer "In9.Cu")
		(net 439)
	)
	(segment
		(start 141.675 149.2)
		(end 141.675 149.4)
		(width 0.1)
		(layer "In9.Cu")
		(net 439)
	)
	(arc
		(start 144.825 151.8)
		(mid 144.766421 151.941421)
		(end 144.625 152)
		(width 0.1)
		(layer "In9.Cu")
		(net 439)
	)
	(arc
		(start 140.075 149.4)
		(mid 140.016421 149.541421)
		(end 139.875 149.6)
		(width 0.1)
		(layer "In9.Cu")
		(net 439)
	)
	(arc
		(start 154.160478 144.617898)
		(mid 154.037166 144.56682)
		(end 153.913854 144.617898)
		(width 0.1)
		(layer "In9.Cu")
		(net 439)
	)
	(arc
		(start 140.275 149)
		(mid 140.133579 149.058579)
		(end 140.075 149.2)
		(width 0.1)
		(layer "In9.Cu")
		(net 439)
	)
	(arc
		(start 140.675 149.6)
		(mid 140.533579 149.541421)
		(end 140.475 149.4)
		(width 0.1)
		(layer "In9.Cu")
		(net 439)
	)
	(arc
		(start 153.91299 144.618762)
		(mid 153.861913 144.742074)
		(end 153.912991 144.865385)
		(width 0.1)
		(layer "In9.Cu")
		(net 439)
	)
	(arc
		(start 144.525 152)
		(mid 144.383579 151.941421)
		(end 144.325 151.8)
		(width 0.1)
		(layer "In9.Cu")
		(net 439)
	)
	(arc
		(start 141.275 149.2)
		(mid 141.216421 149.058579)
		(end 141.075 149)
		(width 0.1)
		(layer "In9.Cu")
		(net 439)
	)
	(arc
		(start 145.025 151.6)
		(mid 144.883579 151.658579)
		(end 144.825 151.8)
		(width 0.1)
		(layer "In9.Cu")
		(net 439)
	)
	(arc
		(start 145.325 151.8)
		(mid 145.266421 151.658579)
		(end 145.125 151.6)
		(width 0.1)
		(layer "In9.Cu")
		(net 439)
	)
	(arc
		(start 143.325 151.8)
		(mid 143.266421 151.658579)
		(end 143.125 151.6)
		(width 0.1)
		(layer "In9.Cu")
		(net 439)
	)
	(arc
		(start 139.875 149.6)
		(mid 139.733579 149.541421)
		(end 139.675 149.4)
		(width 0.1)
		(layer "In9.Cu")
		(net 439)
	)
	(arc
		(start 154.158789 145.359514)
		(mid 154.035464 145.410597)
		(end 153.912139 145.359514)
		(width 0.1)
		(layer "In9.Cu")
		(net 439)
	)
	(arc
		(start 153.418045 145.113836)
		(mid 153.366981 145.237115)
		(end 153.418045 145.360394)
		(width 0.1)
		(layer "In9.Cu")
		(net 439)
	)
	(arc
		(start 155.15 143.875)
		(mid 155.098948 143.99825)
		(end 155.15 144.1215)
		(width 0.1)
		(layer "In9.Cu")
		(net 439)
	)
	(arc
		(start 141.675 149.4)
		(mid 141.616421 149.541421)
		(end 141.475 149.6)
		(width 0.1)
		(layer "In9.Cu")
		(net 439)
	)
	(arc
		(start 142.525 152)
		(mid 142.383579 151.941421)
		(end 142.325 151.8)
		(width 0.1)
		(layer "In9.Cu")
		(net 439)
	)
	(arc
		(start 141.875 149)
		(mid 141.733579 149.058579)
		(end 141.675 149.2)
		(width 0.1)
		(layer "In9.Cu")
		(net 439)
	)
	(arc
		(start 153.418045 145.360394)
		(mid 153.469109 145.483674)
		(end 153.418044 145.606953)
		(width 0.1)
		(layer "In9.Cu")
		(net 439)
	)
	(arc
		(start 154.159628 145.112024)
		(mid 154.210711 145.235349)
		(end 154.159628 145.358674)
		(width 0.1)
		(layer "In9.Cu")
		(net 439)
	)
	(arc
		(start 154.655455 144.122921)
		(mid 154.532143 144.071843)
		(end 154.408831 144.122921)
		(width 0.1)
		(layer "In9.Cu")
		(net 439)
	)
	(arc
		(start 145.525 152)
		(mid 145.383579 151.941421)
		(end 145.325 151.8)
		(width 0.1)
		(layer "In9.Cu")
		(net 439)
	)
	(arc
		(start 143.525 152)
		(mid 143.383579 151.941421)
		(end 143.325 151.8)
		(width 0.1)
		(layer "In9.Cu")
		(net 439)
	)
	(arc
		(start 141.475 149.6)
		(mid 141.333579 149.541421)
		(end 141.275 149.4)
		(width 0.1)
		(layer "In9.Cu")
		(net 439)
	)
	(arc
		(start 140.875 149.4)
		(mid 140.816421 149.541421)
		(end 140.675 149.6)
		(width 0.1)
		(layer "In9.Cu")
		(net 439)
	)
	(arc
		(start 154.407967 144.123785)
		(mid 154.35689 144.247097)
		(end 154.407968 144.370408)
		(width 0.1)
		(layer "In9.Cu")
		(net 439)
	)
	(arc
		(start 141.825 151.8)
		(mid 141.766421 151.941421)
		(end 141.625 152)
		(width 0.1)
		(layer "In9.Cu")
		(net 439)
	)
	(arc
		(start 142.025 151.6)
		(mid 141.883579 151.658579)
		(end 141.825 151.8)
		(width 0.1)
		(layer "In9.Cu")
		(net 439)
	)
	(arc
		(start 143.025 151.6)
		(mid 142.883579 151.658579)
		(end 142.825 151.8)
		(width 0.1)
		(layer "In9.Cu")
		(net 439)
	)
	(arc
		(start 154.653789 144.864546)
		(mid 154.530456 144.915631)
		(end 154.407124 144.864545)
		(width 0.1)
		(layer "In9.Cu")
		(net 439)
	)
	(arc
		(start 144.025 151.6)
		(mid 143.883579 151.658579)
		(end 143.825 151.8)
		(width 0.1)
		(layer "In9.Cu")
		(net 439)
	)
	(arc
		(start 154.654613 144.617055)
		(mid 154.705698 144.740389)
		(end 154.654613 144.863721)
		(width 0.1)
		(layer "In9.Cu")
		(net 439)
	)
	(arc
		(start 155.148515 144.369484)
		(mid 155.025266 144.420534)
		(end 154.902016 144.369483)
		(width 0.1)
		(layer "In9.Cu")
		(net 439)
	)
	(arc
		(start 144.325 151.8)
		(mid 144.266421 151.658579)
		(end 144.125 151.6)
		(width 0.1)
		(layer "In9.Cu")
		(net 439)
	)
	(arc
		(start 139.675 149.2)
		(mid 139.616421 149.058579)
		(end 139.475 149)
		(width 0.1)
		(layer "In9.Cu")
		(net 439)
	)
	(arc
		(start 141.075 149)
		(mid 140.933579 149.058579)
		(end 140.875 149.2)
		(width 0.1)
		(layer "In9.Cu")
		(net 439)
	)
	(arc
		(start 142.325 151.8)
		(mid 142.266421 151.658579)
		(end 142.125 151.6)
		(width 0.1)
		(layer "In9.Cu")
		(net 439)
	)
	(arc
		(start 143.825 151.8)
		(mid 143.766421 151.941421)
		(end 143.625 152)
		(width 0.1)
		(layer "In9.Cu")
		(net 439)
	)
	(arc
		(start 140.475 149.2)
		(mid 140.416421 149.058579)
		(end 140.275 149)
		(width 0.1)
		(layer "In9.Cu")
		(net 439)
	)
	(arc
		(start 153.665533 145.112907)
		(mid 153.542253 145.061843)
		(end 153.418974 145.112908)
		(width 0.1)
		(layer "In9.Cu")
		(net 439)
	)
	(arc
		(start 155.149999 144.1215)
		(mid 155.201052 144.244748)
		(end 155.15 144.367999)
		(width 0.1)
		(layer "In9.Cu")
		(net 439)
	)
	(arc
		(start 142.825 151.8)
		(mid 142.766421 151.941421)
		(end 142.625 152)
		(width 0.1)
		(layer "In9.Cu")
		(net 439)
	)
	(segment
		(start 129.739179 143.995008)
		(end 129.716328 144.017859)
		(width 0.15)
		(layer "F.Cu")
		(net 440)
	)
	(segment
		(start 131.176 143.983)
		(end 129.751187 143.983)
		(width 0.256)
		(layer "F.Cu")
		(net 440)
	)
	(segment
		(start 129.751187 143.983)
		(end 129.716328 144.017859)
		(width 0.256)
		(layer "F.Cu")
		(net 440)
	)
	(segment
		(start 175.9995 147.9995)
		(end 175.5 147.5)
		(width 0.256)
		(layer "F.Cu")
		(net 440)
	)
	(via
		(at 129.716328 144.017859)
		(size 0.45)
		(drill 0.1)
		(layers "F.Cu" "B.Cu")
		(remove_unused_layers yes)
		(keep_end_layers yes)
		(zone_layer_connections)
		(net 440)
	)
	(via
		(at 175.5 147.5)
		(size 0.45)
		(drill 0.1)
		(layers "F.Cu" "B.Cu")
		(remove_unused_layers yes)
		(keep_end_layers yes)
		(zone_layer_connections)
		(net 440)
	)
	(segment
		(start 164.93 145.72)
		(end 172.96 145.72)
		(width 0.1)
		(layer "In9.Cu")
		(net 440)
	)
	(segment
		(start 156.561091 145.3)
		(end 156.56109 145.3)
		(width 0.1)
		(layer "In9.Cu")
		(net 440)
	)
	(segment
		(start 164.41 145.2)
		(end 164.93 145.72)
		(width 0.1)
		(layer "In9.Cu")
		(net 440)
	)
	(segment
		(start 156.265263 146.55981)
		(end 156.265264 146.55981)
		(width 0.1)
		(layer "In9.Cu")
		(net 440)
	)
	(segment
		(start 174.74 147.5)
		(end 175.5 147.5)
		(width 0.1)
		(layer "In9.Cu")
		(net 440)
	)
	(segment
		(start 156.95 145.3)
		(end 157.05 145.2)
		(width 0.1)
		(layer "In9.Cu")
		(net 440)
	)
	(segment
		(start 147.5 153)
		(end 152.55 147.95)
		(width 0.1)
		(layer "In9.Cu")
		(net 440)
	)
	(segment
		(start 172.96 145.72)
		(end 174.74 147.5)
		(width 0.1)
		(layer "In9.Cu")
		(net 440)
	)
	(segment
		(start 140.1 152.35)
		(end 140.75 153)
		(width 0.1)
		(layer "In9.Cu")
		(net 440)
	)
	(segment
		(start 154.523444 146.762538)
		(end 154.523446 146.762538)
		(width 0.1)
		(layer "In9.Cu")
		(net 440)
	)
	(segment
		(start 155.690187 145.984733)
		(end 156.265263 146.55981)
		(width 0.1)
		(layer "In9.Cu")
		(net 440)
	)
	(segment
		(start 154.912354 146.762538)
		(end 155.487435 147.337617)
		(width 0.1)
		(layer "In9.Cu")
		(net 440)
	)
	(segment
		(start 156.654173 146.170899)
		(end 156.079095 145.595821)
		(width 0.1)
		(layer "In9.Cu")
		(net 440)
	)
	(segment
		(start 155.876344 146.948708)
		(end 155.588817 146.66118)
		(width 0.1)
		(layer "In9.Cu")
		(net 440)
	)
	(segment
		(start 140.1 150.575)
		(end 140.1 152.35)
		(width 0.1)
		(layer "In9.Cu")
		(net 440)
	)
	(segment
		(start 155.876343 147.337618)
		(end 155.876343 147.337617)
		(width 0.1)
		(layer "In9.Cu")
		(net 440)
	)
	(segment
		(start 129.716328 144.017859)
		(end 129.25 144.484187)
		(width 0.1)
		(layer "In9.Cu")
		(net 440)
	)
	(segment
		(start 152.55 147.95)
		(end 154.3 147.95)
		(width 0.1)
		(layer "In9.Cu")
		(net 440)
	)
	(segment
		(start 154.616543 147.244546)
		(end 154.523444 147.151447)
		(width 0.1)
		(layer "In9.Cu")
		(net 440)
	)
	(segment
		(start 131.4 149.6)
		(end 139.125 149.6)
		(width 0.1)
		(layer "In9.Cu")
		(net 440)
	)
	(segment
		(start 156.654173 146.559809)
		(end 156.654174 146.559808)
		(width 0.1)
		(layer "In9.Cu")
		(net 440)
	)
	(segment
		(start 155.588817 146.66118)
		(end 155.301278 146.373641)
		(width 0.1)
		(layer "In9.Cu")
		(net 440)
	)
	(segment
		(start 139.125 149.6)
		(end 140.1 150.575)
		(width 0.1)
		(layer "In9.Cu")
		(net 440)
	)
	(segment
		(start 156.079095 145.206913)
		(end 156.079096 145.206913)
		(width 0.1)
		(layer "In9.Cu")
		(net 440)
	)
	(segment
		(start 156.468004 145.206913)
		(end 156.561091 145.3)
		(width 0.1)
		(layer "In9.Cu")
		(net 440)
	)
	(segment
		(start 157.05 145.2)
		(end 164.41 145.2)
		(width 0.1)
		(layer "In9.Cu")
		(net 440)
	)
	(segment
		(start 154.523444 147.151447)
		(end 154.523443 147.151447)
		(width 0.1)
		(layer "In9.Cu")
		(net 440)
	)
	(segment
		(start 154.3 147.95)
		(end 154.616542 147.633455)
		(width 0.1)
		(layer "In9.Cu")
		(net 440)
	)
	(segment
		(start 155.301278 145.984733)
		(end 155.301278 145.984734)
		(width 0.1)
		(layer "In9.Cu")
		(net 440)
	)
	(segment
		(start 140.75 153)
		(end 147.5 153)
		(width 0.1)
		(layer "In9.Cu")
		(net 440)
	)
	(segment
		(start 129.25 147.45)
		(end 131.4 149.6)
		(width 0.1)
		(layer "In9.Cu")
		(net 440)
	)
	(segment
		(start 129.25 144.484187)
		(end 129.25 147.45)
		(width 0.1)
		(layer "In9.Cu")
		(net 440)
	)
	(segment
		(start 155.487435 147.337617)
		(end 155.487434 147.337619)
		(width 0.1)
		(layer "In9.Cu")
		(net 440)
	)
	(arc
		(start 156.654174 146.559808)
		(mid 156.734719 146.365353)
		(end 156.654173 146.170899)
		(width 0.1)
		(layer "In9.Cu")
		(net 440)
	)
	(arc
		(start 154.616542 147.633455)
		(mid 154.697088 147.439001)
		(end 154.616543 147.244546)
		(width 0.1)
		(layer "In9.Cu")
		(net 440)
	)
	(arc
		(start 155.301278 146.373641)
		(mid 155.220733 146.179187)
		(end 155.301278 145.984733)
		(width 0.1)
		(layer "In9.Cu")
		(net 440)
	)
	(arc
		(start 156.079095 145.595821)
		(mid 155.99855 145.401367)
		(end 156.079095 145.206913)
		(width 0.1)
		(layer "In9.Cu")
		(net 440)
	)
	(arc
		(start 156.079096 145.206913)
		(mid 156.27355 145.126368)
		(end 156.468004 145.206913)
		(width 0.1)
		(layer "In9.Cu")
		(net 440)
	)
	(arc
		(start 154.523446 146.762538)
		(mid 154.7179 146.681993)
		(end 154.912354 146.762538)
		(width 0.1)
		(layer "In9.Cu")
		(net 440)
	)
	(arc
		(start 154.523443 147.151447)
		(mid 154.442898 146.956992)
		(end 154.523444 146.762538)
		(width 0.1)
		(layer "In9.Cu")
		(net 440)
	)
	(arc
		(start 155.487434 147.337619)
		(mid 155.681889 147.418164)
		(end 155.876343 147.337618)
		(width 0.1)
		(layer "In9.Cu")
		(net 440)
	)
	(arc
		(start 155.876343 147.337617)
		(mid 155.956889 147.143163)
		(end 155.876344 146.948708)
		(width 0.1)
		(layer "In9.Cu")
		(net 440)
	)
	(arc
		(start 155.301278 145.984734)
		(mid 155.495732 145.904188)
		(end 155.690187 145.984733)
		(width 0.1)
		(layer "In9.Cu")
		(net 440)
	)
	(arc
		(start 156.265264 146.55981)
		(mid 156.459719 146.640355)
		(end 156.654173 146.559809)
		(width 0.1)
		(layer "In9.Cu")
		(net 440)
	)
	(arc
		(start 156.56109 145.3)
		(mid 156.755545 145.380546)
		(end 156.95 145.3)
		(width 0.1)
		(layer "In9.Cu")
		(net 440)
	)
	(segment
		(start 144.433 169.072501)
		(end 144.433 168.207501)
		(width 0.15)
		(layer "F.Cu")
		(net 441)
	)
	(segment
		(start 144.433 166.772)
		(end 144.433 168.190499)
		(width 0.15)
		(layer "F.Cu")
		(net 441)
	)
	(segment
		(start 144.433 168.207501)
		(end 144.424499 168.199)
		(width 0.15)
		(layer "F.Cu")
		(net 441)
	)
	(segment
		(start 144.433 169.072501)
		(end 144.774499 169.414)
		(width 0.15)
		(layer "F.Cu")
		(net 441)
	)
	(segment
		(start 144.433 168.190499)
		(end 144.424499 168.199)
		(width 0.15)
		(layer "F.Cu")
		(net 441)
	)
	(via
		(at 144.424499 168.199)
		(size 0.45)
		(drill 0.1)
		(layers "F.Cu" "B.Cu")
		(remove_unused_layers yes)
		(keep_end_layers yes)
		(zone_layer_connections)
		(net 441)
	)
	(segment
		(start 144.424499 168.199)
		(end 145.124499 168.199)
		(width 0.15)
		(layer "B.Cu")
		(net 441)
	)
	(segment
		(start 145.124499 168.199)
		(end 145.324499 168.399)
		(width 0.15)
		(layer "B.Cu")
		(net 441)
	)
	(segment
		(start 145.324499 168.399)
		(end 145.324499 168.914)
		(width 0.15)
		(layer "B.Cu")
		(net 441)
	)
	(segment
		(start 178.9995 156.0005)
		(end 178.5 156.5)
		(width 0.256)
		(layer "F.Cu")
		(net 442)
	)
	(via
		(at 178.5 156.5)
		(size 0.45)
		(drill 0.1)
		(layers "F.Cu" "B.Cu")
		(remove_unused_layers yes)
		(keep_end_layers yes)
		(zone_layer_connections)
		(net 442)
	)
	(via
		(at 145.524499 170.849)
		(size 0.45)
		(drill 0.1)
		(layers "F.Cu" "B.Cu")
		(remove_unused_layers yes)
		(keep_end_layers yes)
		(zone_layer_connections)
		(net 442)
	)
	(segment
		(start 145.324499 169.884)
		(end 145.324499 170.649)
		(width 0.15)
		(layer "B.Cu")
		(net 442)
	)
	(segment
		(start 145.324499 170.649)
		(end 145.524499 170.849)
		(width 0.15)
		(layer "B.Cu")
		(net 442)
	)
	(segment
		(start 142.12 175.89)
		(end 156.61 175.89)
		(width 0.1)
		(layer "In9.Cu")
		(net 442)
	)
	(segment
		(start 139.75 170.07)
		(end 139.93 170.25)
		(width 0.1)
		(layer "In9.Cu")
		(net 442)
	)
	(segment
		(start 156.61 175.89)
		(end 164.5 168)
		(width 0.1)
		(layer "In9.Cu")
		(net 442)
	)
	(segment
		(start 141.926 169.006)
		(end 139.969 169.006)
		(width 0.1)
		(layer "In9.Cu")
		(net 442)
	)
	(segment
		(start 139.93 173.7)
		(end 142.12 175.89)
		(width 0.1)
		(layer "In9.Cu")
		(net 442)
	)
	(segment
		(start 139.75 169.225)
		(end 139.75 170.07)
		(width 0.1)
		(layer "In9.Cu")
		(net 442)
	)
	(segment
		(start 164.5 168)
		(end 167.5 168)
		(width 0.1)
		(layer "In9.Cu")
		(net 442)
	)
	(segment
		(start 179 160.7)
		(end 179 157)
		(width 0.1)
		(layer "In9.Cu")
		(net 442)
	)
	(segment
		(start 142.55 169.63)
		(end 141.926 169.006)
		(width 0.1)
		(layer "In9.Cu")
		(net 442)
	)
	(segment
		(start 178.65 161.05)
		(end 179 160.7)
		(width 0.1)
		(layer "In9.Cu")
		(net 442)
	)
	(segment
		(start 145.524499 170.849)
		(end 144.305499 169.63)
		(width 0.1)
		(layer "In9.Cu")
		(net 442)
	)
	(segment
		(start 144.305499 169.63)
		(end 142.55 169.63)
		(width 0.1)
		(layer "In9.Cu")
		(net 442)
	)
	(segment
		(start 139.93 170.25)
		(end 139.93 173.7)
		(width 0.1)
		(layer "In9.Cu")
		(net 442)
	)
	(segment
		(start 167.5 168)
		(end 174.45 161.05)
		(width 0.1)
		(layer "In9.Cu")
		(net 442)
	)
	(segment
		(start 174.45 161.05)
		(end 178.65 161.05)
		(width 0.1)
		(layer "In9.Cu")
		(net 442)
	)
	(segment
		(start 139.969 169.006)
		(end 139.75 169.225)
		(width 0.1)
		(layer "In9.Cu")
		(net 442)
	)
	(segment
		(start 179 157)
		(end 178.5 156.5)
		(width 0.1)
		(layer "In9.Cu")
		(net 442)
	)
	(segment
		(start 137.272499 180.896)
		(end 136.677499 180.896)
		(width 0.201)
		(layer "F.Cu")
		(net 443)
	)
	(segment
		(start 135.824499 181.749)
		(end 135.824499 182.779)
		(width 0.201)
		(layer "F.Cu")
		(net 443)
	)
	(segment
		(start 136.677499 180.896)
		(end 135.824499 181.749)
		(width 0.201)
		(layer "F.Cu")
		(net 443)
	)
	(segment
		(start 137.823499 182.38)
		(end 137.424499 182.779)
		(width 0.201)
		(layer "F.Cu")
		(net 444)
	)
	(segment
		(start 137.823499 181.447)
		(end 137.823499 182.38)
		(width 0.201)
		(layer "F.Cu")
		(net 444)
	)
	(segment
		(start 138.220499 181.447)
		(end 138.220499 182.145)
		(width 0.201)
		(layer "F.Cu")
		(net 445)
	)
	(segment
		(start 138.220499 182.145)
		(end 138.869499 182.794)
		(width 0.201)
		(layer "F.Cu")
		(net 445)
	)
	(segment
		(start 138.869499 182.794)
		(end 139.424499 182.794)
		(width 0.201)
		(layer "F.Cu")
		(net 445)
	)
	(segment
		(start 140.494499 182.249)
		(end 141.024499 182.779)
		(width 0.201)
		(layer "F.Cu")
		(net 446)
	)
	(segment
		(start 138.623499 181.848)
		(end 139.024499 182.249)
		(width 0.201)
		(layer "F.Cu")
		(net 446)
	)
	(segment
		(start 138.623499 181.447)
		(end 138.623499 181.848)
		(width 0.201)
		(layer "F.Cu")
		(net 446)
	)
	(segment
		(start 139.024499 182.249)
		(end 140.494499 182.249)
		(width 0.201)
		(layer "F.Cu")
		(net 446)
	)
	(segment
		(start 149.374499 172.733)
		(end 148.775499 172.134)
		(width 0.15)
		(layer "F.Cu")
		(net 447)
	)
	(segment
		(start 148.775499 172.134)
		(end 148.775499 171.383)
		(width 0.15)
		(layer "F.Cu")
		(net 447)
	)
	(segment
		(start 149.374499 172.764)
		(end 149.374499 172.733)
		(width 0.15)
		(layer "F.Cu")
		(net 447)
	)
	(segment
		(start 148.364499 160.109)
		(end 149.019499 160.109)
		(width 0.15)
		(layer "F.Cu")
		(net 448)
	)
	(segment
		(start 149.019499 160.109)
		(end 149.419499 159.709)
		(width 0.15)
		(layer "F.Cu")
		(net 448)
	)
	(segment
		(start 149.169499 160.459)
		(end 149.419499 160.709)
		(width 0.15)
		(layer "F.Cu")
		(net 449)
	)
	(segment
		(start 148.364499 160.459)
		(end 149.169499 160.459)
		(width 0.15)
		(layer "F.Cu")
		(net 449)
	)
	(segment
		(start 183.9995 139.9995)
		(end 183.5 139.500001)
		(width 0.256)
		(layer "F.Cu")
		(net 450)
	)
	(segment
		(start 141.15 110.598)
		(end 141.15 111.75)
		(width 0.38)
		(layer "F.Cu")
		(net 450)
	)
	(via
		(at 183.5 139.500001)
		(size 0.45)
		(drill 0.1)
		(layers "F.Cu" "B.Cu")
		(remove_unused_layers yes)
		(keep_end_layers yes)
		(zone_layer_connections)
		(net 450)
	)
	(via
		(at 141.15 111.75)
		(size 0.45)
		(drill 0.1)
		(layers "F.Cu" "B.Cu")
		(remove_unused_layers yes)
		(keep_end_layers yes)
		(zone_layer_connections)
		(net 450)
	)
	(segment
		(start 162.65 117.17)
		(end 162.65 116.896282)
		(width 0.148)
		(layer "In4.Cu")
		(net 450)
	)
	(segment
		(start 168.05 117.17)
		(end 168.05 116.896282)
		(width 0.148)
		(layer "In4.Cu")
		(net 450)
	)
	(segment
		(start 164.45 117.17)
		(end 164.45 116.896282)
		(width 0.148)
		(layer "In4.Cu")
		(net 450)
	)
	(segment
		(start 163.55 116.896282)
		(end 163.55 117.17)
		(width 0.148)
		(layer "In4.Cu")
		(net 450)
	)
	(segment
		(start 165.35 116.896282)
		(end 165.35 117.17)
		(width 0.148)
		(layer "In4.Cu")
		(net 450)
	)
	(segment
		(start 146.12 117.62)
		(end 162.2 117.62)
		(width 0.148)
		(layer "In4.Cu")
		(net 450)
	)
	(segment
		(start 172.34 117.62)
		(end 183.5 128.78)
		(width 0.148)
		(layer "In4.Cu")
		(net 450)
	)
	(segment
		(start 141.15 112.65)
		(end 146.12 117.62)
		(width 0.148)
		(layer "In4.Cu")
		(net 450)
	)
	(segment
		(start 170.75 116.896265)
		(end 170.75 117.17)
		(width 0.148)
		(layer "In4.Cu")
		(net 450)
	)
	(segment
		(start 171.2 117.62)
		(end 172.15 117.62)
		(width 0.148)
		(layer "In4.Cu")
		(net 450)
	)
	(segment
		(start 167.15 116.896282)
		(end 167.15 117.17)
		(width 0.148)
		(layer "In4.Cu")
		(net 450)
	)
	(segment
		(start 172.15 117.62)
		(end 172.34 117.62)
		(width 0.148)
		(layer "In4.Cu")
		(net 450)
	)
	(segment
		(start 183.5 128.78)
		(end 183.5 139.500001)
		(width 0.148)
		(layer "In4.Cu")
		(net 450)
	)
	(segment
		(start 169.85 117.17)
		(end 169.85 116.896265)
		(width 0.148)
		(layer "In4.Cu")
		(net 450)
	)
	(segment
		(start 168.95 116.896282)
		(end 168.95 117.17)
		(width 0.148)
		(layer "In4.Cu")
		(net 450)
	)
	(segment
		(start 141.15 111.75)
		(end 141.15 112.65)
		(width 0.148)
		(layer "In4.Cu")
		(net 450)
	)
	(segment
		(start 166.25 117.17)
		(end 166.25 116.896282)
		(width 0.148)
		(layer "In4.Cu")
		(net 450)
	)
	(arc
		(start 163.55 117.17)
		(mid 163.681802 117.488198)
		(end 164 117.62)
		(width 0.148)
		(layer "In4.Cu")
		(net 450)
	)
	(arc
		(start 164.9 116.446282)
		(mid 165.218198 116.578084)
		(end 165.35 116.896282)
		(width 0.148)
		(layer "In4.Cu")
		(net 450)
	)
	(arc
		(start 165.8 117.62)
		(mid 166.118198 117.488198)
		(end 166.25 117.17)
		(width 0.148)
		(layer "In4.Cu")
		(net 450)
	)
	(arc
		(start 169.4 117.62)
		(mid 169.718198 117.488198)
		(end 169.85 117.17)
		(width 0.148)
		(layer "In4.Cu")
		(net 450)
	)
	(arc
		(start 168.5 116.446282)
		(mid 168.818198 116.578084)
		(end 168.95 116.896282)
		(width 0.148)
		(layer "In4.Cu")
		(net 450)
	)
	(arc
		(start 167.6 117.62)
		(mid 167.918198 117.488198)
		(end 168.05 117.17)
		(width 0.148)
		(layer "In4.Cu")
		(net 450)
	)
	(arc
		(start 162.65 116.896282)
		(mid 162.781802 116.578084)
		(end 163.1 116.446282)
		(width 0.148)
		(layer "In4.Cu")
		(net 450)
	)
	(arc
		(start 164.45 116.896282)
		(mid 164.581802 116.578084)
		(end 164.9 116.446282)
		(width 0.148)
		(layer "In4.Cu")
		(net 450)
	)
	(arc
		(start 163.1 116.446282)
		(mid 163.418198 116.578084)
		(end 163.55 116.896282)
		(width 0.148)
		(layer "In4.Cu")
		(net 450)
	)
	(arc
		(start 162.2 117.62)
		(mid 162.518198 117.488198)
		(end 162.65 117.17)
		(width 0.148)
		(layer "In4.Cu")
		(net 450)
	)
	(arc
		(start 168.95 117.17)
		(mid 169.081802 117.488198)
		(end 169.4 117.62)
		(width 0.148)
		(layer "In4.Cu")
		(net 450)
	)
	(arc
		(start 164 117.62)
		(mid 164.318198 117.488198)
		(end 164.45 117.17)
		(width 0.148)
		(layer "In4.Cu")
		(net 450)
	)
	(arc
		(start 165.35 117.17)
		(mid 165.481802 117.488198)
		(end 165.8 117.62)
		(width 0.148)
		(layer "In4.Cu")
		(net 450)
	)
	(arc
		(start 167.15 117.17)
		(mid 167.281802 117.488198)
		(end 167.6 117.62)
		(width 0.148)
		(layer "In4.Cu")
		(net 450)
	)
	(arc
		(start 170.75 117.17)
		(mid 170.881802 117.488198)
		(end 171.2 117.62)
		(width 0.148)
		(layer "In4.Cu")
		(net 450)
	)
	(arc
		(start 168.05 116.896282)
		(mid 168.181802 116.578084)
		(end 168.5 116.446282)
		(width 0.148)
		(layer "In4.Cu")
		(net 450)
	)
	(arc
		(start 166.25 116.896282)
		(mid 166.381802 116.578084)
		(end 166.7 116.446282)
		(width 0.148)
		(layer "In4.Cu")
		(net 450)
	)
	(arc
		(start 169.85 116.896265)
		(mid 169.981802 116.578067)
		(end 170.3 116.446265)
		(width 0.148)
		(layer "In4.Cu")
		(net 450)
	)
	(arc
		(start 170.3 116.446265)
		(mid 170.618198 116.578067)
		(end 170.75 116.896265)
		(width 0.148)
		(layer "In4.Cu")
		(net 450)
	)
	(arc
		(start 166.7 116.446282)
		(mid 167.018198 116.578084)
		(end 167.15 116.896282)
		(width 0.148)
		(layer "In4.Cu")
		(net 450)
	)
	(segment
		(start 189 143)
		(end 189.499499 143.4995)
		(width 0.256)
		(layer "F.Cu")
		(net 451)
	)
	(segment
		(start 167.5 110.598)
		(end 167.5 111.75)
		(width 0.38)
		(layer "F.Cu")
		(net 451)
	)
	(via
		(at 167.5 111.75)
		(size 0.45)
		(drill 0.1)
		(layers "F.Cu" "B.Cu")
		(remove_unused_layers yes)
		(keep_end_layers yes)
		(zone_layer_connections)
		(net 451)
	)
	(via
		(at 189.499499 143.4995)
		(size 0.45)
		(drill 0.1)
		(layers "F.Cu" "B.Cu")
		(remove_unused_layers yes)
		(keep_end_layers yes)
		(zone_layer_connections)
		(net 451)
	)
	(segment
		(start 189.1 143.15)
		(end 190.1 142.15)
		(width 0.1)
		(layer "In6.Cu")
		(net 451)
	)
	(segment
		(start 182.263245 125.20278)
		(end 181.849064 125.616958)
		(width 0.13)
		(layer "In6.Cu")
		(net 451)
	)
	(segment
		(start 186.629107 130.397)
		(end 186.629105 130.396999)
		(width 0.13)
		(layer "In6.Cu")
		(net 451)
	)
	(segment
		(start 188.04332 131.811213)
		(end 188.043318 131.811212)
		(width 0.13)
		(layer "In6.Cu")
		(net 451)
	)
	(segment
		(start 189.334261 132.273894)
		(end 188.740687 132.867464)
		(width 0.13)
		(layer "In6.Cu")
		(net 451)
	)
	(segment
		(start 189.33426 132.273895)
		(end 189.334261 132.273894)
		(width 0.13)
		(layer "In6.Cu")
		(net 451)
	)
	(segment
		(start 182.263244 125.202781)
		(end 182.263245 125.20278)
		(width 0.13)
		(layer "In6.Cu")
		(net 451)
	)
	(segment
		(start 183.677457 125.740182)
		(end 183.677456 125.740182)
		(width 0.13)
		(layer "In6.Cu")
		(net 451)
	)
	(segment
		(start 188.920129 133.225425)
		(end 188.740696 133.046028)
		(width 0.13)
		(layer "In6.Cu")
		(net 451)
	)
	(segment
		(start 180.972255 124.740148)
		(end 180.972253 124.740147)
		(width 0.13)
		(layer "In6.Cu")
		(net 451)
	)
	(segment
		(start 183.677456 126.616994)
		(end 183.263279 127.031172)
		(width 0.13)
		(layer "In6.Cu")
		(net 451)
	)
	(segment
		(start 189.499499 143.4995)
		(end 189.473999 143.525)
		(width 0.1)
		(layer "In6.Cu")
		(net 451)
	)
	(segment
		(start 180.972253 124.740147)
		(end 181.386433 124.325968)
		(width 0.13)
		(layer "In6.Cu")
		(net 451)
	)
	(segment
		(start 176.449706 120.755)
		(end 180.521077 124.826372)
		(width 0.13)
		(layer "In6.Cu")
		(net 451)
	)
	(segment
		(start 189.1 143.475)
		(end 189.1 143.15)
		(width 0.1)
		(layer "In6.Cu")
		(net 451)
	)
	(segment
		(start 172.299706 120.755)
		(end 176.449706 120.755)
		(width 0.13)
		(layer "In6.Cu")
		(net 451)
	)
	(segment
		(start 188.92013 133.225425)
		(end 190.12 134.425294)
		(width 0.13)
		(layer "In6.Cu")
		(net 451)
	)
	(segment
		(start 185.091656 128.031221)
		(end 184.67749 128.445384)
		(width 0.13)
		(layer "In6.Cu")
		(net 451)
	)
	(segment
		(start 183.677455 126.616995)
		(end 183.677456 126.616994)
		(width 0.13)
		(layer "In6.Cu")
		(net 451)
	)
	(segment
		(start 186.505872 129.445431)
		(end 186.091703 129.859597)
		(width 0.13)
		(layer "In6.Cu")
		(net 451)
	)
	(segment
		(start 187.92006 130.859669)
		(end 187.505916 131.27381)
		(width 0.13)
		(layer "In6.Cu")
		(net 451)
	)
	(segment
		(start 185.214894 128.982787)
		(end 185.214892 128.982786)
		(width 0.13)
		(layer "In6.Cu")
		(net 451)
	)
	(segment
		(start 182.386468 126.154361)
		(end 182.386466 126.15436)
		(width 0.13)
		(layer "In6.Cu")
		(net 451)
	)
	(segment
		(start 187.920059 130.85967)
		(end 187.92006 130.859669)
		(width 0.13)
		(layer "In6.Cu")
		(net 451)
	)
	(segment
		(start 190.12 134.425294)
		(end 190.12 138)
		(width 0.13)
		(layer "In6.Cu")
		(net 451)
	)
	(segment
		(start 183.800679 127.568573)
		(end 184.214844 127.154409)
		(width 0.13)
		(layer "In6.Cu")
		(net 451)
	)
	(segment
		(start 185.091655 128.031222)
		(end 185.091656 128.031221)
		(width 0.13)
		(layer "In6.Cu")
		(net 451)
	)
	(segment
		(start 167.195 111.905)
		(end 167.195 115.650294)
		(width 0.13)
		(layer "In6.Cu")
		(net 451)
	)
	(segment
		(start 190.1 142.15)
		(end 190.1 138.02)
		(width 0.1)
		(layer "In6.Cu")
		(net 451)
	)
	(segment
		(start 167.5 111.75)
		(end 167.35 111.75)
		(width 0.13)
		(layer "In6.Cu")
		(net 451)
	)
	(segment
		(start 183.800681 127.568574)
		(end 183.800679 127.568573)
		(width 0.13)
		(layer "In6.Cu")
		(net 451)
	)
	(segment
		(start 186.505871 129.445432)
		(end 186.505872 129.445431)
		(width 0.13)
		(layer "In6.Cu")
		(net 451)
	)
	(segment
		(start 186.629105 130.396999)
		(end 187.043248 129.982857)
		(width 0.13)
		(layer "In6.Cu")
		(net 451)
	)
	(segment
		(start 188.043318 131.811212)
		(end 188.457449 131.397082)
		(width 0.13)
		(layer "In6.Cu")
		(net 451)
	)
	(segment
		(start 180.885969 124.826404)
		(end 180.972255 124.740148)
		(width 0.13)
		(layer "In6.Cu")
		(net 451)
	)
	(segment
		(start 190.1 138.02)
		(end 190.12 138)
		(width 0.1)
		(layer "In6.Cu")
		(net 451)
	)
	(segment
		(start 167.35 111.75)
		(end 167.195 111.905)
		(width 0.13)
		(layer "In6.Cu")
		(net 451)
	)
	(segment
		(start 189.15 143.525)
		(end 189.1 143.475)
		(width 0.1)
		(layer "In6.Cu")
		(net 451)
	)
	(segment
		(start 182.386466 126.15436)
		(end 182.800644 125.740183)
		(width 0.13)
		(layer "In6.Cu")
		(net 451)
	)
	(segment
		(start 189.473999 143.525)
		(end 189.15 143.525)
		(width 0.1)
		(layer "In6.Cu")
		(net 451)
	)
	(segment
		(start 185.214892 128.982786)
		(end 185.62906 128.568619)
		(width 0.13)
		(layer "In6.Cu")
		(net 451)
	)
	(segment
		(start 167.195 115.650294)
		(end 172.299706 120.755)
		(width 0.13)
		(layer "In6.Cu")
		(net 451)
	)
	(arc
		(start 185.62906 128.568619)
		(mid 186.067466 128.387025)
		(end 186.505872 128.568619)
		(width 0.13)
		(layer "In6.Cu")
		(net 451)
	)
	(arc
		(start 186.091703 130.396998)
		(mid 186.360405 130.508299)
		(end 186.629107 130.397)
		(width 0.13)
		(layer "In6.Cu")
		(net 451)
	)
	(arc
		(start 187.92006 129.982857)
		(mid 188.101653 130.421264)
		(end 187.920059 130.85967)
		(width 0.13)
		(layer "In6.Cu")
		(net 451)
	)
	(arc
		(start 180.521077 124.826372)
		(mid 180.703516 124.901951)
		(end 180.885969 124.826404)
		(width 0.13)
		(layer "In6.Cu")
		(net 451)
	)
	(arc
		(start 186.505872 128.568619)
		(mid 186.687465 129.007026)
		(end 186.505871 129.445432)
		(width 0.13)
		(layer "In6.Cu")
		(net 451)
	)
	(arc
		(start 186.091703 129.859597)
		(mid 185.980404 130.128298)
		(end 186.091704 130.396998)
		(width 0.13)
		(layer "In6.Cu")
		(net 451)
	)
	(arc
		(start 187.505916 131.27381)
		(mid 187.394617 131.542512)
		(end 187.505916 131.811212)
		(width 0.13)
		(layer "In6.Cu")
		(net 451)
	)
	(arc
		(start 184.67749 128.982785)
		(mid 184.946192 129.094086)
		(end 185.214894 128.982787)
		(width 0.13)
		(layer "In6.Cu")
		(net 451)
	)
	(arc
		(start 188.740687 132.867464)
		(mid 188.703707 132.956748)
		(end 188.740696 133.046028)
		(width 0.13)
		(layer "In6.Cu")
		(net 451)
	)
	(arc
		(start 183.677456 125.740182)
		(mid 183.859049 126.178589)
		(end 183.677455 126.616995)
		(width 0.13)
		(layer "In6.Cu")
		(net 451)
	)
	(arc
		(start 187.505916 131.811211)
		(mid 187.774618 131.922512)
		(end 188.04332 131.811213)
		(width 0.13)
		(layer "In6.Cu")
		(net 451)
	)
	(arc
		(start 185.091656 127.154409)
		(mid 185.273249 127.592816)
		(end 185.091655 128.031222)
		(width 0.13)
		(layer "In6.Cu")
		(net 451)
	)
	(arc
		(start 181.386433 124.325968)
		(mid 181.824839 124.144374)
		(end 182.263245 124.325968)
		(width 0.13)
		(layer "In6.Cu")
		(net 451)
	)
	(arc
		(start 181.849064 125.616958)
		(mid 181.737765 125.885659)
		(end 181.849065 126.154359)
		(width 0.13)
		(layer "In6.Cu")
		(net 451)
	)
	(arc
		(start 184.214844 127.154409)
		(mid 184.65325 126.972815)
		(end 185.091656 127.154409)
		(width 0.13)
		(layer "In6.Cu")
		(net 451)
	)
	(arc
		(start 188.457449 131.397082)
		(mid 188.895855 131.215488)
		(end 189.334261 131.397082)
		(width 0.13)
		(layer "In6.Cu")
		(net 451)
	)
	(arc
		(start 181.849064 126.154359)
		(mid 182.117766 126.26566)
		(end 182.386468 126.154361)
		(width 0.13)
		(layer "In6.Cu")
		(net 451)
	)
	(arc
		(start 183.263279 127.031172)
		(mid 183.151979 127.299872)
		(end 183.263278 127.568573)
		(width 0.13)
		(layer "In6.Cu")
		(net 451)
	)
	(arc
		(start 183.263277 127.568572)
		(mid 183.531979 127.679873)
		(end 183.800681 127.568574)
		(width 0.13)
		(layer "In6.Cu")
		(net 451)
	)
	(arc
		(start 187.043248 129.982857)
		(mid 187.481654 129.801263)
		(end 187.92006 129.982857)
		(width 0.13)
		(layer "In6.Cu")
		(net 451)
	)
	(arc
		(start 182.263245 124.325968)
		(mid 182.444838 124.764375)
		(end 182.263244 125.202781)
		(width 0.13)
		(layer "In6.Cu")
		(net 451)
	)
	(arc
		(start 184.67749 128.445384)
		(mid 184.566191 128.714086)
		(end 184.67749 128.982786)
		(width 0.13)
		(layer "In6.Cu")
		(net 451)
	)
	(arc
		(start 182.800644 125.740183)
		(mid 183.23905 125.558589)
		(end 183.677457 125.740182)
		(width 0.13)
		(layer "In6.Cu")
		(net 451)
	)
	(arc
		(start 189.334261 131.397082)
		(mid 189.515854 131.835489)
		(end 189.33426 132.273895)
		(width 0.13)
		(layer "In6.Cu")
		(net 451)
	)
	(segment
		(start 166.65 110.598)
		(end 166.65 111.75)
		(width 0.38)
		(layer "F.Cu")
		(net 452)
	)
	(segment
		(start 188 143)
		(end 188.4995 143.4995)
		(width 0.256)
		(layer "F.Cu")
		(net 452)
	)
	(via
		(at 166.65 111.75)
		(size 0.45)
		(drill 0.1)
		(layers "F.Cu" "B.Cu")
		(remove_unused_layers yes)
		(keep_end_layers yes)
		(zone_layer_connections)
		(net 452)
	)
	(via
		(at 188.4995 143.4995)
		(size 0.45)
		(drill 0.1)
		(layers "F.Cu" "B.Cu")
		(remove_unused_layers yes)
		(keep_end_layers yes)
		(zone_layer_connections)
		(net 452)
	)
	(segment
		(start 182.093539 125.033074)
		(end 182.093539 125.033073)
		(width 0.13)
		(layer "In6.Cu")
		(net 452)
	)
	(segment
		(start 181.066838 124.984976)
		(end 181.556138 124.495672)
		(width 0.13)
		(layer "In6.Cu")
		(net 452)
	)
	(segment
		(start 184.507786 129.152492)
		(end 184.507785 129.15249)
		(width 0.13)
		(layer "In6.Cu")
		(net 452)
	)
	(segment
		(start 187.336212 131.980918)
		(end 187.336211 131.980916)
		(width 0.13)
		(layer "In6.Cu")
		(net 452)
	)
	(segment
		(start 189.164556 131.566786)
		(end 189.164556 131.566787)
		(width 0.13)
		(layer "In6.Cu")
		(net 452)
	)
	(segment
		(start 186.336166 129.275724)
		(end 185.921999 129.689892)
		(width 0.13)
		(layer "In6.Cu")
		(net 452)
	)
	(segment
		(start 185.921999 130.566705)
		(end 185.921998 130.566703)
		(width 0.13)
		(layer "In6.Cu")
		(net 452)
	)
	(segment
		(start 187.750355 130.152561)
		(end 187.750355 130.152562)
		(width 0.13)
		(layer "In6.Cu")
		(net 452)
	)
	(segment
		(start 181.67936 126.324065)
		(end 181.679359 126.324064)
		(width 0.13)
		(layer "In6.Cu")
		(net 452)
	)
	(segment
		(start 166.955 115.749706)
		(end 172.200294 120.995)
		(width 0.13)
		(layer "In6.Cu")
		(net 452)
	)
	(segment
		(start 189.164555 132.104188)
		(end 189.164555 132.104187)
		(width 0.13)
		(layer "In6.Cu")
		(net 452)
	)
	(segment
		(start 176.350294 120.995)
		(end 180.340273 124.984978)
		(width 0.13)
		(layer "In6.Cu")
		(net 452)
	)
	(segment
		(start 188.750425 133.395131)
		(end 189.88 134.524706)
		(width 0.13)
		(layer "In6.Cu")
		(net 452)
	)
	(segment
		(start 188.525 143.525)
		(end 188.8 143.525)
		(width 0.1)
		(layer "In6.Cu")
		(net 452)
	)
	(segment
		(start 188.750425 133.39513)
		(end 188.551919 133.196648)
		(width 0.13)
		(layer "In6.Cu")
		(net 452)
	)
	(segment
		(start 187.336212 131.980917)
		(end 187.336212 131.980918)
		(width 0.13)
		(layer "In6.Cu")
		(net 452)
	)
	(segment
		(start 183.507752 126.447289)
		(end 183.093573 126.861465)
		(width 0.13)
		(layer "In6.Cu")
		(net 452)
	)
	(segment
		(start 188.9 143.067158)
		(end 189.9 142.067158)
		(width 0.1)
		(layer "In6.Cu")
		(net 452)
	)
	(segment
		(start 182.093539 125.033073)
		(end 181.67936 125.447253)
		(width 0.13)
		(layer "In6.Cu")
		(net 452)
	)
	(segment
		(start 187.750354 130.689962)
		(end 187.336212 131.104105)
		(width 0.13)
		(layer "In6.Cu")
		(net 452)
	)
	(segment
		(start 166.955 111.93)
		(end 166.955 115.749706)
		(width 0.13)
		(layer "In6.Cu")
		(net 452)
	)
	(segment
		(start 183.970386 127.738279)
		(end 184.384549 127.324113)
		(width 0.13)
		(layer "In6.Cu")
		(net 452)
	)
	(segment
		(start 166.775 111.75)
		(end 166.955 111.93)
		(width 0.13)
		(layer "In6.Cu")
		(net 452)
	)
	(segment
		(start 189.164555 132.104187)
		(end 188.551904 132.716839)
		(width 0.13)
		(layer "In6.Cu")
		(net 452)
	)
	(segment
		(start 186.336166 128.738324)
		(end 186.336167 128.738324)
		(width 0.13)
		(layer "In6.Cu")
		(net 452)
	)
	(segment
		(start 188.4995 143.4995)
		(end 188.525 143.525)
		(width 0.1)
		(layer "In6.Cu")
		(net 452)
	)
	(segment
		(start 184.92195 127.861515)
		(end 184.92195 127.861514)
		(width 0.13)
		(layer "In6.Cu")
		(net 452)
	)
	(segment
		(start 184.921951 127.324113)
		(end 184.921951 127.324114)
		(width 0.13)
		(layer "In6.Cu")
		(net 452)
	)
	(segment
		(start 188.9 143.425)
		(end 188.9 143.067158)
		(width 0.1)
		(layer "In6.Cu")
		(net 452)
	)
	(segment
		(start 166.65 111.75)
		(end 166.775 111.75)
		(width 0.13)
		(layer "In6.Cu")
		(net 452)
	)
	(segment
		(start 183.50775 125.909886)
		(end 183.507751 125.909887)
		(width 0.13)
		(layer "In6.Cu")
		(net 452)
	)
	(segment
		(start 184.92195 127.861514)
		(end 184.507786 128.275679)
		(width 0.13)
		(layer "In6.Cu")
		(net 452)
	)
	(segment
		(start 185.384599 129.152492)
		(end 185.798765 128.738323)
		(width 0.13)
		(layer "In6.Cu")
		(net 452)
	)
	(segment
		(start 187.750354 130.689963)
		(end 187.750354 130.689962)
		(width 0.13)
		(layer "In6.Cu")
		(net 452)
	)
	(segment
		(start 188.213025 131.980918)
		(end 188.627154 131.566786)
		(width 0.13)
		(layer "In6.Cu")
		(net 452)
	)
	(segment
		(start 186.798812 130.566705)
		(end 187.212953 130.152561)
		(width 0.13)
		(layer "In6.Cu")
		(net 452)
	)
	(segment
		(start 172.200294 120.995)
		(end 176.350294 120.995)
		(width 0.13)
		(layer "In6.Cu")
		(net 452)
	)
	(segment
		(start 182.556173 126.324066)
		(end 182.970349 125.909887)
		(width 0.13)
		(layer "In6.Cu")
		(net 452)
	)
	(segment
		(start 185.921999 130.566704)
		(end 185.921999 130.566705)
		(width 0.13)
		(layer "In6.Cu")
		(net 452)
	)
	(segment
		(start 189.9 138.02)
		(end 189.88 138)
		(width 0.1)
		(layer "In6.Cu")
		(net 452)
	)
	(segment
		(start 189.9 142.067158)
		(end 189.9 138.02)
		(width 0.1)
		(layer "In6.Cu")
		(net 452)
	)
	(segment
		(start 189.88 134.524706)
		(end 189.88 138)
		(width 0.13)
		(layer "In6.Cu")
		(net 452)
	)
	(segment
		(start 183.50775 126.447288)
		(end 183.507752 126.447289)
		(width 0.13)
		(layer "In6.Cu")
		(net 452)
	)
	(segment
		(start 182.093539 124.495673)
		(end 182.09354 124.495673)
		(width 0.13)
		(layer "In6.Cu")
		(net 452)
	)
	(segment
		(start 184.507786 129.152491)
		(end 184.507786 129.152492)
		(width 0.13)
		(layer "In6.Cu")
		(net 452)
	)
	(segment
		(start 188.8 143.525)
		(end 188.9 143.425)
		(width 0.1)
		(layer "In6.Cu")
		(net 452)
	)
	(segment
		(start 186.336166 129.275725)
		(end 186.336166 129.275724)
		(width 0.13)
		(layer "In6.Cu")
		(net 452)
	)
	(arc
		(start 181.556138 124.495672)
		(mid 181.824839 124.384373)
		(end 182.093539 124.495673)
		(width 0.13)
		(layer "In6.Cu")
		(net 452)
	)
	(arc
		(start 189.164556 131.566787)
		(mid 189.275855 131.835488)
		(end 189.164555 132.104188)
		(width 0.13)
		(layer "In6.Cu")
		(net 452)
	)
	(arc
		(start 187.336211 131.980916)
		(mid 187.774619 132.162512)
		(end 188.213025 131.980918)
		(width 0.13)
		(layer "In6.Cu")
		(net 452)
	)
	(arc
		(start 188.627154 131.566786)
		(mid 188.895856 131.455487)
		(end 189.164556 131.566786)
		(width 0.13)
		(layer "In6.Cu")
		(net 452)
	)
	(arc
		(start 183.507751 125.909887)
		(mid 183.61905 126.178588)
		(end 183.50775 126.447288)
		(width 0.13)
		(layer "In6.Cu")
		(net 452)
	)
	(arc
		(start 181.67936 125.447253)
		(mid 181.497766 125.885659)
		(end 181.67936 126.324065)
		(width 0.13)
		(layer "In6.Cu")
		(net 452)
	)
	(arc
		(start 181.679359 126.324064)
		(mid 182.117767 126.50566)
		(end 182.556173 126.324066)
		(width 0.13)
		(layer "In6.Cu")
		(net 452)
	)
	(arc
		(start 184.921951 127.324114)
		(mid 185.03325 127.592815)
		(end 184.92195 127.861515)
		(width 0.13)
		(layer "In6.Cu")
		(net 452)
	)
	(arc
		(start 184.507786 128.275679)
		(mid 184.326192 128.714085)
		(end 184.507786 129.152491)
		(width 0.13)
		(layer "In6.Cu")
		(net 452)
	)
	(arc
		(start 185.921998 130.566703)
		(mid 186.360406 130.748299)
		(end 186.798812 130.566705)
		(width 0.13)
		(layer "In6.Cu")
		(net 452)
	)
	(arc
		(start 182.970349 125.909887)
		(mid 183.239049 125.798587)
		(end 183.50775 125.909886)
		(width 0.13)
		(layer "In6.Cu")
		(net 452)
	)
	(arc
		(start 186.336167 128.738324)
		(mid 186.447466 129.007025)
		(end 186.336166 129.275725)
		(width 0.13)
		(layer "In6.Cu")
		(net 452)
	)
	(arc
		(start 180.340273 124.984978)
		(mid 180.703556 125.135454)
		(end 181.066838 124.984976)
		(width 0.13)
		(layer "In6.Cu")
		(net 452)
	)
	(arc
		(start 187.336212 131.104105)
		(mid 187.154618 131.542511)
		(end 187.336212 131.980917)
		(width 0.13)
		(layer "In6.Cu")
		(net 452)
	)
	(arc
		(start 182.09354 124.495673)
		(mid 182.204839 124.764374)
		(end 182.093539 125.033074)
		(width 0.13)
		(layer "In6.Cu")
		(net 452)
	)
	(arc
		(start 183.093573 126.861465)
		(mid 182.911979 127.299871)
		(end 183.093572 127.738278)
		(width 0.13)
		(layer "In6.Cu")
		(net 452)
	)
	(arc
		(start 187.212953 130.152561)
		(mid 187.481655 130.041262)
		(end 187.750355 130.152561)
		(width 0.13)
		(layer "In6.Cu")
		(net 452)
	)
	(arc
		(start 185.798765 128.738323)
		(mid 186.067466 128.627024)
		(end 186.336166 128.738324)
		(width 0.13)
		(layer "In6.Cu")
		(net 452)
	)
	(arc
		(start 187.750355 130.152562)
		(mid 187.861654 130.421263)
		(end 187.750354 130.689963)
		(width 0.13)
		(layer "In6.Cu")
		(net 452)
	)
	(arc
		(start 184.384549 127.324113)
		(mid 184.653251 127.212814)
		(end 184.921951 127.324113)
		(width 0.13)
		(layer "In6.Cu")
		(net 452)
	)
	(arc
		(start 188.551904 132.716839)
		(mid 188.452535 132.956747)
		(end 188.551919 133.196648)
		(width 0.13)
		(layer "In6.Cu")
		(net 452)
	)
	(arc
		(start 185.921999 129.689892)
		(mid 185.740405 130.128298)
		(end 185.921999 130.566704)
		(width 0.13)
		(layer "In6.Cu")
		(net 452)
	)
	(arc
		(start 184.507785 129.15249)
		(mid 184.946193 129.334086)
		(end 185.384599 129.152492)
		(width 0.13)
		(layer "In6.Cu")
		(net 452)
	)
	(arc
		(start 183.093572 127.738277)
		(mid 183.53198 127.919873)
		(end 183.970386 127.738279)
		(width 0.13)
		(layer "In6.Cu")
		(net 452)
	)
	(segment
		(start 136.9 110.598)
		(end 136.9 111.75)
		(width 0.38)
		(layer "F.Cu")
		(net 453)
	)
	(segment
		(start 182.9995 139.9995)
		(end 182.499999 139.500001)
		(width 0.256)
		(layer "F.Cu")
		(net 453)
	)
	(via
		(at 182.499999 139.500001)
		(size 0.45)
		(drill 0.1)
		(layers "F.Cu" "B.Cu")
		(remove_unused_layers yes)
		(keep_end_layers yes)
		(zone_layer_connections)
		(net 453)
	)
	(via
		(at 136.9 111.75)
		(size 0.45)
		(drill 0.1)
		(layers "F.Cu" "B.Cu")
		(remove_unused_layers yes)
		(keep_end_layers yes)
		(zone_layer_connections)
		(net 453)
	)
	(segment
		(start 136.9 115.3)
		(end 147.3 125.7)
		(width 0.148)
		(layer "In4.Cu")
		(net 453)
	)
	(segment
		(start 179.3 142)
		(end 180.75 142)
		(width 0.148)
		(layer "In4.Cu")
		(net 453)
	)
	(segment
		(start 137.225 112.725)
		(end 137.301001 112.725)
		(width 0.148)
		(layer "In4.Cu")
		(net 453)
	)
	(segment
		(start 137.225 114.025)
		(end 137.301001 114.025)
		(width 0.148)
		(layer "In4.Cu")
		(net 453)
	)
	(segment
		(start 147.3 125.7)
		(end 159.995 125.7)
		(width 0.148)
		(layer "In4.Cu")
		(net 453)
	)
	(segment
		(start 136.9 115)
		(end 136.9 115.3)
		(width 0.148)
		(layer "In4.Cu")
		(net 453)
	)
	(segment
		(start 181 141.75)
		(end 181 140.35)
		(width 0.148)
		(layer "In4.Cu")
		(net 453)
	)
	(segment
		(start 168.21 124.19)
		(end 179 134.98)
		(width 0.148)
		(layer "In4.Cu")
		(net 453)
	)
	(segment
		(start 179 134.98)
		(end 179 141.7)
		(width 0.148)
		(layer "In4.Cu")
		(net 453)
	)
	(segment
		(start 137.301001 114.675)
		(end 137.225 114.675)
		(width 0.148)
		(layer "In4.Cu")
		(net 453)
	)
	(segment
		(start 159.995 125.7)
		(end 161.505 124.19)
		(width 0.148)
		(layer "In4.Cu")
		(net 453)
	)
	(segment
		(start 181.35 140)
		(end 182 140)
		(width 0.148)
		(layer "In4.Cu")
		(net 453)
	)
	(segment
		(start 180.75 142)
		(end 181 141.75)
		(width 0.148)
		(layer "In4.Cu")
		(net 453)
	)
	(segment
		(start 161.505 124.19)
		(end 168.21 124.19)
		(width 0.148)
		(layer "In4.Cu")
		(net 453)
	)
	(segment
		(start 182 140)
		(end 182.499999 139.500001)
		(width 0.148)
		(layer "In4.Cu")
		(net 453)
	)
	(segment
		(start 179 141.7)
		(end 179.3 142)
		(width 0.148)
		(layer "In4.Cu")
		(net 453)
	)
	(segment
		(start 137.301001 113.375)
		(end 137.225 113.375)
		(width 0.148)
		(layer "In4.Cu")
		(net 453)
	)
	(segment
		(start 181 140.35)
		(end 181.35 140)
		(width 0.148)
		(layer "In4.Cu")
		(net 453)
	)
	(segment
		(start 136.9 111.75)
		(end 136.9 112.4)
		(width 0.148)
		(layer "In4.Cu")
		(net 453)
	)
	(arc
		(start 137.225 114.675)
		(mid 136.99519 114.77019)
		(end 136.9 115)
		(width 0.148)
		(layer "In4.Cu")
		(net 453)
	)
	(arc
		(start 137.626001 114.35)
		(mid 137.530811 114.57981)
		(end 137.301001 114.675)
		(width 0.148)
		(layer "In4.Cu")
		(net 453)
	)
	(arc
		(start 136.9 113.7)
		(mid 136.99519 113.92981)
		(end 137.225 114.025)
		(width 0.148)
		(layer "In4.Cu")
		(net 453)
	)
	(arc
		(start 137.301001 112.725)
		(mid 137.530811 112.82019)
		(end 137.626001 113.05)
		(width 0.148)
		(layer "In4.Cu")
		(net 453)
	)
	(arc
		(start 137.626001 113.05)
		(mid 137.530811 113.27981)
		(end 137.301001 113.375)
		(width 0.148)
		(layer "In4.Cu")
		(net 453)
	)
	(arc
		(start 137.225 113.375)
		(mid 136.99519 113.47019)
		(end 136.9 113.7)
		(width 0.148)
		(layer "In4.Cu")
		(net 453)
	)
	(arc
		(start 137.301001 114.025)
		(mid 137.530811 114.12019)
		(end 137.626001 114.35)
		(width 0.148)
		(layer "In4.Cu")
		(net 453)
	)
	(arc
		(start 136.9 112.4)
		(mid 136.99519 112.62981)
		(end 137.225 112.725)
		(width 0.148)
		(layer "In4.Cu")
		(net 453)
	)
	(segment
		(start 182.999501 144.9995)
		(end 182.5 144.5)
		(width 0.256)
		(layer "F.Cu")
		(net 454)
	)
	(segment
		(start 135.2 110.598)
		(end 135.2 111.75)
		(width 0.38)
		(layer "F.Cu")
		(net 454)
	)
	(via
		(at 182.5 144.5)
		(size 0.45)
		(drill 0.1)
		(layers "F.Cu" "B.Cu")
		(remove_unused_layers yes)
		(keep_end_layers yes)
		(zone_layer_connections)
		(net 454)
	)
	(via
		(at 135.2 111.75)
		(size 0.45)
		(drill 0.1)
		(layers "F.Cu" "B.Cu")
		(remove_unused_layers yes)
		(keep_end_layers yes)
		(zone_layer_connections)
		(net 454)
	)
	(segment
		(start 160.181076 128.531076)
		(end 160.181076 128.531075)
		(width 0.148)
		(layer "In4.Cu")
		(net 454)
	)
	(segment
		(start 157.831076 128.531075)
		(end 157.831076 128.531076)
		(width 0.148)
		(layer "In4.Cu")
		(net 454)
	)
	(segment
		(start 162.9 127.39)
		(end 161.39 128.9)
		(width 0.148)
		(layer "In4.Cu")
		(net 454)
	)
	(segment
		(start 150.41205 128.162049)
		(end 148.8 128.162049)
		(width 0.148)
		(layer "In4.Cu")
		(net 454)
	)
	(segment
		(start 161.39 128.9)
		(end 160.55 128.9)
		(width 0.148)
		(layer "In4.Cu")
		(net 454)
	)
	(segment
		(start 148.431025 128.531024)
		(end 148.431025 128.531025)
		(width 0.148)
		(layer "In4.Cu")
		(net 454)
	)
	(segment
		(start 157.462152 128.9)
		(end 155.85 128.9)
		(width 0.148)
		(layer "In4.Cu")
		(net 454)
	)
	(segment
		(start 155.112152 128.162151)
		(end 153.5 128.162151)
		(width 0.148)
		(layer "In4.Cu")
		(net 454)
	)
	(segment
		(start 150.781025 128.531025)
		(end 150.781025 128.531024)
		(width 0.148)
		(layer "In4.Cu")
		(net 454)
	)
	(segment
		(start 159.812152 128.162151)
		(end 158.2 128.162151)
		(width 0.148)
		(layer "In4.Cu")
		(net 454)
	)
	(segment
		(start 177 143.75)
		(end 177 136.55)
		(width 0.148)
		(layer "In4.Cu")
		(net 454)
	)
	(segment
		(start 146.41 128.9)
		(end 135.2 117.69)
		(width 0.148)
		(layer "In4.Cu")
		(net 454)
	)
	(segment
		(start 153.131076 128.531075)
		(end 153.131076 128.531076)
		(width 0.148)
		(layer "In4.Cu")
		(net 454)
	)
	(segment
		(start 182.5 144.5)
		(end 182 144)
		(width 0.148)
		(layer "In4.Cu")
		(net 454)
	)
	(segment
		(start 135.2 117.69)
		(end 135.2 111.75)
		(width 0.148)
		(layer "In4.Cu")
		(net 454)
	)
	(segment
		(start 177.25 144)
		(end 177 143.75)
		(width 0.148)
		(layer "In4.Cu")
		(net 454)
	)
	(segment
		(start 167.84 127.39)
		(end 162.9 127.39)
		(width 0.148)
		(layer "In4.Cu")
		(net 454)
	)
	(segment
		(start 152.762152 128.9)
		(end 151.15 128.9)
		(width 0.148)
		(layer "In4.Cu")
		(net 454)
	)
	(segment
		(start 177 136.55)
		(end 167.84 127.39)
		(width 0.148)
		(layer "In4.Cu")
		(net 454)
	)
	(segment
		(start 146.45 128.9)
		(end 146.41 128.9)
		(width 0.148)
		(layer "In4.Cu")
		(net 454)
	)
	(segment
		(start 148.06205 128.9)
		(end 146.45 128.9)
		(width 0.148)
		(layer "In4.Cu")
		(net 454)
	)
	(segment
		(start 155.481076 128.531076)
		(end 155.481076 128.531075)
		(width 0.148)
		(layer "In4.Cu")
		(net 454)
	)
	(segment
		(start 182 144)
		(end 177.25 144)
		(width 0.148)
		(layer "In4.Cu")
		(net 454)
	)
	(arc
		(start 150.781025 128.531024)
		(mid 150.672955 128.270119)
		(end 150.41205 128.162049)
		(width 0.148)
		(layer "In4.Cu")
		(net 454)
	)
	(arc
		(start 153.131076 128.531076)
		(mid 153.023021 128.791945)
		(end 152.762152 128.9)
		(width 0.148)
		(layer "In4.Cu")
		(net 454)
	)
	(arc
		(start 157.831076 128.531076)
		(mid 157.723021 128.791945)
		(end 157.462152 128.9)
		(width 0.148)
		(layer "In4.Cu")
		(net 454)
	)
	(arc
		(start 151.15 128.9)
		(mid 150.889095 128.79193)
		(end 150.781025 128.531025)
		(width 0.148)
		(layer "In4.Cu")
		(net 454)
	)
	(arc
		(start 148.8 128.162049)
		(mid 148.539095 128.270119)
		(end 148.431025 128.531024)
		(width 0.148)
		(layer "In4.Cu")
		(net 454)
	)
	(arc
		(start 153.5 128.162151)
		(mid 153.239131 128.270206)
		(end 153.131076 128.531075)
		(width 0.148)
		(layer "In4.Cu")
		(net 454)
	)
	(arc
		(start 148.431025 128.531025)
		(mid 148.322955 128.79193)
		(end 148.06205 128.9)
		(width 0.148)
		(layer "In4.Cu")
		(net 454)
	)
	(arc
		(start 160.181076 128.531075)
		(mid 160.073021 128.270206)
		(end 159.812152 128.162151)
		(width 0.148)
		(layer "In4.Cu")
		(net 454)
	)
	(arc
		(start 160.55 128.9)
		(mid 160.289131 128.791945)
		(end 160.181076 128.531076)
		(width 0.148)
		(layer "In4.Cu")
		(net 454)
	)
	(arc
		(start 158.2 128.162151)
		(mid 157.939131 128.270206)
		(end 157.831076 128.531075)
		(width 0.148)
		(layer "In4.Cu")
		(net 454)
	)
	(arc
		(start 155.85 128.9)
		(mid 155.589131 128.791945)
		(end 155.481076 128.531076)
		(width 0.148)
		(layer "In4.Cu")
		(net 454)
	)
	(arc
		(start 155.481076 128.531075)
		(mid 155.373021 128.270206)
		(end 155.112152 128.162151)
		(width 0.148)
		(layer "In4.Cu")
		(net 454)
	)
	(segment
		(start 179.9995 142.9995)
		(end 179.5 142.5)
		(width 0.256)
		(layer "F.Cu")
		(net 455)
	)
	(segment
		(start 133.5 110.598)
		(end 133.5 111.75)
		(width 0.38)
		(layer "F.Cu")
		(net 455)
	)
	(via
		(at 179.5 142.5)
		(size 0.45)
		(drill 0.1)
		(layers "F.Cu" "B.Cu")
		(remove_unused_layers yes)
		(keep_end_layers yes)
		(zone_layer_connections)
		(net 455)
	)
	(via
		(at 133.5 111.75)
		(size 0.45)
		(drill 0.1)
		(layers "F.Cu" "B.Cu")
		(remove_unused_layers yes)
		(keep_end_layers yes)
		(zone_layer_connections)
		(net 455)
	)
	(segment
		(start 144.173904 116.968737)
		(end 144.173903 116.968735)
		(width 0.148)
		(layer "In2.Cu")
		(net 455)
	)
	(segment
		(start 143.24632 117.189212)
		(end 143.246319 117.189213)
		(width 0.148)
		(layer "In2.Cu")
		(net 455)
	)
	(segment
		(start 146.781851 121.431852)
		(end 146.781851 121.431851)
		(width 0.148)
		(layer "In2.Cu")
		(net 455)
	)
	(segment
		(start 147.002309 120.504287)
		(end 147.00231 120.504286)
		(width 0.148)
		(layer "In2.Cu")
		(net 455)
	)
	(segment
		(start 181.376 140.899)
		(end 181.05 141.225)
		(width 0.148)
		(layer "In2.Cu")
		(net 455)
	)
	(segment
		(start 179.935728 142.5)
		(end 179.5 142.5)
		(width 0.148)
		(layer "In2.Cu")
		(net 455)
	)
	(segment
		(start 183 137.45)
		(end 183 139.7)
		(width 0.148)
		(layer "In2.Cu")
		(net 455)
	)
	(segment
		(start 157.05 132.9)
		(end 158.8 134.65)
		(width 0.148)
		(layer "In2.Cu")
		(net 455)
	)
	(segment
		(start 143.953425 118.603425)
		(end 143.953426 118.603426)
		(width 0.148)
		(layer "In2.Cu")
		(net 455)
	)
	(segment
		(start 146.074746 120.017638)
		(end 146.074745 120.017639)
		(width 0.148)
		(layer "In2.Cu")
		(net 455)
	)
	(segment
		(start 183 139.7)
		(end 182.7 140)
		(width 0.148)
		(layer "In2.Cu")
		(net 455)
	)
	(segment
		(start 142.759691 116.261627)
		(end 142.759692 116.261626)
		(width 0.148)
		(layer "In2.Cu")
		(net 455)
	)
	(segment
		(start 142.759692 116.261626)
		(end 142.539213 116.482106)
		(width 0.148)
		(layer "In2.Cu")
		(net 455)
	)
	(segment
		(start 158.8 134.65)
		(end 180.2 134.65)
		(width 0.148)
		(layer "In2.Cu")
		(net 455)
	)
	(segment
		(start 182.7 140)
		(end 182.299001 140)
		(width 0.148)
		(layer "In2.Cu")
		(net 455)
	)
	(segment
		(start 144.173903 117.675841)
		(end 143.953426 117.896319)
		(width 0.148)
		(layer "In2.Cu")
		(net 455)
	)
	(segment
		(start 145.588102 119.090069)
		(end 145.367637 119.310531)
		(width 0.148)
		(layer "In2.Cu")
		(net 455)
	)
	(segment
		(start 147.00231 120.504286)
		(end 146.781852 120.724745)
		(width 0.148)
		(layer "In2.Cu")
		(net 455)
	)
	(segment
		(start 144.660533 118.603425)
		(end 144.660532 118.603426)
		(width 0.148)
		(layer "In2.Cu")
		(net 455)
	)
	(segment
		(start 144.660532 118.603426)
		(end 144.880996 118.382963)
		(width 0.148)
		(layer "In2.Cu")
		(net 455)
	)
	(segment
		(start 181.05 141.65)
		(end 180.7 142)
		(width 0.148)
		(layer "In2.Cu")
		(net 455)
	)
	(segment
		(start 145.367637 120.017637)
		(end 145.367639 120.017639)
		(width 0.148)
		(layer "In2.Cu")
		(net 455)
	)
	(segment
		(start 146.074745 120.017639)
		(end 146.295204 119.797181)
		(width 0.148)
		(layer "In2.Cu")
		(net 455)
	)
	(segment
		(start 143.953427 118.603426)
		(end 143.953425 118.603425)
		(width 0.148)
		(layer "In2.Cu")
		(net 455)
	)
	(segment
		(start 144.173902 117.675842)
		(end 144.173903 117.675841)
		(width 0.148)
		(layer "In2.Cu")
		(net 455)
	)
	(segment
		(start 180.2 134.65)
		(end 183 137.45)
		(width 0.148)
		(layer "In2.Cu")
		(net 455)
	)
	(segment
		(start 180.435728 142)
		(end 179.935728 142.5)
		(width 0.148)
		(layer "In2.Cu")
		(net 455)
	)
	(segment
		(start 141.832107 115.774999)
		(end 141.832106 115.775)
		(width 0.148)
		(layer "In2.Cu")
		(net 455)
	)
	(segment
		(start 182.101 140.65)
		(end 181.852 140.899)
		(width 0.148)
		(layer "In2.Cu")
		(net 455)
	)
	(segment
		(start 157.05 131.7)
		(end 157.05 132.9)
		(width 0.148)
		(layer "In2.Cu")
		(net 455)
	)
	(segment
		(start 133.5 111.75)
		(end 134.7 112.95)
		(width 0.148)
		(layer "In2.Cu")
		(net 455)
	)
	(segment
		(start 182.299001 140)
		(end 182.101 140.198001)
		(width 0.148)
		(layer "In2.Cu")
		(net 455)
	)
	(segment
		(start 142.759692 115.554521)
		(end 142.759692 115.55452)
		(width 0.148)
		(layer "In2.Cu")
		(net 455)
	)
	(segment
		(start 145.367638 120.017638)
		(end 145.367637 120.017637)
		(width 0.148)
		(layer "In2.Cu")
		(net 455)
	)
	(segment
		(start 134.7 112.95)
		(end 138.3 112.95)
		(width 0.148)
		(layer "In2.Cu")
		(net 455)
	)
	(segment
		(start 143.246319 117.189213)
		(end 143.466797 116.968736)
		(width 0.148)
		(layer "In2.Cu")
		(net 455)
	)
	(segment
		(start 181.05 141.225)
		(end 181.05 141.65)
		(width 0.148)
		(layer "In2.Cu")
		(net 455)
	)
	(segment
		(start 180.7 142)
		(end 180.435728 142)
		(width 0.148)
		(layer "In2.Cu")
		(net 455)
	)
	(segment
		(start 147.002311 119.79718)
		(end 147.00231 119.79718)
		(width 0.148)
		(layer "In2.Cu")
		(net 455)
	)
	(segment
		(start 146.781851 121.431851)
		(end 157.05 131.7)
		(width 0.148)
		(layer "In2.Cu")
		(net 455)
	)
	(segment
		(start 142.539212 117.189212)
		(end 142.539213 117.189213)
		(width 0.148)
		(layer "In2.Cu")
		(net 455)
	)
	(segment
		(start 145.588103 118.382964)
		(end 145.588102 118.382963)
		(width 0.148)
		(layer "In2.Cu")
		(net 455)
	)
	(segment
		(start 138.3 112.95)
		(end 141.125 115.775)
		(width 0.148)
		(layer "In2.Cu")
		(net 455)
	)
	(segment
		(start 141.832106 115.775)
		(end 142.052586 115.554521)
		(width 0.148)
		(layer "In2.Cu")
		(net 455)
	)
	(segment
		(start 181.852 140.899)
		(end 181.376 140.899)
		(width 0.148)
		(layer "In2.Cu")
		(net 455)
	)
	(segment
		(start 182.101 140.198001)
		(end 182.101 140.65)
		(width 0.148)
		(layer "In2.Cu")
		(net 455)
	)
	(segment
		(start 142.539213 117.189212)
		(end 142.539212 117.189212)
		(width 0.148)
		(layer "In2.Cu")
		(net 455)
	)
	(segment
		(start 145.588101 119.09007)
		(end 145.588102 119.090069)
		(width 0.148)
		(layer "In2.Cu")
		(net 455)
	)
	(arc
		(start 146.295204 119.797181)
		(mid 146.648757 119.650734)
		(end 147.002311 119.79718)
		(width 0.148)
		(layer "In2.Cu")
		(net 455)
	)
	(arc
		(start 143.466797 116.968736)
		(mid 143.820351 116.82229)
		(end 144.173904 116.968737)
		(width 0.148)
		(layer "In2.Cu")
		(net 455)
	)
	(arc
		(start 143.953426 117.896319)
		(mid 143.80698 118.249873)
		(end 143.953427 118.603426)
		(width 0.148)
		(layer "In2.Cu")
		(net 455)
	)
	(arc
		(start 145.367637 119.310531)
		(mid 145.221191 119.664085)
		(end 145.367638 120.017638)
		(width 0.148)
		(layer "In2.Cu")
		(net 455)
	)
	(arc
		(start 141.125 115.775)
		(mid 141.478554 115.921446)
		(end 141.832107 115.774999)
		(width 0.148)
		(layer "In2.Cu")
		(net 455)
	)
	(arc
		(start 144.173903 116.968735)
		(mid 144.320349 117.322289)
		(end 144.173902 117.675842)
		(width 0.148)
		(layer "In2.Cu")
		(net 455)
	)
	(arc
		(start 142.759692 115.55452)
		(mid 142.906138 115.908074)
		(end 142.759691 116.261627)
		(width 0.148)
		(layer "In2.Cu")
		(net 455)
	)
	(arc
		(start 142.539213 117.189213)
		(mid 142.892767 117.335659)
		(end 143.24632 117.189212)
		(width 0.148)
		(layer "In2.Cu")
		(net 455)
	)
	(arc
		(start 143.953426 118.603426)
		(mid 144.30698 118.749872)
		(end 144.660533 118.603425)
		(width 0.148)
		(layer "In2.Cu")
		(net 455)
	)
	(arc
		(start 147.00231 119.79718)
		(mid 147.148756 120.150734)
		(end 147.002309 120.504287)
		(width 0.148)
		(layer "In2.Cu")
		(net 455)
	)
	(arc
		(start 145.588102 118.382963)
		(mid 145.734548 118.736517)
		(end 145.588101 119.09007)
		(width 0.148)
		(layer "In2.Cu")
		(net 455)
	)
	(arc
		(start 142.539213 116.482106)
		(mid 142.392766 116.835658)
		(end 142.539213 117.189212)
		(width 0.148)
		(layer "In2.Cu")
		(net 455)
	)
	(arc
		(start 142.052586 115.554521)
		(mid 142.406138 115.408074)
		(end 142.759692 115.554521)
		(width 0.148)
		(layer "In2.Cu")
		(net 455)
	)
	(arc
		(start 144.880996 118.382963)
		(mid 145.23455 118.236517)
		(end 145.588103 118.382964)
		(width 0.148)
		(layer "In2.Cu")
		(net 455)
	)
	(arc
		(start 146.781852 120.724745)
		(mid 146.635405 121.078298)
		(end 146.781851 121.431852)
		(width 0.148)
		(layer "In2.Cu")
		(net 455)
	)
	(arc
		(start 145.367639 120.017639)
		(mid 145.721193 120.164085)
		(end 146.074746 120.017638)
		(width 0.148)
		(layer "In2.Cu")
		(net 455)
	)
	(segment
		(start 178.9995 140.9995)
		(end 178.500001 140.5)
		(width 0.256)
		(layer "F.Cu")
		(net 456)
	)
	(segment
		(start 131.802 110.598)
		(end 131.802 109.446)
		(width 0.38)
		(layer "F.Cu")
		(net 456)
	)
	(via
		(at 178.500001 140.5)
		(size 0.45)
		(drill 0.1)
		(layers "F.Cu" "B.Cu")
		(remove_unused_layers yes)
		(keep_end_layers yes)
		(zone_layer_connections)
		(net 456)
	)
	(via
		(at 131.802 109.446)
		(size 0.45)
		(drill 0.1)
		(layers "F.Cu" "B.Cu")
		(remove_unused_layers yes)
		(keep_end_layers yes)
		(zone_layer_connections)
		(net 456)
	)
	(segment
		(start 180.675 140.05)
		(end 180.385728 140.05)
		(width 0.148)
		(layer "In2.Cu")
		(net 456)
	)
	(segment
		(start 181 139.725)
		(end 180.675 140.05)
		(width 0.148)
		(layer "In2.Cu")
		(net 456)
	)
	(segment
		(start 156.55 136.35)
		(end 179.65 136.35)
		(width 0.148)
		(layer "In2.Cu")
		(net 456)
	)
	(segment
		(start 179.65 136.35)
		(end 181 137.7)
		(width 0.148)
		(layer "In2.Cu")
		(net 456)
	)
	(segment
		(start 138.25208 116.602079)
		(end 138.252081 116.602081)
		(width 0.148)
		(layer "In2.Cu")
		(net 456)
	)
	(segment
		(start 136.705104 116.946975)
		(end 136.705105 116.946975)
		(width 0.148)
		(layer "In2.Cu")
		(net 456)
	)
	(segment
		(start 131.802 109.446)
		(end 132.5 110.144)
		(width 0.148)
		(layer "In2.Cu")
		(net 456)
	)
	(segment
		(start 132.5 113.4)
		(end 134.25 115.15)
		(width 0.148)
		(layer "In2.Cu")
		(net 456)
	)
	(segment
		(start 154.8 133.15)
		(end 154.8 134.6)
		(width 0.148)
		(layer "In2.Cu")
		(net 456)
	)
	(segment
		(start 178.899001 140.899)
		(end 178.500001 140.5)
		(width 0.148)
		(layer "In2.Cu")
		(net 456)
	)
	(segment
		(start 134.25 115.15)
		(end 136.8 115.15)
		(width 0.148)
		(layer "In2.Cu")
		(net 456)
	)
	(segment
		(start 179.751 140.899)
		(end 178.899001 140.899)
		(width 0.148)
		(layer "In2.Cu")
		(net 456)
	)
	(segment
		(start 138.508161 118.149121)
		(end 138.85312 117.804161)
		(width 0.148)
		(layer "In2.Cu")
		(net 456)
	)
	(segment
		(start 180.385728 140.05)
		(end 180.101 140.334728)
		(width 0.148)
		(layer "In2.Cu")
		(net 456)
	)
	(segment
		(start 139.454161 117.80416)
		(end 139.454161 117.804161)
		(width 0.148)
		(layer "In2.Cu")
		(net 456)
	)
	(segment
		(start 154.8 134.6)
		(end 156.55 136.35)
		(width 0.148)
		(layer "In2.Cu")
		(net 456)
	)
	(segment
		(start 181 137.7)
		(end 181 139.725)
		(width 0.148)
		(layer "In2.Cu")
		(net 456)
	)
	(segment
		(start 180.101 140.334728)
		(end 180.101 140.549)
		(width 0.148)
		(layer "In2.Cu")
		(net 456)
	)
	(segment
		(start 136.8 115.15)
		(end 137.05 115.4)
		(width 0.148)
		(layer "In2.Cu")
		(net 456)
	)
	(segment
		(start 137.907119 118.149122)
		(end 137.90712 118.149122)
		(width 0.148)
		(layer "In2.Cu")
		(net 456)
	)
	(segment
		(start 138.25208 117.203122)
		(end 137.90712 117.548081)
		(width 0.148)
		(layer "In2.Cu")
		(net 456)
	)
	(segment
		(start 132.5 110.144)
		(end 132.5 113.4)
		(width 0.148)
		(layer "In2.Cu")
		(net 456)
	)
	(segment
		(start 180.101 140.549)
		(end 179.751 140.899)
		(width 0.148)
		(layer "In2.Cu")
		(net 456)
	)
	(segment
		(start 137.049999 116.001041)
		(end 136.705105 116.345934)
		(width 0.148)
		(layer "In2.Cu")
		(net 456)
	)
	(segment
		(start 137.306146 116.946974)
		(end 137.651039 116.60208)
		(width 0.148)
		(layer "In2.Cu")
		(net 456)
	)
	(segment
		(start 139.454161 117.804161)
		(end 154.8 133.15)
		(width 0.148)
		(layer "In2.Cu")
		(net 456)
	)
	(arc
		(start 136.705105 116.946975)
		(mid 137.005626 117.071454)
		(end 137.306146 116.946974)
		(width 0.148)
		(layer "In2.Cu")
		(net 456)
	)
	(arc
		(start 138.252081 116.602081)
		(mid 138.37656 116.902602)
		(end 138.25208 117.203122)
		(width 0.148)
		(layer "In2.Cu")
		(net 456)
	)
	(arc
		(start 136.705105 116.345934)
		(mid 136.580625 116.646454)
		(end 136.705104 116.946975)
		(width 0.148)
		(layer "In2.Cu")
		(net 456)
	)
	(arc
		(start 137.651039 116.60208)
		(mid 137.951559 116.4776)
		(end 138.25208 116.602079)
		(width 0.148)
		(layer "In2.Cu")
		(net 456)
	)
	(arc
		(start 137.05 115.4)
		(mid 137.174479 115.700521)
		(end 137.049999 116.001041)
		(width 0.148)
		(layer "In2.Cu")
		(net 456)
	)
	(arc
		(start 138.85312 117.804161)
		(mid 139.15364 117.679681)
		(end 139.454161 117.80416)
		(width 0.148)
		(layer "In2.Cu")
		(net 456)
	)
	(arc
		(start 137.90712 117.548081)
		(mid 137.78264 117.848601)
		(end 137.907119 118.149122)
		(width 0.148)
		(layer "In2.Cu")
		(net 456)
	)
	(arc
		(start 137.90712 118.149122)
		(mid 138.207641 118.273601)
		(end 138.508161 118.149121)
		(width 0.148)
		(layer "In2.Cu")
		(net 456)
	)
	(segment
		(start 185.999499 146.9995)
		(end 185.5 146.5)
		(width 0.256)
		(layer "F.Cu")
		(net 457)
	)
	(segment
		(start 158.15 110.598)
		(end 158.15 111.75)
		(width 0.38)
		(layer "F.Cu")
		(net 457)
	)
	(via
		(at 185.5 146.5)
		(size 0.45)
		(drill 0.1)
		(layers "F.Cu" "B.Cu")
		(remove_unused_layers yes)
		(keep_end_layers yes)
		(zone_layer_connections)
		(net 457)
	)
	(via
		(at 158.15 111.75)
		(size 0.45)
		(drill 0.1)
		(layers "F.Cu" "B.Cu")
		(remove_unused_layers yes)
		(keep_end_layers yes)
		(zone_layer_connections)
		(net 457)
	)
	(segment
		(start 186.139 145.9)
		(end 188.083578 145.9)
		(width 0.1)
		(layer "In2.Cu")
		(net 457)
	)
	(segment
		(start 165.42 118.357485)
		(end 165.42 118.025)
		(width 0.13)
		(layer "In2.Cu")
		(net 457)
	)
	(segment
		(start 176.725294 117.67)
		(end 180.33 121.274706)
		(width 0.13)
		(layer "In2.Cu")
		(net 457)
	)
	(segment
		(start 171.83 118.025)
		(end 171.83 118.357485)
		(width 0.13)
		(layer "In2.Cu")
		(net 457)
	)
	(segment
		(start 180.33 124.117636)
		(end 189.87648 133.664116)
		(width 0.13)
		(layer "In2.Cu")
		(net 457)
	)
	(segment
		(start 185.883112 146.155888)
		(end 186.139 145.9)
		(width 0.1)
		(layer "In2.Cu")
		(net 457)
	)
	(segment
		(start 180.33 121.274706)
		(end 180.33 124.117636)
		(width 0.13)
		(layer "In2.Cu")
		(net 457)
	)
	(segment
		(start 157.97381 111.155917)
		(end 158.336211 111.155917)
		(width 0.13)
		(layer "In2.Cu")
		(net 457)
	)
	(segment
		(start 157.845 111.284727)
		(end 157.97381 111.155917)
		(width 0.13)
		(layer "In2.Cu")
		(net 457)
	)
	(segment
		(start 157.73 113.067816)
		(end 157.73 114.174706)
		(width 0.13)
		(layer "In2.Cu")
		(net 457)
	)
	(segment
		(start 173.375 117.67)
		(end 175.565307 117.67)
		(width 0.13)
		(layer "In2.Cu")
		(net 457)
	)
	(segment
		(start 157.735734 112.60246)
		(end 157.771089 112.637815)
		(width 0.13)
		(layer "In2.Cu")
		(net 457)
	)
	(segment
		(start 188.083578 145.9)
		(end 188.9 145.083578)
		(width 0.1)
		(layer "In2.Cu")
		(net 457)
	)
	(segment
		(start 189.9 142.158578)
		(end 189.9 138.684033)
		(width 0.1)
		(layer "In2.Cu")
		(net 457)
	)
	(segment
		(start 168.03 118.025)
		(end 168.03 118.357485)
		(width 0.13)
		(layer "In2.Cu")
		(net 457)
	)
	(segment
		(start 158.159998 112.248908)
		(end 158.159999 112.248908)
		(width 0.13)
		(layer "In2.Cu")
		(net 457)
	)
	(segment
		(start 158.655 111.474706)
		(end 158.655 112.142816)
		(width 0.13)
		(layer "In2.Cu")
		(net 457)
	)
	(segment
		(start 185.5 146.5)
		(end 185.838677 146.5)
		(width 0.1)
		(layer "In2.Cu")
		(net 457)
	)
	(segment
		(start 157.845 111.445)
		(end 157.845 111.284727)
		(width 0.13)
		(layer "In2.Cu")
		(net 457)
	)
	(segment
		(start 158.336211 111.155917)
		(end 158.655 111.474706)
		(width 0.13)
		(layer "In2.Cu")
		(net 457)
	)
	(segment
		(start 185.838677 146.5)
		(end 185.883112 146.455565)
		(width 0.1)
		(layer "In2.Cu")
		(net 457)
	)
	(segment
		(start 173.02 118.357485)
		(end 173.02 118.025)
		(width 0.13)
		(layer "In2.Cu")
		(net 457)
	)
	(segment
		(start 169.22 118.357485)
		(end 169.22 118.025)
		(width 0.13)
		(layer "In2.Cu")
		(net 457)
	)
	(segment
		(start 157.771088 113.026724)
		(end 157.73 113.067816)
		(width 0.13)
		(layer "In2.Cu")
		(net 457)
	)
	(segment
		(start 157.735734 112.213553)
		(end 157.735734 112.213552)
		(width 0.13)
		(layer "In2.Cu")
		(net 457)
	)
	(segment
		(start 185.883112 146.455565)
		(end 185.883112 146.155888)
		(width 0.1)
		(layer "In2.Cu")
		(net 457)
	)
	(segment
		(start 188.9 143.158578)
		(end 189.9 142.158578)
		(width 0.1)
		(layer "In2.Cu")
		(net 457)
	)
	(segment
		(start 175.565307 117.67)
		(end 176.725294 117.67)
		(width 0.13)
		(layer "In2.Cu")
		(net 457)
	)
	(segment
		(start 171.12 118.357511)
		(end 171.12 118.025)
		(width 0.13)
		(layer "In2.Cu")
		(net 457)
	)
	(segment
		(start 189.87648 133.664116)
		(end 189.87648 138.660513)
		(width 0.13)
		(layer "In2.Cu")
		(net 457)
	)
	(segment
		(start 158.655 112.142816)
		(end 158.548908 112.248908)
		(width 0.13)
		(layer "In2.Cu")
		(net 457)
	)
	(segment
		(start 189.9 138.684033)
		(end 189.87648 138.660513)
		(width 0.1)
		(layer "In2.Cu")
		(net 457)
	)
	(segment
		(start 157.73 114.174706)
		(end 161.225294 117.67)
		(width 0.13)
		(layer "In2.Cu")
		(net 457)
	)
	(segment
		(start 166.13 118.025)
		(end 166.13 118.357511)
		(width 0.13)
		(layer "In2.Cu")
		(net 457)
	)
	(segment
		(start 169.93 118.025)
		(end 169.93 118.357511)
		(width 0.13)
		(layer "In2.Cu")
		(net 457)
	)
	(segment
		(start 164.23 118.025)
		(end 164.23 118.357485)
		(width 0.13)
		(layer "In2.Cu")
		(net 457)
	)
	(segment
		(start 158.159999 112.248908)
		(end 158.124643 112.213552)
		(width 0.13)
		(layer "In2.Cu")
		(net 457)
	)
	(segment
		(start 162.33 118.025)
		(end 162.33 118.357511)
		(width 0.13)
		(layer "In2.Cu")
		(net 457)
	)
	(segment
		(start 167.32 118.357511)
		(end 167.32 118.025)
		(width 0.13)
		(layer "In2.Cu")
		(net 457)
	)
	(segment
		(start 158.15 111.75)
		(end 157.845 111.445)
		(width 0.13)
		(layer "In2.Cu")
		(net 457)
	)
	(segment
		(start 161.225294 117.67)
		(end 161.975 117.67)
		(width 0.13)
		(layer "In2.Cu")
		(net 457)
	)
	(segment
		(start 188.9 145.083578)
		(end 188.9 143.158578)
		(width 0.1)
		(layer "In2.Cu")
		(net 457)
	)
	(segment
		(start 163.52 118.357511)
		(end 163.52 118.025)
		(width 0.13)
		(layer "In2.Cu")
		(net 457)
	)
	(arc
		(start 164.23 118.357485)
		(mid 164.404271 118.778214)
		(end 164.825 118.952485)
		(width 0.13)
		(layer "In2.Cu")
		(net 457)
	)
	(arc
		(start 165.42 118.025)
		(mid 165.523977 117.773977)
		(end 165.775 117.67)
		(width 0.13)
		(layer "In2.Cu")
		(net 457)
	)
	(arc
		(start 169.22 118.025)
		(mid 169.323977 117.773977)
		(end 169.575 117.67)
		(width 0.13)
		(layer "In2.Cu")
		(net 457)
	)
	(arc
		(start 171.475 117.67)
		(mid 171.726023 117.773977)
		(end 171.83 118.025)
		(width 0.13)
		(layer "In2.Cu")
		(net 457)
	)
	(arc
		(start 169.93 118.357511)
		(mid 170.104271 118.77824)
		(end 170.525 118.952511)
		(width 0.13)
		(layer "In2.Cu")
		(net 457)
	)
	(arc
		(start 168.03 118.357485)
		(mid 168.204271 118.778214)
		(end 168.625 118.952485)
		(width 0.13)
		(layer "In2.Cu")
		(net 457)
	)
	(arc
		(start 169.575 117.67)
		(mid 169.826023 117.773977)
		(end 169.93 118.025)
		(width 0.13)
		(layer "In2.Cu")
		(net 457)
	)
	(arc
		(start 163.875 117.67)
		(mid 164.126023 117.773977)
		(end 164.23 118.025)
		(width 0.13)
		(layer "In2.Cu")
		(net 457)
	)
	(arc
		(start 162.33 118.357511)
		(mid 162.504271 118.77824)
		(end 162.925 118.952511)
		(width 0.13)
		(layer "In2.Cu")
		(net 457)
	)
	(arc
		(start 173.02 118.025)
		(mid 173.123977 117.773977)
		(end 173.375 117.67)
		(width 0.13)
		(layer "In2.Cu")
		(net 457)
	)
	(arc
		(start 163.52 118.025)
		(mid 163.623977 117.773977)
		(end 163.875 117.67)
		(width 0.13)
		(layer "In2.Cu")
		(net 457)
	)
	(arc
		(start 170.525 118.952511)
		(mid 170.945729 118.77824)
		(end 171.12 118.357511)
		(width 0.13)
		(layer "In2.Cu")
		(net 457)
	)
	(arc
		(start 157.771089 112.637815)
		(mid 157.851634 112.83227)
		(end 157.771088 113.026724)
		(width 0.13)
		(layer "In2.Cu")
		(net 457)
	)
	(arc
		(start 167.32 118.025)
		(mid 167.423977 117.773977)
		(end 167.675 117.67)
		(width 0.13)
		(layer "In2.Cu")
		(net 457)
	)
	(arc
		(start 172.425 118.952485)
		(mid 172.845729 118.778214)
		(end 173.02 118.357485)
		(width 0.13)
		(layer "In2.Cu")
		(net 457)
	)
	(arc
		(start 157.735734 112.213552)
		(mid 157.655189 112.408006)
		(end 157.735734 112.60246)
		(width 0.13)
		(layer "In2.Cu")
		(net 457)
	)
	(arc
		(start 171.83 118.357485)
		(mid 172.004271 118.778214)
		(end 172.425 118.952485)
		(width 0.13)
		(layer "In2.Cu")
		(net 457)
	)
	(arc
		(start 164.825 118.952485)
		(mid 165.245729 118.778214)
		(end 165.42 118.357485)
		(width 0.13)
		(layer "In2.Cu")
		(net 457)
	)
	(arc
		(start 158.124643 112.213552)
		(mid 157.930188 112.133007)
		(end 157.735734 112.213553)
		(width 0.13)
		(layer "In2.Cu")
		(net 457)
	)
	(arc
		(start 171.12 118.025)
		(mid 171.223977 117.773977)
		(end 171.475 117.67)
		(width 0.13)
		(layer "In2.Cu")
		(net 457)
	)
	(arc
		(start 161.975 117.67)
		(mid 162.226023 117.773977)
		(end 162.33 118.025)
		(width 0.13)
		(layer "In2.Cu")
		(net 457)
	)
	(arc
		(start 158.548908 112.248908)
		(mid 158.354453 112.329454)
		(end 158.159998 112.248908)
		(width 0.13)
		(layer "In2.Cu")
		(net 457)
	)
	(arc
		(start 166.13 118.357511)
		(mid 166.304271 118.77824)
		(end 166.725 118.952511)
		(width 0.13)
		(layer "In2.Cu")
		(net 457)
	)
	(arc
		(start 167.675 117.67)
		(mid 167.926023 117.773977)
		(end 168.03 118.025)
		(width 0.13)
		(layer "In2.Cu")
		(net 457)
	)
	(arc
		(start 166.725 118.952511)
		(mid 167.145729 118.77824)
		(end 167.32 118.357511)
		(width 0.13)
		(layer "In2.Cu")
		(net 457)
	)
	(arc
		(start 162.925 118.952511)
		(mid 163.345729 118.77824)
		(end 163.52 118.357511)
		(width 0.13)
		(layer "In2.Cu")
		(net 457)
	)
	(arc
		(start 168.625 118.952485)
		(mid 169.045729 118.778214)
		(end 169.22 118.357485)
		(width 0.13)
		(layer "In2.Cu")
		(net 457)
	)
	(arc
		(start 165.775 117.67)
		(mid 166.026023 117.773977)
		(end 166.13 118.025)
		(width 0.13)
		(layer "In2.Cu")
		(net 457)
	)
	(segment
		(start 178.5 145.499999)
		(end 178.9995 145.9995)
		(width 0.256)
		(layer "F.Cu")
		(net 458)
	)
	(via
		(at 178.5 145.499999)
		(size 0.45)
		(drill 0.1)
		(layers "F.Cu" "B.Cu")
		(remove_unused_layers yes)
		(keep_end_layers yes)
		(zone_layer_connections)
		(net 458)
	)
	(segment
		(start 177.416775 145.899999)
		(end 177.605998 145.899999)
		(width 0.1)
		(layer "B.Cu")
		(net 458)
	)
	(segment
		(start 178.5025 145.499999)
		(end 178.5 145.499999)
		(width 0.256)
		(layer "B.Cu")
		(net 458)
	)
	(segment
		(start 176.89 146.426774)
		(end 176.89 147.648576)
		(width 0.1)
		(layer "B.Cu")
		(net 458)
	)
	(segment
		(start 178.449313 145.550686)
		(end 178.5 145.499999)
		(width 0.1)
		(layer "B.Cu")
		(net 458)
	)
	(segment
		(start 173.85 148.754491)
		(end 173.85 149.183723)
		(width 0.16)
		(layer "B.Cu")
		(net 458)
	)
	(segment
		(start 178.506769 145.49823)
		(end 179 145.005)
		(width 0.256)
		(layer "B.Cu")
		(net 458)
	)
	(segment
		(start 174.998625 147.889999)
		(end 176.648577 147.889999)
		(width 0.1)
		(layer "B.Cu")
		(net 458)
	)
	(segment
		(start 174.181978 148.048817)
		(end 174.114242 148.116553)
		(width 0.16)
		(layer "B.Cu")
		(net 458)
	)
	(segment
		(start 174.907638 147.852311)
		(end 174.656386 147.852311)
		(width 0.16)
		(layer "B.Cu")
		(net 458)
	)
	(segment
		(start 173.53 149.956272)
		(end 173.53 150.209999)
		(width 0.16)
		(layer "B.Cu")
		(net 458)
	)
	(arc
		(start 174.953132 147.871155)
		(mid 174.974004 147.885101)
		(end 174.998625 147.889999)
		(width 0.1)
		(layer "B.Cu")
		(net 458)
	)
	(arc
		(start 178.506769 145.49823)
		(mid 178.50481 145.499539)
		(end 178.5025 145.499999)
		(width 0.256)
		(layer "B.Cu")
		(net 458)
	)
	(arc
		(start 178.449313 145.550686)
		(mid 178.062397 145.809215)
		(end 177.605998 145.899999)
		(width 0.1)
		(layer "B.Cu")
		(net 458)
	)
	(arc
		(start 173.85 149.183723)
		(mid 173.808417 149.392773)
		(end 173.69 149.569998)
		(width 0.16)
		(layer "B.Cu")
		(net 458)
	)
	(arc
		(start 176.89 146.426774)
		(mid 176.930098 146.225186)
		(end 177.044289 146.054288)
		(width 0.1)
		(layer "B.Cu")
		(net 458)
	)
	(arc
		(start 173.85 148.754491)
		(mid 173.918674 148.409241)
		(end 174.114242 148.116553)
		(width 0.16)
		(layer "B.Cu")
		(net 458)
	)
	(arc
		(start 177.416775 145.899999)
		(mid 177.215187 145.940097)
		(end 177.044289 146.054288)
		(width 0.1)
		(layer "B.Cu")
		(net 458)
	)
	(arc
		(start 174.181978 148.048817)
		(mid 174.399638 147.903381)
		(end 174.656386 147.852311)
		(width 0.16)
		(layer "B.Cu")
		(net 458)
	)
	(arc
		(start 176.819289 147.819288)
		(mid 176.740965 147.871621)
		(end 176.648577 147.889999)
		(width 0.1)
		(layer "B.Cu")
		(net 458)
	)
	(arc
		(start 176.819289 147.819288)
		(mid 176.871622 147.740964)
		(end 176.89 147.648576)
		(width 0.1)
		(layer "B.Cu")
		(net 458)
	)
	(arc
		(start 173.53 149.956272)
		(mid 173.571582 149.747222)
		(end 173.69 149.569998)
		(width 0.16)
		(layer "B.Cu")
		(net 458)
	)
	(arc
		(start 174.907638 147.852311)
		(mid 174.932259 147.857208)
		(end 174.953132 147.871155)
		(width 0.1)
		(layer "B.Cu")
		(net 458)
	)
	(segment
		(start 248.251 106)
		(end 248.251 107.152)
		(width 0.38)
		(layer "F.Cu")
		(net 459)
	)
	(segment
		(start 237.126499 134.108)
		(end 236.147 134.108)
		(width 0.177)
		(layer "F.Cu")
		(net 459)
	)
	(segment
		(start 236.147 134.108)
		(end 236.14 134.101)
		(width 0.177)
		(layer "F.Cu")
		(net 459)
	)
	(via
		(at 248.251 107.152)
		(size 0.45)
		(drill 0.1)
		(layers "F.Cu" "B.Cu")
		(remove_unused_layers yes)
		(keep_end_layers yes)
		(zone_layer_connections)
		(net 459)
	)
	(via
		(at 236.14 134.101)
		(size 0.45)
		(drill 0.1)
		(layers "F.Cu" "B.Cu")
		(remove_unused_layers yes)
		(keep_end_layers yes)
		(zone_layer_connections)
		(net 459)
	)
	(segment
		(start 236.14 134.101)
		(end 235.759 134.101)
		(width 0.198)
		(layer "B.Cu")
		(net 459)
	)
	(segment
		(start 235.759 134.101)
		(end 235.59 134.27)
		(width 0.198)
		(layer "B.Cu")
		(net 459)
	)
	(segment
		(start 247.923 107.152)
		(end 248.251 107.152)
		(width 0.15)
		(layer "In4.Cu")
		(net 459)
	)
	(segment
		(start 238.4 129.15)
		(end 246.4 121.15)
		(width 0.15)
		(layer "In4.Cu")
		(net 459)
	)
	(segment
		(start 235.55 133.26)
		(end 238.4 130.41)
		(width 0.15)
		(layer "In4.Cu")
		(net 459)
	)
	(segment
		(start 246 109.075)
		(end 247.923 107.152)
		(width 0.15)
		(layer "In4.Cu")
		(net 459)
	)
	(segment
		(start 235.55 133.9)
		(end 235.55 133.26)
		(width 0.15)
		(layer "In4.Cu")
		(net 459)
	)
	(segment
		(start 238.4 130.41)
		(end 238.4 129.15)
		(width 0.15)
		(layer "In4.Cu")
		(net 459)
	)
	(segment
		(start 246.4 121.15)
		(end 246.4 111.175)
		(width 0.15)
		(layer "In4.Cu")
		(net 459)
	)
	(segment
		(start 236.14 134.101)
		(end 235.751 134.101)
		(width 0.15)
		(layer "In4.Cu")
		(net 459)
	)
	(segment
		(start 246.4 111.175)
		(end 246 110.775)
		(width 0.15)
		(layer "In4.Cu")
		(net 459)
	)
	(segment
		(start 235.751 134.101)
		(end 235.55 133.9)
		(width 0.15)
		(layer "In4.Cu")
		(net 459)
	)
	(segment
		(start 246 110.775)
		(end 246 109.075)
		(width 0.15)
		(layer "In4.Cu")
		(net 459)
	)
	(segment
		(start 237.126499 133.457)
		(end 236.147 133.457)
		(width 0.177)
		(layer "F.Cu")
		(net 460)
	)
	(segment
		(start 236.147 133.457)
		(end 236.14 133.45)
		(width 0.177)
		(layer "F.Cu")
		(net 460)
	)
	(segment
		(start 249.1 106)
		(end 249.1 104.848)
		(width 0.38)
		(layer "F.Cu")
		(net 460)
	)
	(via
		(at 236.14 133.45)
		(size 0.45)
		(drill 0.1)
		(layers "F.Cu" "B.Cu")
		(remove_unused_layers yes)
		(keep_end_layers yes)
		(zone_layer_connections)
		(net 460)
	)
	(via
		(at 249.1 104.848)
		(size 0.45)
		(drill 0.1)
		(layers "F.Cu" "B.Cu")
		(remove_unused_layers yes)
		(keep_end_layers yes)
		(zone_layer_connections)
		(net 460)
	)
	(segment
		(start 235.739998 133.45)
		(end 235.579999 133.290001)
		(width 0.198)
		(layer "B.Cu")
		(net 460)
	)
	(segment
		(start 236.14 133.45)
		(end 235.739998 133.45)
		(width 0.198)
		(layer "B.Cu")
		(net 460)
	)
	(segment
		(start 236.525 133.45)
		(end 240 129.975)
		(width 0.15)
		(layer "In4.Cu")
		(net 460)
	)
	(segment
		(start 247.4 121.65)
		(end 247.4 110.45)
		(width 0.15)
		(layer "In4.Cu")
		(net 460)
	)
	(segment
		(start 247.4 110.45)
		(end 249.1 108.75)
		(width 0.15)
		(layer "In4.Cu")
		(net 460)
	)
	(segment
		(start 249.1 108.75)
		(end 249.1 104.848)
		(width 0.15)
		(layer "In4.Cu")
		(net 460)
	)
	(segment
		(start 236.14 133.45)
		(end 236.525 133.45)
		(width 0.15)
		(layer "In4.Cu")
		(net 460)
	)
	(segment
		(start 240 129.05)
		(end 247.4 121.65)
		(width 0.15)
		(layer "In4.Cu")
		(net 460)
	)
	(segment
		(start 240 129.975)
		(end 240 129.05)
		(width 0.15)
		(layer "In4.Cu")
		(net 460)
	)
	(segment
		(start 249.1 110.598)
		(end 249.1 111.75)
		(width 0.38)
		(layer "F.Cu")
		(net 461)
	)
	(via
		(at 249.1 111.75)
		(size 0.45)
		(drill 0.1)
		(layers "F.Cu" "B.Cu")
		(remove_unused_layers yes)
		(keep_end_layers yes)
		(zone_layer_connections)
		(net 461)
	)
	(segment
		(start 248.875 110.625)
		(end 249.1 110.85)
		(width 0.198)
		(layer "B.Cu")
		(net 461)
	)
	(segment
		(start 249.1 110.85)
		(end 249.1 111.75)
		(width 0.198)
		(layer "B.Cu")
		(net 461)
	)
	(segment
		(start 248.325 110.625)
		(end 248.875 110.625)
		(width 0.198)
		(layer "B.Cu")
		(net 461)
	)
	(segment
		(start 195.0005 154.0005)
		(end 195.5 154.5)
		(width 0.256)
		(layer "F.Cu")
		(net 462)
	)
	(via
		(at 195.5 154.5)
		(size 0.45)
		(drill 0.1)
		(layers "F.Cu" "B.Cu")
		(remove_unused_layers yes)
		(keep_end_layers yes)
		(zone_layer_connections)
		(net 462)
	)
	(segment
		(start 195.999 154.001)
		(end 195.5 154.5)
		(width 0.201)
		(layer "B.Cu")
		(net 462)
	)
	(segment
		(start 197 154)
		(end 195.999 154)
		(width 0.256)
		(layer "B.Cu")
		(net 462)
	)
	(segment
		(start 195.999 154)
		(end 195.999 154.001)
		(width 0.201)
		(layer "B.Cu")
		(net 462)
	)
	(segment
		(start 175.9995 163.0005)
		(end 175.5 163.5)
		(width 0.256)
		(layer "F.Cu")
		(net 463)
	)
	(via
		(at 175.5 163.5)
		(size 0.45)
		(drill 0.1)
		(layers "F.Cu" "B.Cu")
		(remove_unused_layers yes)
		(keep_end_layers yes)
		(zone_layer_connections)
		(net 463)
	)
	(segment
		(start 175.9995 162.0005)
		(end 175.5 162.5)
		(width 0.256)
		(layer "F.Cu")
		(net 464)
	)
	(via
		(at 175.5 162.5)
		(size 0.45)
		(drill 0.1)
		(layers "F.Cu" "B.Cu")
		(remove_unused_layers yes)
		(keep_end_layers yes)
		(zone_layer_connections)
		(net 464)
	)
	(segment
		(start 242.404997 133.457)
		(end 242.411998 133.464)
		(width 0.177)
		(layer "F.Cu")
		(net 465)
	)
	(segment
		(start 194.0005 150.999501)
		(end 194.5 150.5)
		(width 0.256)
		(layer "F.Cu")
		(net 465)
	)
	(segment
		(start 241.425499 133.457)
		(end 242.404997 133.457)
		(width 0.177)
		(layer "F.Cu")
		(net 465)
	)
	(segment
		(start 237.082499 182.007)
		(end 237.902499 182.007)
		(width 0.177)
		(layer "F.Cu")
		(net 465)
	)
	(segment
		(start 236.624499 181.549)
		(end 237.082499 182.007)
		(width 0.177)
		(layer "F.Cu")
		(net 465)
	)
	(via
		(at 194.5 150.5)
		(size 0.45)
		(drill 0.1)
		(layers "F.Cu" "B.Cu")
		(remove_unused_layers yes)
		(keep_end_layers yes)
		(zone_layer_connections)
		(net 465)
	)
	(via
		(at 236.624499 181.549)
		(size 0.45)
		(drill 0.1)
		(layers "F.Cu" "B.Cu")
		(remove_unused_layers yes)
		(keep_end_layers yes)
		(zone_layer_connections)
		(net 465)
	)
	(via
		(at 242.411998 133.464)
		(size 0.45)
		(drill 0.1)
		(layers "F.Cu" "B.Cu")
		(remove_unused_layers yes)
		(keep_end_layers yes)
		(zone_layer_connections)
		(net 465)
	)
	(segment
		(start 242.411998 133.464)
		(end 242.846 133.464)
		(width 0.198)
		(layer "B.Cu")
		(net 465)
	)
	(segment
		(start 237.939499 179.449)
		(end 237.524499 179.449)
		(width 0.15)
		(layer "B.Cu")
		(net 465)
	)
	(segment
		(start 236.624499 180.349)
		(end 236.624499 181.549)
		(width 0.15)
		(layer "B.Cu")
		(net 465)
	)
	(segment
		(start 242.846 133.464)
		(end 242.97 133.34)
		(width 0.198)
		(layer "B.Cu")
		(net 465)
	)
	(segment
		(start 237.524499 179.449)
		(end 236.624499 180.349)
		(width 0.15)
		(layer "B.Cu")
		(net 465)
	)
	(segment
		(start 236.576999 164.451999)
		(end 236.576999 181.5015)
		(width 0.1)
		(layer "In4.Cu")
		(net 465)
	)
	(segment
		(start 248.444669 143.05)
		(end 248.068669 142.674)
		(width 0.1)
		(layer "In4.Cu")
		(net 465)
	)
	(segment
		(start 234.26 134.5)
		(end 222.31 146.45)
		(width 0.1)
		(layer "In4.Cu")
		(net 465)
	)
	(segment
		(start 259.126 139.64133)
		(end 257.89233 140.875)
		(width 0.1)
		(layer "In4.Cu")
		(net 465)
	)
	(segment
		(start 202 150.875)
		(end 194.875 150.875)
		(width 0.1)
		(layer "In4.Cu")
		(net 465)
	)
	(segment
		(start 258.906331 135.049999)
		(end 259.126 135.269668)
		(width 0.1)
		(layer "In4.Cu")
		(net 465)
	)
	(segment
		(start 242.411998 133.464)
		(end 238.914997 133.464)
		(width 0.1)
		(layer "In4.Cu")
		(net 465)
	)
	(segment
		(start 249.2635 133.7365)
		(end 247.857 132.33)
		(width 0.1)
		(layer "In4.Cu")
		(net 465)
	)
	(segment
		(start 234.25 162.125)
		(end 236.576999 164.451999)
		(width 0.1)
		(layer "In4.Cu")
		(net 465)
	)
	(segment
		(start 248.755331 143.05)
		(end 248.444669 143.05)
		(width 0.1)
		(layer "In4.Cu")
		(net 465)
	)
	(segment
		(start 236.576999 181.5015)
		(end 236.624499 181.549)
		(width 0.1)
		(layer "In4.Cu")
		(net 465)
	)
	(segment
		(start 194.875 150.875)
		(end 194.5 150.5)
		(width 0.1)
		(layer "In4.Cu")
		(net 465)
	)
	(segment
		(start 259.126 135.269668)
		(end 259.126 139.64133)
		(width 0.1)
		(layer "In4.Cu")
		(net 465)
	)
	(segment
		(start 208.5 148.5)
		(end 208.1 148.9)
		(width 0.1)
		(layer "In4.Cu")
		(net 465)
	)
	(segment
		(start 234.25 148.180331)
		(end 234.25 162.125)
		(width 0.1)
		(layer "In4.Cu")
		(net 465)
	)
	(segment
		(start 250.3385 134.8115)
		(end 252.26733 134.8115)
		(width 0.1)
		(layer "In4.Cu")
		(net 465)
	)
	(segment
		(start 237.878997 134.5)
		(end 234.26 134.5)
		(width 0.1)
		(layer "In4.Cu")
		(net 465)
	)
	(segment
		(start 250.930331 140.875)
		(end 248.755331 143.05)
		(width 0.1)
		(layer "In4.Cu")
		(net 465)
	)
	(segment
		(start 257.89233 140.875)
		(end 250.930331 140.875)
		(width 0.1)
		(layer "In4.Cu")
		(net 465)
	)
	(segment
		(start 239.756331 142.674)
		(end 234.25 148.180331)
		(width 0.1)
		(layer "In4.Cu")
		(net 465)
	)
	(segment
		(start 242.411998 132.968002)
		(end 242.411998 133.464)
		(width 0.1)
		(layer "In4.Cu")
		(net 465)
	)
	(segment
		(start 219.35 146.45)
		(end 217.3 148.5)
		(width 0.1)
		(layer "In4.Cu")
		(net 465)
	)
	(segment
		(start 203.975 148.9)
		(end 202 150.875)
		(width 0.1)
		(layer "In4.Cu")
		(net 465)
	)
	(segment
		(start 252.26733 134.8115)
		(end 252.505829 135.049999)
		(width 0.1)
		(layer "In4.Cu")
		(net 465)
	)
	(segment
		(start 238.914997 133.464)
		(end 237.878997 134.5)
		(width 0.1)
		(layer "In4.Cu")
		(net 465)
	)
	(segment
		(start 217.3 148.5)
		(end 208.5 148.5)
		(width 0.1)
		(layer "In4.Cu")
		(net 465)
	)
	(segment
		(start 243.05 132.33)
		(end 242.411998 132.968002)
		(width 0.1)
		(layer "In4.Cu")
		(net 465)
	)
	(segment
		(start 249.2635 133.7365)
		(end 250.3385 134.8115)
		(width 0.1)
		(layer "In4.Cu")
		(net 465)
	)
	(segment
		(start 222.31 146.45)
		(end 219.35 146.45)
		(width 0.1)
		(layer "In4.Cu")
		(net 465)
	)
	(segment
		(start 247.857 132.33)
		(end 243.05 132.33)
		(width 0.1)
		(layer "In4.Cu")
		(net 465)
	)
	(segment
		(start 208.1 148.9)
		(end 203.975 148.9)
		(width 0.1)
		(layer "In4.Cu")
		(net 465)
	)
	(segment
		(start 252.505829 135.049999)
		(end 258.906331 135.049999)
		(width 0.1)
		(layer "In4.Cu")
		(net 465)
	)
	(segment
		(start 248.068669 142.674)
		(end 239.756331 142.674)
		(width 0.1)
		(layer "In4.Cu")
		(net 465)
	)
	(segment
		(start 198.0005 151.9995)
		(end 198.5 151.500001)
		(width 0.256)
		(layer "F.Cu")
		(net 466)
	)
	(via
		(at 198.5 151.500001)
		(size 0.45)
		(drill 0.1)
		(layers "F.Cu" "B.Cu")
		(remove_unused_layers yes)
		(keep_end_layers yes)
		(zone_layer_connections)
		(net 466)
	)
	(segment
		(start 113.917499 176.867)
		(end 114.6155 176.867)
		(width 0.201)
		(layer "F.Cu")
		(net 467)
	)
	(segment
		(start 114.6155 176.867)
		(end 115.086 177.3375)
		(width 0.201)
		(layer "F.Cu")
		(net 467)
	)
	(segment
		(start 109.375 176.7685)
		(end 113.917499 176.7685)
		(width 0.201)
		(layer "F.Cu")
		(net 467)
	)
	(segment
		(start 122.076 184.778)
		(end 122.076 185.692)
		(width 0.201)
		(layer "F.Cu")
		(net 467)
	)
	(segment
		(start 115.086 177.3375)
		(end 115.776 177.3375)
		(width 0.201)
		(layer "F.Cu")
		(net 467)
	)
	(via
		(at 115.086 177.3375)
		(size 0.45)
		(drill 0.1)
		(layers "F.Cu" "B.Cu")
		(remove_unused_layers yes)
		(keep_end_layers yes)
		(zone_layer_connections)
		(net 467)
	)
	(via
		(at 122.076 185.692)
		(size 0.45)
		(drill 0.1)
		(layers "F.Cu" "B.Cu")
		(remove_unused_layers yes)
		(keep_end_layers yes)
		(zone_layer_connections)
		(net 467)
	)
	(segment
		(start 116.0315 177.3375)
		(end 115.086 177.3375)
		(width 0.201)
		(layer "B.Cu")
		(net 467)
	)
	(segment
		(start 120.846 183.692)
		(end 120.846 182.152)
		(width 0.201)
		(layer "B.Cu")
		(net 467)
	)
	(segment
		(start 120.846 182.152)
		(end 116.0315 177.3375)
		(width 0.201)
		(layer "B.Cu")
		(net 467)
	)
	(segment
		(start 122.076 185.692)
		(end 122.076 184.922)
		(width 0.201)
		(layer "B.Cu")
		(net 467)
	)
	(segment
		(start 122.076 184.922)
		(end 120.846 183.692)
		(width 0.201)
		(layer "B.Cu")
		(net 467)
	)
	(segment
		(start 109.375 176.2685)
		(end 113.917499 176.2685)
		(width 0.201)
		(layer "F.Cu")
		(net 468)
	)
	(segment
		(start 122.576 184.778)
		(end 122.576 186.182)
		(width 0.201)
		(layer "F.Cu")
		(net 468)
	)
	(segment
		(start 113.917499 176.367)
		(end 115.776 176.367)
		(width 0.201)
		(layer "F.Cu")
		(net 468)
	)
	(via
		(at 122.576 186.182)
		(size 0.45)
		(drill 0.1)
		(layers "F.Cu" "B.Cu")
		(remove_unused_layers yes)
		(keep_end_layers yes)
		(zone_layer_connections)
		(net 468)
	)
	(via
		(at 115.086 176.372)
		(size 0.45)
		(drill 0.1)
		(layers "F.Cu" "B.Cu")
		(remove_unused_layers yes)
		(keep_end_layers yes)
		(zone_layer_connections)
		(net 468)
	)
	(segment
		(start 122.576 186.182)
		(end 122.576 184.822)
		(width 0.201)
		(layer "B.Cu")
		(net 468)
	)
	(segment
		(start 121.306 181.902)
		(end 115.776 176.372)
		(width 0.201)
		(layer "B.Cu")
		(net 468)
	)
	(segment
		(start 122.576 184.822)
		(end 121.306 183.552)
		(width 0.201)
		(layer "B.Cu")
		(net 468)
	)
	(segment
		(start 115.776 176.372)
		(end 115.086 176.372)
		(width 0.201)
		(layer "B.Cu")
		(net 468)
	)
	(segment
		(start 121.306 183.552)
		(end 121.306 181.902)
		(width 0.201)
		(layer "B.Cu")
		(net 468)
	)
	(segment
		(start 175.9995 142.999499)
		(end 175.5 142.5)
		(width 0.256)
		(layer "F.Cu")
		(net 469)
	)
	(via
		(at 175.5 142.5)
		(size 0.45)
		(drill 0.1)
		(layers "F.Cu" "B.Cu")
		(remove_unused_layers yes)
		(keep_end_layers yes)
		(zone_layer_connections)
		(net 469)
	)
	(segment
		(start 199.4995 160.4995)
		(end 199 160)
		(width 0.256)
		(layer "F.Cu")
		(net 470)
	)
	(via
		(at 199.4995 160.4995)
		(size 0.45)
		(drill 0.1)
		(layers "F.Cu" "B.Cu")
		(remove_unused_layers yes)
		(keep_end_layers yes)
		(zone_layer_connections)
		(net 470)
	)
	(segment
		(start 199.31382 160.0995)
		(end 199.282343 160.0995)
		(width 0.1)
		(layer "B.Cu")
		(net 470)
	)
	(segment
		(start 199.32929 164.587868)
		(end 199.512132 164.77071)
		(width 0.1)
		(layer "B.Cu")
		(net 470)
	)
	(segment
		(start 199.0995 161.577029)
		(end 199.0995 161.875235)
		(width 0.1)
		(layer "B.Cu")
		(net 470)
	)
	(segment
		(start 186.337499 192.027523)
		(end 186.337499 192.354656)
		(width 0.22)
		(layer "B.Cu")
		(net 470)
	)
	(segment
		(start 186.6485 192.7485)
		(end 186.672499 192.7485)
		(width 0.22)
		(layer "B.Cu")
		(net 470)
	)
	(segment
		(start 199.690147 166.447506)
		(end 199.690147 175.825086)
		(width 0.22)
		(layer "B.Cu")
		(net 470)
	)
	(segment
		(start 199.0995 161.32)
		(end 199.0995 161.577029)
		(width 0.1)
		(layer "B.Cu")
		(net 470)
	)
	(segment
		(start 186.396078 192.496078)
		(end 186.6485 192.7485)
		(width 0.22)
		(layer "B.Cu")
		(net 470)
	)
	(segment
		(start 199.158079 162.016657)
		(end 199.182843 162.041421)
		(width 0.1)
		(layer "B.Cu")
		(net 470)
	)
	(segment
		(start 199.47021 160.17021)
		(end 199.460085 160.160085)
		(width 0.1)
		(layer "B.Cu")
		(net 470)
	)
	(segment
		(start 199.3 162.324263)
		(end 199.3 164.517157)
		(width 0.1)
		(layer "B.Cu")
		(net 470)
	)
	(segment
		(start 198.114381 179.629321)
		(end 186.776839 190.966863)
		(width 0.22)
		(layer "B.Cu")
		(net 470)
	)
	(segment
		(start 199.0995 160.282343)
		(end 199.0995 160.72)
		(width 0.1)
		(layer "B.Cu")
		(net 470)
	)
	(segment
		(start 199.4995 160.4995)
		(end 199.4995 160.240921)
		(width 0.1)
		(layer "B.Cu")
		(net 470)
	)
	(segment
		(start 199.6 164.982842)
		(end 199.6 166.315938)
		(width 0.1)
		(layer "B.Cu")
		(net 470)
	)
	(segment
		(start 199.62929 166.386649)
		(end 199.690147 166.447506)
		(width 0.1)
		(layer "B.Cu")
		(net 470)
	)
	(segment
		(start 199.211632 160.12879)
		(end 199.128789 160.211633)
		(width 0.1)
		(layer "B.Cu")
		(net 470)
	)
	(arc
		(start 199.0995 160.72)
		(mid 199.143434 160.826066)
		(end 199.2495 160.87)
		(width 0.1)
		(layer "B.Cu")
		(net 470)
	)
	(arc
		(start 199.2495 160.87)
		(mid 199.355566 160.913934)
		(end 199.3995 161.02)
		(width 0.1)
		(layer "B.Cu")
		(net 470)
	)
	(arc
		(start 199.3995 161.02)
		(mid 199.355566 161.126066)
		(end 199.2495 161.17)
		(width 0.1)
		(layer "B.Cu")
		(net 470)
	)
	(arc
		(start 199.128789 160.211633)
		(mid 199.107112 160.244075)
		(end 199.0995 160.282343)
		(width 0.1)
		(layer "B.Cu")
		(net 470)
	)
	(arc
		(start 186.776839 190.966863)
		(mid 186.45168 191.453498)
		(end 186.337499 192.027523)
		(width 0.22)
		(layer "B.Cu")
		(net 470)
	)
	(arc
		(start 199.3 164.517157)
		(mid 199.307612 164.555426)
		(end 199.32929 164.587868)
		(width 0.1)
		(layer "B.Cu")
		(net 470)
	)
	(arc
		(start 199.2495 161.17)
		(mid 199.143434 161.213934)
		(end 199.0995 161.32)
		(width 0.1)
		(layer "B.Cu")
		(net 470)
	)
	(arc
		(start 199.4995 160.240921)
		(mid 199.491888 160.202652)
		(end 199.47021 160.17021)
		(width 0.1)
		(layer "B.Cu")
		(net 470)
	)
	(arc
		(start 199.0995 161.875235)
		(mid 199.114724 161.951772)
		(end 199.158079 162.016657)
		(width 0.1)
		(layer "B.Cu")
		(net 470)
	)
	(arc
		(start 199.182843 162.041421)
		(mid 199.269552 162.17119)
		(end 199.3 162.324263)
		(width 0.1)
		(layer "B.Cu")
		(net 470)
	)
	(arc
		(start 199.6 166.315938)
		(mid 199.607612 166.354207)
		(end 199.62929 166.386649)
		(width 0.1)
		(layer "B.Cu")
		(net 470)
	)
	(arc
		(start 199.282343 160.0995)
		(mid 199.244074 160.107112)
		(end 199.211632 160.12879)
		(width 0.1)
		(layer "B.Cu")
		(net 470)
	)
	(arc
		(start 198.114381 179.629321)
		(mid 199.280619 177.883923)
		(end 199.690147 175.825086)
		(width 0.22)
		(layer "B.Cu")
		(net 470)
	)
	(arc
		(start 199.512132 164.77071)
		(mid 199.577164 164.868037)
		(end 199.6 164.982842)
		(width 0.1)
		(layer "B.Cu")
		(net 470)
	)
	(arc
		(start 186.337499 192.354656)
		(mid 186.352723 192.431193)
		(end 186.396078 192.496078)
		(width 0.22)
		(layer "B.Cu")
		(net 470)
	)
	(arc
		(start 199.460085 160.160085)
		(mid 199.392978 160.115246)
		(end 199.31382 160.0995)
		(width 0.1)
		(layer "B.Cu")
		(net 470)
	)
	(segment
		(start 196.000501 153.0005)
		(end 196.5 153.499999)
		(width 0.256)
		(layer "F.Cu")
		(net 471)
	)
	(via
		(at 196.5 153.499999)
		(size 0.45)
		(drill 0.1)
		(layers "F.Cu" "B.Cu")
		(remove_unused_layers yes)
		(keep_end_layers yes)
		(zone_layer_connections)
		(net 471)
	)
	(segment
		(start 241.425499 134.108001)
		(end 242.404998 134.108)
		(width 0.177)
		(layer "F.Cu")
		(net 472)
	)
	(segment
		(start 236.629499 185.763001)
		(end 236.635499 185.757001)
		(width 0.177)
		(layer "F.Cu")
		(net 472)
	)
	(segment
		(start 242.404998 134.108)
		(end 242.411998 134.115)
		(width 0.177)
		(layer "F.Cu")
		(net 472)
	)
	(segment
		(start 236.635499 185.757001)
		(end 237.902499 185.757)
		(width 0.177)
		(layer "F.Cu")
		(net 472)
	)
	(segment
		(start 194.0005 151.999499)
		(end 194.499999 151.5)
		(width 0.256)
		(layer "F.Cu")
		(net 472)
	)
	(via
		(at 236.629499 185.763001)
		(size 0.45)
		(drill 0.1)
		(layers "F.Cu" "B.Cu")
		(remove_unused_layers yes)
		(keep_end_layers yes)
		(zone_layer_connections)
		(net 472)
	)
	(via
		(at 242.411998 134.115)
		(size 0.45)
		(drill 0.1)
		(layers "F.Cu" "B.Cu")
		(remove_unused_layers yes)
		(keep_end_layers yes)
		(zone_layer_connections)
		(net 472)
	)
	(via
		(at 194.499999 151.5)
		(size 0.45)
		(drill 0.1)
		(layers "F.Cu" "B.Cu")
		(remove_unused_layers yes)
		(keep_end_layers yes)
		(zone_layer_connections)
		(net 472)
	)
	(segment
		(start 236.229499 186.163001)
		(end 236.629499 185.763001)
		(width 0.15)
		(layer "B.Cu")
		(net 472)
	)
	(segment
		(start 237.574499 188.849)
		(end 236.229499 187.504)
		(width 0.15)
		(layer "B.Cu")
		(net 472)
	)
	(segment
		(start 237.939499 188.849)
		(end 237.574499 188.849)
		(width 0.15)
		(layer "B.Cu")
		(net 472)
	)
	(segment
		(start 236.229499 187.504)
		(end 236.229499 186.163001)
		(width 0.15)
		(layer "B.Cu")
		(net 472)
	)
	(segment
		(start 242.815 134.115)
		(end 242.97 134.27)
		(width 0.198)
		(layer "B.Cu")
		(net 472)
	)
	(segment
		(start 242.411998 134.115)
		(end 242.815 134.115)
		(width 0.198)
		(layer "B.Cu")
		(net 472)
	)
	(segment
		(start 240.18 134.57)
		(end 233.55 141.2)
		(width 0.1)
		(layer "In4.Cu")
		(net 472)
	)
	(segment
		(start 208.675 148.725)
		(end 211.375 148.725)
		(width 0.1)
		(layer "In4.Cu")
		(net 472)
	)
	(segment
		(start 234.53 134.76)
		(end 238.149328 134.76)
		(width 0.1)
		(layer "In4.Cu")
		(net 472)
	)
	(segment
		(start 194.874999 151.125)
		(end 202.122489 151.125)
		(width 0.1)
		(layer "In4.Cu")
		(net 472)
	)
	(segment
		(start 202.122489 151.125)
		(end 204.147489 149.1)
		(width 0.1)
		(layer "In4.Cu")
		(net 472)
	)
	(segment
		(start 238.149328 134.76)
		(end 239.119328 133.79)
		(width 0.1)
		(layer "In4.Cu")
		(net 472)
	)
	(segment
		(start 220.050331 149.5)
		(end 220.297 149.253331)
		(width 0.1)
		(layer "In4.Cu")
		(net 472)
	)
	(segment
		(start 237.6 182.295501)
		(end 237.6 184.7925)
		(width 0.1)
		(layer "In4.Cu")
		(net 472)
	)
	(segment
		(start 242.086998 133.79)
		(end 242.411998 134.115)
		(width 0.1)
		(layer "In4.Cu")
		(net 472)
	)
	(segment
		(start 194.499999 151.5)
		(end 194.874999 151.125)
		(width 0.1)
		(layer "In4.Cu")
		(net 472)
	)
	(segment
		(start 241.956998 134.57)
		(end 240.18 134.57)
		(width 0.1)
		(layer "In4.Cu")
		(net 472)
	)
	(segment
		(start 236.595168 182.05)
		(end 237.354499 182.05)
		(width 0.1)
		(layer "In4.Cu")
		(net 472)
	)
	(segment
		(start 237.6 184.7925)
		(end 236.629499 185.763001)
		(width 0.1)
		(layer "In4.Cu")
		(net 472)
	)
	(segment
		(start 239.119328 133.79)
		(end 242.086998 133.79)
		(width 0.1)
		(layer "In4.Cu")
		(net 472)
	)
	(segment
		(start 220.297 148.993)
		(end 234.53 134.76)
		(width 0.1)
		(layer "In4.Cu")
		(net 472)
	)
	(segment
		(start 242.411998 134.115)
		(end 241.956998 134.57)
		(width 0.1)
		(layer "In4.Cu")
		(net 472)
	)
	(segment
		(start 233.55 162.4125)
		(end 236.249499 165.111999)
		(width 0.1)
		(layer "In4.Cu")
		(net 472)
	)
	(segment
		(start 236.249499 165.111999)
		(end 236.249499 181.704331)
		(width 0.1)
		(layer "In4.Cu")
		(net 472)
	)
	(segment
		(start 220.297 149.253331)
		(end 220.297 148.993)
		(width 0.1)
		(layer "In4.Cu")
		(net 472)
	)
	(segment
		(start 236.249499 181.704331)
		(end 236.595168 182.05)
		(width 0.1)
		(layer "In4.Cu")
		(net 472)
	)
	(segment
		(start 211.375 148.725)
		(end 212.15 149.5)
		(width 0.1)
		(layer "In4.Cu")
		(net 472)
	)
	(segment
		(start 204.147489 149.1)
		(end 208.3 149.1)
		(width 0.1)
		(layer "In4.Cu")
		(net 472)
	)
	(segment
		(start 233.55 141.2)
		(end 233.55 162.4125)
		(width 0.1)
		(layer "In4.Cu")
		(net 472)
	)
	(segment
		(start 212.15 149.5)
		(end 220.050331 149.5)
		(width 0.1)
		(layer "In4.Cu")
		(net 472)
	)
	(segment
		(start 208.3 149.1)
		(end 208.675 148.725)
		(width 0.1)
		(layer "In4.Cu")
		(net 472)
	)
	(segment
		(start 237.354499 182.05)
		(end 237.6 182.295501)
		(width 0.1)
		(layer "In4.Cu")
		(net 472)
	)
	(segment
		(start 234.715 132.075)
		(end 234.75 132.11)
		(width 0.15)
		(layer "F.Cu")
		(net 473)
	)
	(segment
		(start 233.875 132.075)
		(end 234.715 132.075)
		(width 0.256)
		(layer "F.Cu")
		(net 473)
	)
	(via
		(at 234.75 132.11)
		(size 0.45)
		(drill 0.1)
		(layers "F.Cu" "B.Cu")
		(remove_unused_layers yes)
		(keep_end_layers yes)
		(zone_layer_connections)
		(net 473)
	)
	(segment
		(start 234.535 132.325)
		(end 234.75 132.11)
		(width 0.198)
		(layer "B.Cu")
		(net 473)
	)
	(segment
		(start 234.05 132.325)
		(end 234.535 132.325)
		(width 0.198)
		(layer "B.Cu")
		(net 473)
	)
	(segment
		(start 186.9995 146.9995)
		(end 186.5 146.5)
		(width 0.256)
		(layer "F.Cu")
		(net 474)
	)
	(segment
		(start 157.3 110.598)
		(end 157.3 111.75)
		(width 0.38)
		(layer "F.Cu")
		(net 474)
	)
	(via
		(at 157.3 111.75)
		(size 0.45)
		(drill 0.1)
		(layers "F.Cu" "B.Cu")
		(remove_unused_layers yes)
		(keep_end_layers yes)
		(zone_layer_connections)
		(net 474)
	)
	(via
		(at 186.5 146.5)
		(size 0.45)
		(drill 0.1)
		(layers "F.Cu" "B.Cu")
		(remove_unused_layers yes)
		(keep_end_layers yes)
		(zone_layer_connections)
		(net 474)
	)
	(segment
		(start 158.435623 110.915917)
		(end 158.895 111.375294)
		(width 0.13)
		(layer "In2.Cu")
		(net 474)
	)
	(segment
		(start 167.08 118.357511)
		(end 167.08 118.025)
		(width 0.13)
		(layer "In2.Cu")
		(net 474)
	)
	(segment
		(start 190.11648 133.578844)
		(end 190.11648 138.660513)
		(width 0.13)
		(layer "In2.Cu")
		(net 474)
	)
	(segment
		(start 168.98 118.357485)
		(end 168.98 118.025)
		(width 0.13)
		(layer "In2.Cu")
		(net 474)
	)
	(segment
		(start 180.57 121.175294)
		(end 180.57 124.032364)
		(width 0.13)
		(layer "In2.Cu")
		(net 474)
	)
	(segment
		(start 186.157547 146.5)
		(end 186.113112 146.455565)
		(width 0.1)
		(layer "In2.Cu")
		(net 474)
	)
	(segment
		(start 157.605 111.445)
		(end 157.605 111.185315)
		(width 0.13)
		(layer "In2.Cu")
		(net 474)
	)
	(segment
		(start 189.1 143.241422)
		(end 190.1 142.241422)
		(width 0.1)
		(layer "In2.Cu")
		(net 474)
	)
	(segment
		(start 164.47 118.025)
		(end 164.47 118.357485)
		(width 0.13)
		(layer "In2.Cu")
		(net 474)
	)
	(segment
		(start 190.1 142.241422)
		(end 190.1 138.676993)
		(width 0.1)
		(layer "In2.Cu")
		(net 474)
	)
	(segment
		(start 157.3 111.75)
		(end 157.605 111.445)
		(width 0.13)
		(layer "In2.Cu")
		(net 474)
	)
	(segment
		(start 170.17 118.025)
		(end 170.17 118.357511)
		(width 0.13)
		(layer "In2.Cu")
		(net 474)
	)
	(segment
		(start 166.37 118.025)
		(end 166.37 118.357511)
		(width 0.13)
		(layer "In2.Cu")
		(net 474)
	)
	(segment
		(start 158.895 112.242228)
		(end 157.97 113.167228)
		(width 0.13)
		(layer "In2.Cu")
		(net 474)
	)
	(segment
		(start 170.88 118.357511)
		(end 170.88 118.025)
		(width 0.13)
		(layer "In2.Cu")
		(net 474)
	)
	(segment
		(start 176.824706 117.43)
		(end 180.57 121.175294)
		(width 0.13)
		(layer "In2.Cu")
		(net 474)
	)
	(segment
		(start 168.27 118.025)
		(end 168.27 118.357485)
		(width 0.13)
		(layer "In2.Cu")
		(net 474)
	)
	(segment
		(start 158.895 111.375294)
		(end 158.895 112.242228)
		(width 0.13)
		(layer "In2.Cu")
		(net 474)
	)
	(segment
		(start 163.28 118.357511)
		(end 163.28 118.025)
		(width 0.13)
		(layer "In2.Cu")
		(net 474)
	)
	(segment
		(start 180.57 124.032364)
		(end 190.11648 133.578844)
		(width 0.13)
		(layer "In2.Cu")
		(net 474)
	)
	(segment
		(start 162.57 118.025)
		(end 162.57 118.357511)
		(width 0.13)
		(layer "In2.Cu")
		(net 474)
	)
	(segment
		(start 173.375 117.43)
		(end 175.565307 117.43)
		(width 0.13)
		(layer "In2.Cu")
		(net 474)
	)
	(segment
		(start 161.324706 117.43)
		(end 161.975 117.43)
		(width 0.13)
		(layer "In2.Cu")
		(net 474)
	)
	(segment
		(start 157.605 111.185315)
		(end 157.874398 110.915917)
		(width 0.13)
		(layer "In2.Cu")
		(net 474)
	)
	(segment
		(start 157.874398 110.915917)
		(end 158.435623 110.915917)
		(width 0.13)
		(layer "In2.Cu")
		(net 474)
	)
	(segment
		(start 186.5 146.5)
		(end 186.157547 146.5)
		(width 0.1)
		(layer "In2.Cu")
		(net 474)
	)
	(segment
		(start 186.113112 146.20873)
		(end 186.221842 146.1)
		(width 0.1)
		(layer "In2.Cu")
		(net 474)
	)
	(segment
		(start 157.97 114.075294)
		(end 161.324706 117.43)
		(width 0.13)
		(layer "In2.Cu")
		(net 474)
	)
	(segment
		(start 186.221842 146.1)
		(end 188.166422 146.1)
		(width 0.1)
		(layer "In2.Cu")
		(net 474)
	)
	(segment
		(start 186.113112 146.455565)
		(end 186.113112 146.20873)
		(width 0.1)
		(layer "In2.Cu")
		(net 474)
	)
	(segment
		(start 175.565307 117.43)
		(end 176.824706 117.43)
		(width 0.13)
		(layer "In2.Cu")
		(net 474)
	)
	(segment
		(start 165.18 118.357485)
		(end 165.18 118.025)
		(width 0.13)
		(layer "In2.Cu")
		(net 474)
	)
	(segment
		(start 172.07 118.025)
		(end 172.07 118.357485)
		(width 0.13)
		(layer "In2.Cu")
		(net 474)
	)
	(segment
		(start 190.1 138.676993)
		(end 190.11648 138.660513)
		(width 0.1)
		(layer "In2.Cu")
		(net 474)
	)
	(segment
		(start 157.97 113.167228)
		(end 157.97 114.075294)
		(width 0.13)
		(layer "In2.Cu")
		(net 474)
	)
	(segment
		(start 188.166422 146.1)
		(end 189.1 145.166422)
		(width 0.1)
		(layer "In2.Cu")
		(net 474)
	)
	(segment
		(start 172.78 118.357485)
		(end 172.78 118.025)
		(width 0.13)
		(layer "In2.Cu")
		(net 474)
	)
	(segment
		(start 189.1 145.166422)
		(end 189.1 143.241422)
		(width 0.1)
		(layer "In2.Cu")
		(net 474)
	)
	(arc
		(start 172.425 118.712485)
		(mid 172.676023 118.608508)
		(end 172.78 118.357485)
		(width 0.13)
		(layer "In2.Cu")
		(net 474)
	)
	(arc
		(start 168.98 118.025)
		(mid 169.154271 117.604271)
		(end 169.575 117.43)
		(width 0.13)
		(layer "In2.Cu")
		(net 474)
	)
	(arc
		(start 165.775 117.43)
		(mid 166.195729 117.604271)
		(end 166.37 118.025)
		(width 0.13)
		(layer "In2.Cu")
		(net 474)
	)
	(arc
		(start 168.27 118.357485)
		(mid 168.373977 118.608508)
		(end 168.625 118.712485)
		(width 0.13)
		(layer "In2.Cu")
		(net 474)
	)
	(arc
		(start 169.575 117.43)
		(mid 169.995729 117.604271)
		(end 170.17 118.025)
		(width 0.13)
		(layer "In2.Cu")
		(net 474)
	)
	(arc
		(start 171.475 117.43)
		(mid 171.895729 117.604271)
		(end 172.07 118.025)
		(width 0.13)
		(layer "In2.Cu")
		(net 474)
	)
	(arc
		(start 164.825 118.712485)
		(mid 165.076023 118.608508)
		(end 165.18 118.357485)
		(width 0.13)
		(layer "In2.Cu")
		(net 474)
	)
	(arc
		(start 162.925 118.712511)
		(mid 163.176023 118.608534)
		(end 163.28 118.357511)
		(width 0.13)
		(layer "In2.Cu")
		(net 474)
	)
	(arc
		(start 167.675 117.43)
		(mid 168.095729 117.604271)
		(end 168.27 118.025)
		(width 0.13)
		(layer "In2.Cu")
		(net 474)
	)
	(arc
		(start 163.28 118.025)
		(mid 163.454271 117.604271)
		(end 163.875 117.43)
		(width 0.13)
		(layer "In2.Cu")
		(net 474)
	)
	(arc
		(start 162.57 118.357511)
		(mid 162.673977 118.608534)
		(end 162.925 118.712511)
		(width 0.13)
		(layer "In2.Cu")
		(net 474)
	)
	(arc
		(start 165.18 118.025)
		(mid 165.354271 117.604271)
		(end 165.775 117.43)
		(width 0.13)
		(layer "In2.Cu")
		(net 474)
	)
	(arc
		(start 170.17 118.357511)
		(mid 170.273977 118.608534)
		(end 170.525 118.712511)
		(width 0.13)
		(layer "In2.Cu")
		(net 474)
	)
	(arc
		(start 164.47 118.357485)
		(mid 164.573977 118.608508)
		(end 164.825 118.712485)
		(width 0.13)
		(layer "In2.Cu")
		(net 474)
	)
	(arc
		(start 163.875 117.43)
		(mid 164.295729 117.604271)
		(end 164.47 118.025)
		(width 0.13)
		(layer "In2.Cu")
		(net 474)
	)
	(arc
		(start 170.88 118.025)
		(mid 171.054271 117.604271)
		(end 171.475 117.43)
		(width 0.13)
		(layer "In2.Cu")
		(net 474)
	)
	(arc
		(start 172.78 118.025)
		(mid 172.954271 117.604271)
		(end 173.375 117.43)
		(width 0.13)
		(layer "In2.Cu")
		(net 474)
	)
	(arc
		(start 167.08 118.025)
		(mid 167.254271 117.604271)
		(end 167.675 117.43)
		(width 0.13)
		(layer "In2.Cu")
		(net 474)
	)
	(arc
		(start 172.07 118.357485)
		(mid 172.173977 118.608508)
		(end 172.425 118.712485)
		(width 0.13)
		(layer "In2.Cu")
		(net 474)
	)
	(arc
		(start 166.37 118.357511)
		(mid 166.473977 118.608534)
		(end 166.725 118.712511)
		(width 0.13)
		(layer "In2.Cu")
		(net 474)
	)
	(arc
		(start 166.725 118.712511)
		(mid 166.976023 118.608534)
		(end 167.08 118.357511)
		(width 0.13)
		(layer "In2.Cu")
		(net 474)
	)
	(arc
		(start 170.525 118.712511)
		(mid 170.776023 118.608534)
		(end 170.88 118.357511)
		(width 0.13)
		(layer "In2.Cu")
		(net 474)
	)
	(arc
		(start 161.975 117.43)
		(mid 162.395729 117.604271)
		(end 162.57 118.025)
		(width 0.13)
		(layer "In2.Cu")
		(net 474)
	)
	(arc
		(start 168.625 118.712485)
		(mid 168.876023 118.608508)
		(end 168.98 118.357485)
		(width 0.13)
		(layer "In2.Cu")
		(net 474)
	)
	(segment
		(start 177.9995 139.9995)
		(end 177.5 139.5)
		(width 0.256)
		(layer "F.Cu")
		(net 475)
	)
	(segment
		(start 127.55 110.598)
		(end 127.55 111.75)
		(width 0.38)
		(layer "F.Cu")
		(net 475)
	)
	(via
		(at 127.55 111.75)
		(size 0.45)
		(drill 0.1)
		(layers "F.Cu" "B.Cu")
		(remove_unused_layers yes)
		(keep_end_layers yes)
		(zone_layer_connections)
		(net 475)
	)
	(via
		(at 177.5 139.5)
		(size 0.45)
		(drill 0.1)
		(layers "F.Cu" "B.Cu")
		(remove_unused_layers yes)
		(keep_end_layers yes)
		(zone_layer_connections)
		(net 475)
	)
	(segment
		(start 149.967338 136.723776)
		(end 149.282749 136.039187)
		(width 0.148)
		(layer "In2.Cu")
		(net 475)
	)
	(segment
		(start 143.863705 131.513705)
		(end 143.179126 130.829126)
		(width 0.148)
		(layer "In2.Cu")
		(net 475)
	)
	(segment
		(start 136.390946 123.594111)
		(end 136.390946 123.59411)
		(width 0.148)
		(layer "In2.Cu")
		(net 475)
	)
	(segment
		(start 135.70641 122.46274)
		(end 135.706411 122.46274)
		(width 0.148)
		(layer "In2.Cu")
		(net 475)
	)
	(segment
		(start 149.282749 136.039187)
		(end 149.282749 136.039188)
		(width 0.148)
		(layer "In2.Cu")
		(net 475)
	)
	(segment
		(start 143.179126 129.935542)
		(end 142.494548 129.250964)
		(width 0.148)
		(layer "In2.Cu")
		(net 475)
	)
	(segment
		(start 176.675 140)
		(end 176.3 140)
		(width 0.148)
		(layer "In2.Cu")
		(net 475)
	)
	(segment
		(start 138.653686 126.303687)
		(end 138.653684 126.303686)
		(width 0.148)
		(layer "In2.Cu")
		(net 475)
	)
	(segment
		(start 176 140.782136)
		(end 175.782136 141)
		(width 0.148)
		(layer "In2.Cu")
		(net 475)
	)
	(segment
		(start 140.916406 127.67278)
		(end 140.231849 126.988223)
		(width 0.148)
		(layer "In2.Cu")
		(net 475)
	)
	(segment
		(start 137.522317 124.725482)
		(end 137.522317 124.725481)
		(width 0.148)
		(layer "In2.Cu")
		(net 475)
	)
	(segment
		(start 128.3 114.5)
		(end 127.55 113.75)
		(width 0.148)
		(layer "In2.Cu")
		(net 475)
	)
	(segment
		(start 132.996792 120.2)
		(end 132.996793 120.199999)
		(width 0.148)
		(layer "In2.Cu")
		(net 475)
	)
	(segment
		(start 140.916407 128.119594)
		(end 140.916405 128.119593)
		(width 0.148)
		(layer "In2.Cu")
		(net 475)
	)
	(segment
		(start 139.785037 126.988224)
		(end 139.785036 126.988222)
		(width 0.148)
		(layer "In2.Cu")
		(net 475)
	)
	(segment
		(start 136.390945 124.040946)
		(end 136.390943 124.040945)
		(width 0.148)
		(layer "In2.Cu")
		(net 475)
	)
	(segment
		(start 141.600964 129.250964)
		(end 140.916406 128.566406)
		(width 0.148)
		(layer "In2.Cu")
		(net 475)
	)
	(segment
		(start 148.835969 136.039188)
		(end 148.835968 136.039186)
		(width 0.148)
		(layer "In2.Cu")
		(net 475)
	)
	(segment
		(start 137.075482 124.725482)
		(end 136.390945 124.040946)
		(width 0.148)
		(layer "In2.Cu")
		(net 475)
	)
	(segment
		(start 149.967338 137.617338)
		(end 149.967339 137.617338)
		(width 0.148)
		(layer "In2.Cu")
		(net 475)
	)
	(segment
		(start 150.651928 138.301928)
		(end 149.967338 137.617338)
		(width 0.148)
		(layer "In2.Cu")
		(net 475)
	)
	(segment
		(start 151.545554 138.301928)
		(end 151.545554 138.301929)
		(width 0.148)
		(layer "In2.Cu")
		(net 475)
	)
	(segment
		(start 152.230111 138.986485)
		(end 151.545554 138.301928)
		(width 0.148)
		(layer "In2.Cu")
		(net 475)
	)
	(segment
		(start 142.047756 129.250964)
		(end 142.047757 129.250963)
		(width 0.148)
		(layer "In2.Cu")
		(net 475)
	)
	(segment
		(start 140.231849 126.988223)
		(end 140.231849 126.988224)
		(width 0.148)
		(layer "In2.Cu")
		(net 475)
	)
	(segment
		(start 152.230112 139.433299)
		(end 152.23011 139.433298)
		(width 0.148)
		(layer "In2.Cu")
		(net 475)
	)
	(segment
		(start 176.3 140)
		(end 176 140.3)
		(width 0.148)
		(layer "In2.Cu")
		(net 475)
	)
	(segment
		(start 147.704624 134.461008)
		(end 147.020062 133.776446)
		(width 0.148)
		(layer "In2.Cu")
		(net 475)
	)
	(segment
		(start 177.5 139.5)
		(end 177.175 139.5)
		(width 0.148)
		(layer "In2.Cu")
		(net 475)
	)
	(segment
		(start 135.259576 122.462741)
		(end 135.259576 122.46274)
		(width 0.148)
		(layer "In2.Cu")
		(net 475)
	)
	(segment
		(start 175.782136 141)
		(end 153.35 141)
		(width 0.148)
		(layer "In2.Cu")
		(net 475)
	)
	(segment
		(start 132.55 120.2)
		(end 128.3 115.95)
		(width 0.148)
		(layer "In2.Cu")
		(net 475)
	)
	(segment
		(start 146.126446 133.776446)
		(end 145.441867 133.091867)
		(width 0.148)
		(layer "In2.Cu")
		(net 475)
	)
	(segment
		(start 176 140.3)
		(end 176 140.782136)
		(width 0.148)
		(layer "In2.Cu")
		(net 475)
	)
	(segment
		(start 136.390945 123.147275)
		(end 135.70641 122.46274)
		(width 0.148)
		(layer "In2.Cu")
		(net 475)
	)
	(segment
		(start 138.653687 125.856852)
		(end 138.653687 125.856851)
		(width 0.148)
		(layer "In2.Cu")
		(net 475)
	)
	(segment
		(start 139.338223 126.988223)
		(end 138.653686 126.303687)
		(width 0.148)
		(layer "In2.Cu")
		(net 475)
	)
	(segment
		(start 146.573254 133.776446)
		(end 146.573255 133.776445)
		(width 0.148)
		(layer "In2.Cu")
		(net 475)
	)
	(segment
		(start 138.653685 125.856851)
		(end 138.653687 125.856852)
		(width 0.148)
		(layer "In2.Cu")
		(net 475)
	)
	(segment
		(start 128.3 115.95)
		(end 128.3 114.5)
		(width 0.148)
		(layer "In2.Cu")
		(net 475)
	)
	(segment
		(start 151.098742 138.301929)
		(end 151.098741 138.301927)
		(width 0.148)
		(layer "In2.Cu")
		(net 475)
	)
	(segment
		(start 137.969151 124.725481)
		(end 137.969152 124.725481)
		(width 0.148)
		(layer "In2.Cu")
		(net 475)
	)
	(segment
		(start 148.389187 136.039187)
		(end 147.704624 135.354624)
		(width 0.148)
		(layer "In2.Cu")
		(net 475)
	)
	(segment
		(start 136.390944 123.59411)
		(end 136.390946 123.594111)
		(width 0.148)
		(layer "In2.Cu")
		(net 475)
	)
	(segment
		(start 134.128162 120.884578)
		(end 133.443584 120.2)
		(width 0.148)
		(layer "In2.Cu")
		(net 475)
	)
	(segment
		(start 145.441867 132.198283)
		(end 144.757289 131.513705)
		(width 0.148)
		(layer "In2.Cu")
		(net 475)
	)
	(segment
		(start 144.310497 131.513705)
		(end 144.310498 131.513704)
		(width 0.148)
		(layer "In2.Cu")
		(net 475)
	)
	(segment
		(start 138.653686 125.410016)
		(end 137.969151 124.725481)
		(width 0.148)
		(layer "In2.Cu")
		(net 475)
	)
	(segment
		(start 140.916406 128.566406)
		(end 140.916407 128.566406)
		(width 0.148)
		(layer "In2.Cu")
		(net 475)
	)
	(segment
		(start 149.967339 137.170558)
		(end 149.967339 137.170557)
		(width 0.148)
		(layer "In2.Cu")
		(net 475)
	)
	(segment
		(start 153.35 141)
		(end 152.230112 139.880111)
		(width 0.148)
		(layer "In2.Cu")
		(net 475)
	)
	(segment
		(start 134.812741 122.462741)
		(end 134.128162 121.778162)
		(width 0.148)
		(layer "In2.Cu")
		(net 475)
	)
	(segment
		(start 177.175 139.5)
		(end 176.675 140)
		(width 0.148)
		(layer "In2.Cu")
		(net 475)
	)
	(segment
		(start 127.55 113.75)
		(end 127.55 111.75)
		(width 0.148)
		(layer "In2.Cu")
		(net 475)
	)
	(arc
		(start 151.545554 138.301929)
		(mid 151.322148 138.209391)
		(end 151.098742 138.301929)
		(width 0.148)
		(layer "In2.Cu")
		(net 475)
	)
	(arc
		(start 147.704624 134.907816)
		(mid 147.797162 134.684413)
		(end 147.704624 134.461008)
		(width 0.148)
		(layer "In2.Cu")
		(net 475)
	)
	(arc
		(start 138.653687 125.856851)
		(mid 138.746229 125.633433)
		(end 138.653686 125.410016)
		(width 0.148)
		(layer "In2.Cu")
		(net 475)
	)
	(arc
		(start 147.704624 135.354624)
		(mid 147.612088 135.131221)
		(end 147.704624 134.907816)
		(width 0.148)
		(layer "In2.Cu")
		(net 475)
	)
	(arc
		(start 143.179126 130.829126)
		(mid 143.086592 130.60573)
		(end 143.179126 130.382334)
		(width 0.148)
		(layer "In2.Cu")
		(net 475)
	)
	(arc
		(start 143.179126 130.382334)
		(mid 143.27166 130.158938)
		(end 143.179126 129.935542)
		(width 0.148)
		(layer "In2.Cu")
		(net 475)
	)
	(arc
		(start 137.969152 124.725481)
		(mid 137.745734 124.632939)
		(end 137.522317 124.725482)
		(width 0.148)
		(layer "In2.Cu")
		(net 475)
	)
	(arc
		(start 140.916405 128.119593)
		(mid 141.008945 127.896188)
		(end 140.916406 127.67278)
		(width 0.148)
		(layer "In2.Cu")
		(net 475)
	)
	(arc
		(start 139.785036 126.988222)
		(mid 139.561631 127.080762)
		(end 139.338223 126.988223)
		(width 0.148)
		(layer "In2.Cu")
		(net 475)
	)
	(arc
		(start 142.047757 129.250963)
		(mid 141.824361 129.343497)
		(end 141.600964 129.250964)
		(width 0.148)
		(layer "In2.Cu")
		(net 475)
	)
	(arc
		(start 137.522317 124.725481)
		(mid 137.2989 124.818024)
		(end 137.075482 124.725482)
		(width 0.148)
		(layer "In2.Cu")
		(net 475)
	)
	(arc
		(start 136.390943 124.040945)
		(mid 136.298401 123.817527)
		(end 136.390944 123.59411)
		(width 0.148)
		(layer "In2.Cu")
		(net 475)
	)
	(arc
		(start 147.020062 133.776446)
		(mid 146.796659 133.68391)
		(end 146.573254 133.776446)
		(width 0.148)
		(layer "In2.Cu")
		(net 475)
	)
	(arc
		(start 133.443584 120.2)
		(mid 133.220188 120.107466)
		(end 132.996792 120.2)
		(width 0.148)
		(layer "In2.Cu")
		(net 475)
	)
	(arc
		(start 148.835968 136.039186)
		(mid 148.612578 136.131718)
		(end 148.389187 136.039187)
		(width 0.148)
		(layer "In2.Cu")
		(net 475)
	)
	(arc
		(start 144.310498 131.513704)
		(mid 144.087102 131.606238)
		(end 143.863705 131.513705)
		(width 0.148)
		(layer "In2.Cu")
		(net 475)
	)
	(arc
		(start 134.128162 121.33137)
		(mid 134.220696 121.107974)
		(end 134.128162 120.884578)
		(width 0.148)
		(layer "In2.Cu")
		(net 475)
	)
	(arc
		(start 138.653684 126.303686)
		(mid 138.561142 126.080268)
		(end 138.653685 125.856851)
		(width 0.148)
		(layer "In2.Cu")
		(net 475)
	)
	(arc
		(start 152.23011 139.433298)
		(mid 152.32265 139.209893)
		(end 152.230111 138.986485)
		(width 0.148)
		(layer "In2.Cu")
		(net 475)
	)
	(arc
		(start 152.230112 139.880111)
		(mid 152.137574 139.656705)
		(end 152.230112 139.433299)
		(width 0.148)
		(layer "In2.Cu")
		(net 475)
	)
	(arc
		(start 149.282749 136.039188)
		(mid 149.059358 135.946656)
		(end 148.835969 136.039188)
		(width 0.148)
		(layer "In2.Cu")
		(net 475)
	)
	(arc
		(start 145.441867 132.645075)
		(mid 145.534401 132.421679)
		(end 145.441867 132.198283)
		(width 0.148)
		(layer "In2.Cu")
		(net 475)
	)
	(arc
		(start 146.573255 133.776445)
		(mid 146.349851 133.868983)
		(end 146.126446 133.776446)
		(width 0.148)
		(layer "In2.Cu")
		(net 475)
	)
	(arc
		(start 140.231849 126.988224)
		(mid 140.008443 126.895686)
		(end 139.785037 126.988224)
		(width 0.148)
		(layer "In2.Cu")
		(net 475)
	)
	(arc
		(start 149.967339 137.617338)
		(mid 149.874807 137.393947)
		(end 149.967339 137.170558)
		(width 0.148)
		(layer "In2.Cu")
		(net 475)
	)
	(arc
		(start 135.706411 122.46274)
		(mid 135.482993 122.370198)
		(end 135.259576 122.462741)
		(width 0.148)
		(layer "In2.Cu")
		(net 475)
	)
	(arc
		(start 151.098741 138.301927)
		(mid 150.875336 138.394467)
		(end 150.651928 138.301928)
		(width 0.148)
		(layer "In2.Cu")
		(net 475)
	)
	(arc
		(start 132.996793 120.199999)
		(mid 132.773397 120.292533)
		(end 132.55 120.2)
		(width 0.148)
		(layer "In2.Cu")
		(net 475)
	)
	(arc
		(start 145.441867 133.091867)
		(mid 145.349333 132.868471)
		(end 145.441867 132.645075)
		(width 0.148)
		(layer "In2.Cu")
		(net 475)
	)
	(arc
		(start 142.494548 129.250964)
		(mid 142.271152 129.15843)
		(end 142.047756 129.250964)
		(width 0.148)
		(layer "In2.Cu")
		(net 475)
	)
	(arc
		(start 149.967339 137.170557)
		(mid 150.05987 136.947166)
		(end 149.967338 136.723776)
		(width 0.148)
		(layer "In2.Cu")
		(net 475)
	)
	(arc
		(start 140.916407 128.566406)
		(mid 140.823869 128.343)
		(end 140.916407 128.119594)
		(width 0.148)
		(layer "In2.Cu")
		(net 475)
	)
	(arc
		(start 144.757289 131.513705)
		(mid 144.533893 131.421171)
		(end 144.310497 131.513705)
		(width 0.148)
		(layer "In2.Cu")
		(net 475)
	)
	(arc
		(start 136.390946 123.59411)
		(mid 136.483488 123.370692)
		(end 136.390945 123.147275)
		(width 0.148)
		(layer "In2.Cu")
		(net 475)
	)
	(arc
		(start 135.259576 122.46274)
		(mid 135.036159 122.555283)
		(end 134.812741 122.462741)
		(width 0.148)
		(layer "In2.Cu")
		(net 475)
	)
	(arc
		(start 134.128162 121.778162)
		(mid 134.035628 121.554766)
		(end 134.128162 121.33137)
		(width 0.148)
		(layer "In2.Cu")
		(net 475)
	)
	(segment
		(start 178.999499 139.9995)
		(end 178.5 139.5)
		(width 0.256)
		(layer "F.Cu")
		(net 476)
	)
	(segment
		(start 125.85 110.598)
		(end 125.85 111.75)
		(width 0.38)
		(layer "F.Cu")
		(net 476)
	)
	(via
		(at 178.5 139.5)
		(size 0.45)
		(drill 0.1)
		(layers "F.Cu" "B.Cu")
		(remove_unused_layers yes)
		(keep_end_layers yes)
		(zone_layer_connections)
		(net 476)
	)
	(via
		(at 125.85 111.75)
		(size 0.45)
		(drill 0.1)
		(layers "F.Cu" "B.Cu")
		(remove_unused_layers yes)
		(keep_end_layers yes)
		(zone_layer_connections)
		(net 476)
	)
	(segment
		(start 176.564273 143)
		(end 152.19 143)
		(width 0.148)
		(layer "In2.Cu")
		(net 476)
	)
	(segment
		(start 177.65 140)
		(end 177.25 140)
		(width 0.148)
		(layer "In2.Cu")
		(net 476)
	)
	(segment
		(start 177 142.564273)
		(end 176.564273 143)
		(width 0.148)
		(layer "In2.Cu")
		(net 476)
	)
	(segment
		(start 152.19 143)
		(end 125.85 116.66)
		(width 0.148)
		(layer "In2.Cu")
		(net 476)
	)
	(segment
		(start 178.5 139.5)
		(end 178.15 139.5)
		(width 0.148)
		(layer "In2.Cu")
		(net 476)
	)
	(segment
		(start 178.15 139.5)
		(end 177.65 140)
		(width 0.148)
		(layer "In2.Cu")
		(net 476)
	)
	(segment
		(start 177 140.25)
		(end 177 142.564273)
		(width 0.148)
		(layer "In2.Cu")
		(net 476)
	)
	(segment
		(start 125.85 116.66)
		(end 125.85 111.75)
		(width 0.148)
		(layer "In2.Cu")
		(net 476)
	)
	(segment
		(start 177.25 140)
		(end 177 140.25)
		(width 0.148)
		(layer "In2.Cu")
		(net 476)
	)
	(segment
		(start 208.571 154.44)
		(end 208.14 154.44)
		(width 0.256)
		(layer "F.Cu")
		(net 477)
	)
	(segment
		(start 208.925 155)
		(end 208.925 154.794)
		(width 0.256)
		(layer "F.Cu")
		(net 477)
	)
	(segment
		(start 208.925 154.794)
		(end 208.571 154.44)
		(width 0.256)
		(layer "F.Cu")
		(net 477)
	)
	(via
		(at 208.925 155)
		(size 0.45)
		(drill 0.1)
		(layers "F.Cu" "B.Cu")
		(remove_unused_layers yes)
		(keep_end_layers yes)
		(zone_layer_connections)
		(net 477)
	)
	(segment
		(start 208.32 154.67)
		(end 208.65 155)
		(width 0.182)
		(layer "B.Cu")
		(net 477)
	)
	(segment
		(start 208.65 155)
		(end 208.925 155)
		(width 0.182)
		(layer "B.Cu")
		(net 477)
	)
	(segment
		(start 208.275 154.67)
		(end 208.32 154.67)
		(width 0.182)
		(layer "B.Cu")
		(net 477)
	)
	(segment
		(start 197.0005 151.9995)
		(end 197.5 151.5)
		(width 0.256)
		(layer "F.Cu")
		(net 478)
	)
	(via
		(at 197.5 151.5)
		(size 0.45)
		(drill 0.1)
		(layers "F.Cu" "B.Cu")
		(remove_unused_layers yes)
		(keep_end_layers yes)
		(zone_layer_connections)
		(net 478)
	)
	(segment
		(start 197.0005 150.9995)
		(end 197.5 150.5)
		(width 0.256)
		(layer "F.Cu")
		(net 479)
	)
	(via
		(at 197.5 150.5)
		(size 0.45)
		(drill 0.1)
		(layers "F.Cu" "B.Cu")
		(remove_unused_layers yes)
		(keep_end_layers yes)
		(zone_layer_connections)
		(net 479)
	)
	(segment
		(start 118.7 166.36)
		(end 118.7 163.83)
		(width 0.15)
		(layer "B.Cu")
		(net 480)
	)
	(segment
		(start 117.16 162.29)
		(end 110.55 162.29)
		(width 0.15)
		(layer "B.Cu")
		(net 480)
	)
	(segment
		(start 110.55 162.29)
		(end 109.972 162.868)
		(width 0.15)
		(layer "B.Cu")
		(net 480)
	)
	(segment
		(start 105.17 162.868)
		(end 108.189 162.868)
		(width 0.201)
		(layer "B.Cu")
		(net 480)
	)
	(segment
		(start 118.7 163.83)
		(end 117.16 162.29)
		(width 0.15)
		(layer "B.Cu")
		(net 480)
	)
	(segment
		(start 109.972 162.868)
		(end 108.191 162.868)
		(width 0.15)
		(layer "B.Cu")
		(net 480)
	)
	(segment
		(start 198.5 153.5)
		(end 198.0005 153.0005)
		(width 0.256)
		(layer "F.Cu")
		(net 481)
	)
	(via
		(at 198.5 153.5)
		(size 0.45)
		(drill 0.1)
		(layers "F.Cu" "B.Cu")
		(remove_unused_layers yes)
		(keep_end_layers yes)
		(zone_layer_connections)
		(net 481)
	)
	(segment
		(start 215.850001 182.645001)
		(end 216.895001 182.645001)
		(width 0.114)
		(layer "F.Cu")
		(net 482)
	)
	(segment
		(start 226.545001 182.640001)
		(end 227.590001 182.640001)
		(width 0.114)
		(layer "F.Cu")
		(net 482)
	)
	(via
		(at 215.850001 182.645001)
		(size 0.45)
		(drill 0.1)
		(layers "F.Cu" "B.Cu")
		(remove_unused_layers yes)
		(keep_end_layers yes)
		(zone_layer_connections)
		(net 482)
	)
	(via
		(at 226.545001 182.640001)
		(size 0.45)
		(drill 0.1)
		(layers "F.Cu" "B.Cu")
		(remove_unused_layers yes)
		(keep_end_layers yes)
		(zone_layer_connections)
		(net 482)
	)
	(via
		(at 239.5 165.25)
		(size 0.45)
		(drill 0.1)
		(layers "F.Cu" "B.Cu")
		(remove_unused_layers yes)
		(keep_end_layers yes)
		(zone_layer_connections)
		(net 482)
	)
	(segment
		(start 238.936999 165.225)
		(end 239.475 165.225)
		(width 0.182)
		(layer "B.Cu")
		(net 482)
	)
	(segment
		(start 239.475 165.225)
		(end 239.5 165.25)
		(width 0.182)
		(layer "B.Cu")
		(net 482)
	)
	(segment
		(start 227.6 184.25)
		(end 227.6 183.1)
		(width 0.114)
		(layer "In2.Cu")
		(net 482)
	)
	(segment
		(start 226.722385 185.127615)
		(end 217.677615 185.127615)
		(width 0.1)
		(layer "In2.Cu")
		(net 482)
	)
	(segment
		(start 239.674 186.624)
		(end 242.176 186.624)
		(width 0.1)
		(layer "In2.Cu")
		(net 482)
	)
	(segment
		(start 227.140001 182.640001)
		(end 226.545001 182.640001)
		(width 0.114)
		(layer "In2.Cu")
		(net 482)
	)
	(segment
		(start 215.4 183.85)
		(end 215.4 183.095002)
		(width 0.1)
		(layer "In2.Cu")
		(net 482)
	)
	(segment
		(start 215.4 183.095002)
		(end 215.850001 182.645001)
		(width 0.1)
		(layer "In2.Cu")
		(net 482)
	)
	(segment
		(start 228.2 184.85)
		(end 237.9 184.85)
		(width 0.1)
		(layer "In2.Cu")
		(net 482)
	)
	(segment
		(start 227.6 183.1)
		(end 227.140001 182.640001)
		(width 0.114)
		(layer "In2.Cu")
		(net 482)
	)
	(segment
		(start 227.6 184.25)
		(end 226.722385 185.127615)
		(width 0.1)
		(layer "In2.Cu")
		(net 482)
	)
	(segment
		(start 239.93983 165.25)
		(end 239.5 165.25)
		(width 0.1)
		(layer "In2.Cu")
		(net 482)
	)
	(segment
		(start 237.9 184.85)
		(end 239.674 186.624)
		(width 0.1)
		(layer "In2.Cu")
		(net 482)
	)
	(segment
		(start 216.990115 184.440115)
		(end 215.990115 184.440115)
		(width 0.1)
		(layer "In2.Cu")
		(net 482)
	)
	(segment
		(start 243.275 185.525)
		(end 243.275 168.58517)
		(width 0.1)
		(layer "In2.Cu")
		(net 482)
	)
	(segment
		(start 215.990115 184.440115)
		(end 215.4 183.85)
		(width 0.1)
		(layer "In2.Cu")
		(net 482)
	)
	(segment
		(start 217.677615 185.127615)
		(end 216.990115 184.440115)
		(width 0.1)
		(layer "In2.Cu")
		(net 482)
	)
	(segment
		(start 243.275 168.58517)
		(end 239.93983 165.25)
		(width 0.1)
		(layer "In2.Cu")
		(net 482)
	)
	(segment
		(start 227.6 184.25)
		(end 228.2 184.85)
		(width 0.1)
		(layer "In2.Cu")
		(net 482)
	)
	(segment
		(start 242.176 186.624)
		(end 243.275 185.525)
		(width 0.1)
		(layer "In2.Cu")
		(net 482)
	)
	(segment
		(start 198.0005 149.9995)
		(end 198.5 149.5)
		(width 0.256)
		(layer "F.Cu")
		(net 483)
	)
	(via
		(at 198.5 149.5)
		(size 0.45)
		(drill 0.1)
		(layers "F.Cu" "B.Cu")
		(remove_unused_layers yes)
		(keep_end_layers yes)
		(zone_layer_connections)
		(net 483)
	)
	(segment
		(start 258.7825 173.7345)
		(end 259.645 173.7345)
		(width 0.182)
		(layer "F.Cu")
		(net 484)
	)
	(via
		(at 259.645 173.7345)
		(size 0.45)
		(drill 0.1)
		(layers "F.Cu" "B.Cu")
		(remove_unused_layers yes)
		(keep_end_layers yes)
		(zone_layer_connections)
		(net 484)
	)
	(via
		(at 239.5 164.225)
		(size 0.45)
		(drill 0.1)
		(layers "F.Cu" "B.Cu")
		(remove_unused_layers yes)
		(keep_end_layers yes)
		(zone_layer_connections)
		(net 484)
	)
	(segment
		(start 239.475 164.2)
		(end 239.5 164.225)
		(width 0.182)
		(layer "B.Cu")
		(net 484)
	)
	(segment
		(start 238.936999 164.2)
		(end 239.475 164.2)
		(width 0.182)
		(layer "B.Cu")
		(net 484)
	)
	(segment
		(start 259.115499 164.515)
		(end 239.79 164.515)
		(width 0.1)
		(layer "In4.Cu")
		(net 484)
	)
	(segment
		(start 259.705312 173.7345)
		(end 260.224499 173.215313)
		(width 0.1)
		(layer "In4.Cu")
		(net 484)
	)
	(segment
		(start 259.645 173.7345)
		(end 259.705312 173.7345)
		(width 0.1)
		(layer "In4.Cu")
		(net 484)
	)
	(segment
		(start 260.224499 165.624)
		(end 259.115499 164.515)
		(width 0.1)
		(layer "In4.Cu")
		(net 484)
	)
	(segment
		(start 260.224499 173.215313)
		(end 260.224499 165.624)
		(width 0.1)
		(layer "In4.Cu")
		(net 484)
	)
	(segment
		(start 239.79 164.515)
		(end 239.5 164.225)
		(width 0.1)
		(layer "In4.Cu")
		(net 484)
	)
	(segment
		(start 259.749499 156.299)
		(end 259.733999 156.2835)
		(width 0.182)
		(layer "F.Cu")
		(net 485)
	)
	(segment
		(start 259.733999 156.2835)
		(end 258.7555 156.2835)
		(width 0.182)
		(layer "F.Cu")
		(net 485)
	)
	(via
		(at 259.749499 156.299)
		(size 0.45)
		(drill 0.1)
		(layers "F.Cu" "B.Cu")
		(remove_unused_layers yes)
		(keep_end_layers yes)
		(zone_layer_connections)
		(net 485)
	)
	(via
		(at 239.5 163.2)
		(size 0.45)
		(drill 0.1)
		(layers "F.Cu" "B.Cu")
		(remove_unused_layers yes)
		(keep_end_layers yes)
		(zone_layer_connections)
		(net 485)
	)
	(segment
		(start 239.475 163.175)
		(end 239.5 163.2)
		(width 0.182)
		(layer "B.Cu")
		(net 485)
	)
	(segment
		(start 238.936999 163.175)
		(end 239.475 163.175)
		(width 0.182)
		(layer "B.Cu")
		(net 485)
	)
	(segment
		(start 259.199499 156.849)
		(end 259.199499 162.324)
		(width 0.1)
		(layer "In4.Cu")
		(net 485)
	)
	(segment
		(start 240.155 164.305)
		(end 239.5 163.65)
		(width 0.1)
		(layer "In4.Cu")
		(net 485)
	)
	(segment
		(start 259.199499 162.324)
		(end 257.218499 164.305)
		(width 0.1)
		(layer "In4.Cu")
		(net 485)
	)
	(segment
		(start 257.218499 164.305)
		(end 240.155 164.305)
		(width 0.1)
		(layer "In4.Cu")
		(net 485)
	)
	(segment
		(start 259.749499 156.299)
		(end 259.199499 156.849)
		(width 0.1)
		(layer "In4.Cu")
		(net 485)
	)
	(segment
		(start 239.5 163.65)
		(end 239.5 163.2)
		(width 0.1)
		(layer "In4.Cu")
		(net 485)
	)
	(segment
		(start 246.903 143.1)
		(end 247.904 143.1)
		(width 0.256)
		(layer "F.Cu")
		(net 486)
	)
	(via
		(at 247.904 143.1)
		(size 0.45)
		(drill 0.1)
		(layers "F.Cu" "B.Cu")
		(remove_unused_layers yes)
		(keep_end_layers yes)
		(zone_layer_connections)
		(net 486)
	)
	(segment
		(start 249.025 143.8)
		(end 248.325 143.1)
		(width 0.15)
		(layer "B.Cu")
		(net 486)
	)
	(segment
		(start 247.894 143.09)
		(end 247.904 143.1)
		(width 0.182)
		(layer "B.Cu")
		(net 486)
	)
	(segment
		(start 252.559499 143.8)
		(end 249.025 143.8)
		(width 0.15)
		(layer "B.Cu")
		(net 486)
	)
	(segment
		(start 248.325 143.1)
		(end 247.904 143.1)
		(width 0.15)
		(layer "B.Cu")
		(net 486)
	)
	(segment
		(start 200.0005 147.9995)
		(end 200.5 147.5)
		(width 0.256)
		(layer "F.Cu")
		(net 487)
	)
	(via
		(at 200.5 147.5)
		(size 0.45)
		(drill 0.1)
		(layers "F.Cu" "B.Cu")
		(remove_unused_layers yes)
		(keep_end_layers yes)
		(zone_layer_connections)
		(net 487)
	)
	(segment
		(start 154.26 162.749999)
		(end 154.332499 162.822498)
		(width 0.16)
		(layer "F.Cu")
		(net 488)
	)
	(segment
		(start 156.237174 162.799999)
		(end 156.995 162.799999)
		(width 0.16)
		(layer "F.Cu")
		(net 488)
	)
	(segment
		(start 154.507528 162.894998)
		(end 156.007822 162.894998)
		(width 0.16)
		(layer "F.Cu")
		(net 488)
	)
	(via
		(at 154.26 162.749999)
		(size 0.45)
		(drill 0.1)
		(layers "F.Cu" "B.Cu")
		(remove_unused_layers yes)
		(keep_end_layers yes)
		(zone_layer_connections)
		(net 488)
	)
	(arc
		(start 156.007822 162.894998)
		(mid 156.069884 162.882653)
		(end 156.122498 162.847498)
		(width 0.16)
		(layer "F.Cu")
		(net 488)
	)
	(arc
		(start 154.507528 162.894998)
		(mid 154.412803 162.876155)
		(end 154.332499 162.822498)
		(width 0.16)
		(layer "F.Cu")
		(net 488)
	)
	(arc
		(start 156.122498 162.847498)
		(mid 156.175112 162.812343)
		(end 156.237174 162.799999)
		(width 0.16)
		(layer "F.Cu")
		(net 488)
	)
	(segment
		(start 174.16 153.064602)
		(end 174.16 152.196274)
		(width 0.16)
		(layer "B.Cu")
		(net 488)
	)
	(segment
		(start 157.76389 156.755)
		(end 162.27011 156.755)
		(width 0.16)
		(layer "B.Cu")
		(net 488)
	)
	(segment
		(start 153.99454 161.185)
		(end 153.986195 161.185)
		(width 0.16)
		(layer "B.Cu")
		(net 488)
	)
	(segment
		(start 154.014601 162.894998)
		(end 154.008252 162.894998)
		(width 0.16)
		(layer "B.Cu")
		(net 488)
	)
	(segment
		(start 164.201481 157.555)
		(end 169.936671 157.555)
		(width 0.16)
		(layer "B.Cu")
		(net 488)
	)
	(segment
		(start 154.26 162.749999)
		(end 154.185994 162.824004)
		(width 0.16)
		(layer "B.Cu")
		(net 488)
	)
	(segment
		(start 153.781195 160.98)
		(end 153.781195 160.737695)
		(width 0.16)
		(layer "B.Cu")
		(net 488)
	)
	(segment
		(start 153.986195 161.595)
		(end 153.99454 161.595)
		(width 0.16)
		(layer "B.Cu")
		(net 488)
	)
	(segment
		(start 171.349352 156.969849)
		(end 173.385999 154.933204)
		(width 0.16)
		(layer "B.Cu")
		(net 488)
	)
	(segment
		(start 153.781195 162.66794)
		(end 153.781195 161.8)
		(width 0.16)
		(layer "B.Cu")
		(net 488)
	)
	(segment
		(start 174.48 151.423725)
		(end 174.48 151.169999)
		(width 0.16)
		(layer "B.Cu")
		(net 488)
	)
	(arc
		(start 162.27011 156.755)
		(mid 162.792735 156.858956)
		(end 163.235796 157.155)
		(width 0.16)
		(layer "B.Cu")
		(net 488)
	)
	(arc
		(start 174.32 151.81)
		(mid 174.438417 151.632775)
		(end 174.48 151.423725)
		(width 0.16)
		(layer "B.Cu")
		(net 488)
	)
	(arc
		(start 163.235796 157.155)
		(mid 163.678856 157.451043)
		(end 164.201481 157.555)
		(width 0.16)
		(layer "B.Cu")
		(net 488)
	)
	(arc
		(start 153.99454 161.595)
		(mid 154.139497 161.534957)
		(end 154.19954 161.39)
		(width 0.16)
		(layer "B.Cu")
		(net 488)
	)
	(arc
		(start 173.385999 154.933204)
		(mid 173.958843 154.075882)
		(end 174.16 153.064602)
		(width 0.16)
		(layer "B.Cu")
		(net 488)
	)
	(arc
		(start 154.947699 157.921504)
		(mid 156.239778 157.058164)
		(end 157.76389 156.755)
		(width 0.16)
		(layer "B.Cu")
		(net 488)
	)
	(arc
		(start 153.847698 162.828494)
		(mid 153.798478 162.754831)
		(end 153.781195 162.66794)
		(width 0.16)
		(layer "B.Cu")
		(net 488)
	)
	(arc
		(start 153.986195 161.185)
		(mid 153.841238 161.124957)
		(end 153.781195 160.98)
		(width 0.16)
		(layer "B.Cu")
		(net 488)
	)
	(arc
		(start 154.008252 162.894998)
		(mid 153.92136 162.877714)
		(end 153.847698 162.828494)
		(width 0.16)
		(layer "B.Cu")
		(net 488)
	)
	(arc
		(start 153.781195 160.737695)
		(mid 154.084359 159.213583)
		(end 154.947699 157.921504)
		(width 0.16)
		(layer "B.Cu")
		(net 488)
	)
	(arc
		(start 169.936671 157.555)
		(mid 170.701208 157.402924)
		(end 171.349352 156.969849)
		(width 0.16)
		(layer "B.Cu")
		(net 488)
	)
	(arc
		(start 154.19954 161.39)
		(mid 154.139497 161.245043)
		(end 153.99454 161.185)
		(width 0.16)
		(layer "B.Cu")
		(net 488)
	)
	(arc
		(start 153.781195 161.8)
		(mid 153.841238 161.655043)
		(end 153.986195 161.595)
		(width 0.16)
		(layer "B.Cu")
		(net 488)
	)
	(arc
		(start 174.16 152.196274)
		(mid 174.201582 151.987224)
		(end 174.32 151.81)
		(width 0.16)
		(layer "B.Cu")
		(net 488)
	)
	(arc
		(start 154.185994 162.824004)
		(mid 154.107358 162.876547)
		(end 154.014601 162.894998)
		(width 0.16)
		(layer "B.Cu")
		(net 488)
	)
	(segment
		(start 154.26 163.349999)
		(end 154.332499 163.277499)
		(width 0.16)
		(layer "F.Cu")
		(net 489)
	)
	(segment
		(start 156.237174 163.299999)
		(end 156.995 163.299999)
		(width 0.16)
		(layer "F.Cu")
		(net 489)
	)
	(segment
		(start 154.507528 163.205)
		(end 156.007822 163.205)
		(width 0.16)
		(layer "F.Cu")
		(net 489)
	)
	(via
		(at 154.26 163.349999)
		(size 0.45)
		(drill 0.1)
		(layers "F.Cu" "B.Cu")
		(remove_unused_layers yes)
		(keep_end_layers yes)
		(zone_layer_connections)
		(net 489)
	)
	(arc
		(start 156.122498 163.252499)
		(mid 156.069884 163.217344)
		(end 156.007822 163.205)
		(width 0.16)
		(layer "F.Cu")
		(net 489)
	)
	(arc
		(start 156.122498 163.252499)
		(mid 156.175112 163.287654)
		(end 156.237174 163.299999)
		(width 0.16)
		(layer "F.Cu")
		(net 489)
	)
	(arc
		(start 154.332499 163.277499)
		(mid 154.412803 163.223841)
		(end 154.507528 163.205)
		(width 0.16)
		(layer "F.Cu")
		(net 489)
	)
	(segment
		(start 173.121398 154.759397)
		(end 171.139424 156.741369)
		(width 0.16)
		(layer "B.Cu")
		(net 489)
	)
	(segment
		(start 153.628495 163.047699)
		(end 153.669404 163.088608)
		(width 0.16)
		(layer "B.Cu")
		(net 489)
	)
	(segment
		(start 169.923549 157.245)
		(end 164.329889 157.245)
		(width 0.16)
		(layer "B.Cu")
		(net 489)
	)
	(segment
		(start 173.85 152.196274)
		(end 173.85 153.000398)
		(width 0.16)
		(layer "B.Cu")
		(net 489)
	)
	(segment
		(start 154.26 163.349999)
		(end 154.1875 163.277499)
		(width 0.16)
		(layer "B.Cu")
		(net 489)
	)
	(segment
		(start 173.53 151.423725)
		(end 173.53 151.169999)
		(width 0.16)
		(layer "B.Cu")
		(net 489)
	)
	(segment
		(start 162.398518 156.445)
		(end 157.763887 156.445)
		(width 0.16)
		(layer "B.Cu")
		(net 489)
	)
	(segment
		(start 153.950398 163.205)
		(end 154.012471 163.205)
		(width 0.16)
		(layer "B.Cu")
		(net 489)
	)
	(segment
		(start 153.471195 160.737692)
		(end 153.471195 162.667942)
		(width 0.16)
		(layer "B.Cu")
		(net 489)
	)
	(arc
		(start 163.364204 156.845)
		(mid 163.807264 157.141043)
		(end 164.329889 157.245)
		(width 0.16)
		(layer "B.Cu")
		(net 489)
	)
	(arc
		(start 154.728495 157.7023)
		(mid 156.121144 156.771761)
		(end 157.763887 156.445)
		(width 0.16)
		(layer "B.Cu")
		(net 489)
	)
	(arc
		(start 153.628495 163.047699)
		(mid 153.512075 162.873465)
		(end 153.471195 162.667942)
		(width 0.16)
		(layer "B.Cu")
		(net 489)
	)
	(arc
		(start 173.69 151.81)
		(mid 173.571582 151.632775)
		(end 173.53 151.423725)
		(width 0.16)
		(layer "B.Cu")
		(net 489)
	)
	(arc
		(start 173.121398 154.759397)
		(mid 173.660642 153.952361)
		(end 173.85 153.000398)
		(width 0.16)
		(layer "B.Cu")
		(net 489)
	)
	(arc
		(start 169.923549 157.245)
		(mid 170.581576 157.114111)
		(end 171.139424 156.741369)
		(width 0.16)
		(layer "B.Cu")
		(net 489)
	)
	(arc
		(start 173.69 151.81)
		(mid 173.808417 151.987224)
		(end 173.85 152.196274)
		(width 0.16)
		(layer "B.Cu")
		(net 489)
	)
	(arc
		(start 162.398518 156.445)
		(mid 162.921143 156.548956)
		(end 163.364204 156.845)
		(width 0.16)
		(layer "B.Cu")
		(net 489)
	)
	(arc
		(start 153.669404 163.088608)
		(mid 153.798325 163.17475)
		(end 153.950398 163.205)
		(width 0.16)
		(layer "B.Cu")
		(net 489)
	)
	(arc
		(start 154.1875 163.277499)
		(mid 154.107196 163.223841)
		(end 154.012471 163.205)
		(width 0.16)
		(layer "B.Cu")
		(net 489)
	)
	(arc
		(start 154.728495 157.7023)
		(mid 153.797956 159.094949)
		(end 153.471195 160.737692)
		(width 0.16)
		(layer "B.Cu")
		(net 489)
	)
	(segment
		(start 201.0005 145.9995)
		(end 201.5 145.5)
		(width 0.256)
		(layer "F.Cu")
		(net 491)
	)
	(via
		(at 201.5 145.5)
		(size 0.45)
		(drill 0.1)
		(layers "F.Cu" "B.Cu")
		(remove_unused_layers yes)
		(keep_end_layers yes)
		(zone_layer_connections)
		(net 491)
	)
	(segment
		(start 176.999499 165.0005)
		(end 176.5 165.5)
		(width 0.256)
		(layer "F.Cu")
		(net 492)
	)
	(via
		(at 176.5 165.5)
		(size 0.45)
		(drill 0.1)
		(layers "F.Cu" "B.Cu")
		(remove_unused_layers yes)
		(keep_end_layers yes)
		(zone_layer_connections)
		(net 492)
	)
	(segment
		(start 176.9995 164.0005)
		(end 176.500001 164.5)
		(width 0.256)
		(layer "F.Cu")
		(net 493)
	)
	(via
		(at 176.500001 164.5)
		(size 0.45)
		(drill 0.1)
		(layers "F.Cu" "B.Cu")
		(remove_unused_layers yes)
		(keep_end_layers yes)
		(zone_layer_connections)
		(net 493)
	)
	(segment
		(start 176.999499 160.0005)
		(end 176.5 160.499999)
		(width 0.256)
		(layer "F.Cu")
		(net 494)
	)
	(via
		(at 176.5 160.499999)
		(size 0.45)
		(drill 0.1)
		(layers "F.Cu" "B.Cu")
		(remove_unused_layers yes)
		(keep_end_layers yes)
		(zone_layer_connections)
		(net 494)
	)
	(segment
		(start 176.9995 159.0005)
		(end 176.5 159.500001)
		(width 0.256)
		(layer "F.Cu")
		(net 495)
	)
	(via
		(at 176.5 159.500001)
		(size 0.45)
		(drill 0.1)
		(layers "F.Cu" "B.Cu")
		(remove_unused_layers yes)
		(keep_end_layers yes)
		(zone_layer_connections)
		(net 495)
	)
	(via
		(at 105.824499 162.349)
		(size 0.45)
		(drill 0.1)
		(layers "F.Cu" "B.Cu")
		(remove_unused_layers yes)
		(keep_end_layers yes)
		(zone_layer_connections)
		(net 496)
	)
	(segment
		(start 176.999499 156.0005)
		(end 176.5 156.5)
		(width 0.256)
		(layer "F.Cu")
		(net 497)
	)
	(via
		(at 176.5 156.5)
		(size 0.45)
		(drill 0.1)
		(layers "F.Cu" "B.Cu")
		(remove_unused_layers yes)
		(keep_end_layers yes)
		(zone_layer_connections)
		(net 497)
	)
	(segment
		(start 176.9995 155.0005)
		(end 176.500001 155.5)
		(width 0.256)
		(layer "F.Cu")
		(net 498)
	)
	(via
		(at 176.500001 155.5)
		(size 0.45)
		(drill 0.1)
		(layers "F.Cu" "B.Cu")
		(remove_unused_layers yes)
		(keep_end_layers yes)
		(zone_layer_connections)
		(net 498)
	)
	(segment
		(start 110.452 163.368)
		(end 111.12 162.7)
		(width 0.15)
		(layer "B.Cu")
		(net 499)
	)
	(segment
		(start 118.35 166.36)
		(end 118.35 164.16)
		(width 0.15)
		(layer "B.Cu")
		(net 499)
	)
	(segment
		(start 105.17 163.368)
		(end 108.189 163.368)
		(width 0.201)
		(layer "B.Cu")
		(net 499)
	)
	(segment
		(start 108.191 163.368)
		(end 110.452 163.368)
		(width 0.15)
		(layer "B.Cu")
		(net 499)
	)
	(segment
		(start 116.89 162.7)
		(end 118.35 164.16)
		(width 0.15)
		(layer "B.Cu")
		(net 499)
	)
	(segment
		(start 111.12 162.7)
		(end 116.89 162.7)
		(width 0.15)
		(layer "B.Cu")
		(net 499)
	)
	(segment
		(start 176.9995 154.0005)
		(end 176.5 154.5)
		(width 0.256)
		(layer "F.Cu")
		(net 500)
	)
	(via
		(at 176.5 154.5)
		(size 0.45)
		(drill 0.1)
		(layers "F.Cu" "B.Cu")
		(remove_unused_layers yes)
		(keep_end_layers yes)
		(zone_layer_connections)
		(net 500)
	)
	(via
		(at 116.45 167.91)
		(size 0.45)
		(drill 0.1)
		(layers "F.Cu" "B.Cu")
		(remove_unused_layers yes)
		(keep_end_layers yes)
		(zone_layer_connections)
		(net 500)
	)
	(segment
		(start 115.82 167.911)
		(end 116.449 167.911)
		(width 0.201)
		(layer "B.Cu")
		(net 500)
	)
	(segment
		(start 116.449 167.911)
		(end 116.45 167.91)
		(width 0.201)
		(layer "B.Cu")
		(net 500)
	)
	(segment
		(start 115.82 167.911)
		(end 115.82 168.82)
		(width 0.201)
		(layer "B.Cu")
		(net 500)
	)
	(segment
		(start 170.375 154.1)
		(end 167.975 156.5)
		(width 0.1)
		(layer "In9.Cu")
		(net 500)
	)
	(segment
		(start 176.1 154.1)
		(end 170.375 154.1)
		(width 0.1)
		(layer "In9.Cu")
		(net 500)
	)
	(segment
		(start 176.5 154.5)
		(end 176.1 154.1)
		(width 0.1)
		(layer "In9.Cu")
		(net 500)
	)
	(segment
		(start 143.8 158.6)
		(end 141 158.6)
		(width 0.1)
		(layer "In9.Cu")
		(net 500)
	)
	(segment
		(start 157.5 156.5)
		(end 157.1 156.1)
		(width 0.1)
		(layer "In9.Cu")
		(net 500)
	)
	(segment
		(start 144.5 157.9)
		(end 143.8 158.6)
		(width 0.1)
		(layer "In9.Cu")
		(net 500)
	)
	(segment
		(start 128.2 170.1)
		(end 118.64 170.1)
		(width 0.1)
		(layer "In9.Cu")
		(net 500)
	)
	(segment
		(start 151.06 157.9)
		(end 144.5 157.9)
		(width 0.1)
		(layer "In9.Cu")
		(net 500)
	)
	(segment
		(start 136.6 161.7)
		(end 128.2 170.1)
		(width 0.1)
		(layer "In9.Cu")
		(net 500)
	)
	(segment
		(start 167.975 156.5)
		(end 157.5 156.5)
		(width 0.1)
		(layer "In9.Cu")
		(net 500)
	)
	(segment
		(start 152.86 156.1)
		(end 151.06 157.9)
		(width 0.1)
		(layer "In9.Cu")
		(net 500)
	)
	(segment
		(start 118.64 170.1)
		(end 116.45 167.91)
		(width 0.1)
		(layer "In9.Cu")
		(net 500)
	)
	(segment
		(start 141 158.6)
		(end 137.9 161.7)
		(width 0.1)
		(layer "In9.Cu")
		(net 500)
	)
	(segment
		(start 137.9 161.7)
		(end 136.6 161.7)
		(width 0.1)
		(layer "In9.Cu")
		(net 500)
	)
	(segment
		(start 157.1 156.1)
		(end 152.86 156.1)
		(width 0.1)
		(layer "In9.Cu")
		(net 500)
	)
	(segment
		(start 176.9995 143.9995)
		(end 176.5 143.5)
		(width 0.256)
		(layer "F.Cu")
		(net 501)
	)
	(via
		(at 176.5 143.5)
		(size 0.45)
		(drill 0.1)
		(layers "F.Cu" "B.Cu")
		(remove_unused_layers yes)
		(keep_end_layers yes)
		(zone_layer_connections)
		(net 501)
	)
	(segment
		(start 177.9995 163.0005)
		(end 177.5 163.5)
		(width 0.256)
		(layer "F.Cu")
		(net 502)
	)
	(via
		(at 177.5 163.5)
		(size 0.45)
		(drill 0.1)
		(layers "F.Cu" "B.Cu")
		(remove_unused_layers yes)
		(keep_end_layers yes)
		(zone_layer_connections)
		(net 502)
	)
	(segment
		(start 177.9995 162.0005)
		(end 177.5 162.5)
		(width 0.256)
		(layer "F.Cu")
		(net 503)
	)
	(via
		(at 177.5 162.5)
		(size 0.45)
		(drill 0.1)
		(layers "F.Cu" "B.Cu")
		(remove_unused_layers yes)
		(keep_end_layers yes)
		(zone_layer_connections)
		(net 503)
	)
	(segment
		(start 177.9995 155.0005)
		(end 177.5 155.5)
		(width 0.256)
		(layer "F.Cu")
		(net 505)
	)
	(via
		(at 177.5 155.5)
		(size 0.45)
		(drill 0.1)
		(layers "F.Cu" "B.Cu")
		(remove_unused_layers yes)
		(keep_end_layers yes)
		(zone_layer_connections)
		(net 505)
	)
	(via
		(at 115.579499 165.614)
		(size 0.45)
		(drill 0.1)
		(layers "F.Cu" "B.Cu")
		(remove_unused_layers yes)
		(keep_end_layers yes)
		(zone_layer_connections)
		(net 506)
	)
	(segment
		(start 113.431 165.82)
		(end 115.16 165.82)
		(width 0.201)
		(layer "B.Cu")
		(net 506)
	)
	(segment
		(start 115.16 165.82)
		(end 115.17 165.81)
		(width 0.201)
		(layer "B.Cu")
		(net 506)
	)
	(segment
		(start 112.46 166.791)
		(end 113.431 165.82)
		(width 0.201)
		(layer "B.Cu")
		(net 506)
	)
	(segment
		(start 112.46 168.37)
		(end 112.46 166.791)
		(width 0.201)
		(layer "B.Cu")
		(net 506)
	)
	(segment
		(start 180.9995 151.999499)
		(end 180.5 151.5)
		(width 0.256)
		(layer "F.Cu")
		(net 507)
	)
	(via
		(at 116.92 163.97)
		(size 0.45)
		(drill 0.1)
		(layers "F.Cu" "B.Cu")
		(remove_unused_layers yes)
		(keep_end_layers yes)
		(zone_layer_connections)
		(net 507)
	)
	(via
		(at 180.5 151.5)
		(size 0.45)
		(drill 0.1)
		(layers "F.Cu" "B.Cu")
		(remove_unused_layers yes)
		(keep_end_layers yes)
		(zone_layer_connections)
		(net 507)
	)
	(segment
		(start 116.92 163.97)
		(end 116.26 163.97)
		(width 0.201)
		(layer "B.Cu")
		(net 507)
	)
	(segment
		(start 115.32 163.97)
		(end 116.26 163.97)
		(width 0.201)
		(layer "B.Cu")
		(net 507)
	)
	(segment
		(start 180.05 151.05)
		(end 180.5 151.5)
		(width 0.1)
		(layer "In9.Cu")
		(net 507)
	)
	(segment
		(start 168.294668 153.775)
		(end 168.444669 153.624999)
		(width 0.1)
		(layer "In9.Cu")
		(net 507)
	)
	(segment
		(start 171.33033 151.05)
		(end 180.05 151.05)
		(width 0.1)
		(layer "In9.Cu")
		(net 507)
	)
	(segment
		(start 122.73 163.97)
		(end 130 156.7)
		(width 0.1)
		(layer "In9.Cu")
		(net 507)
	)
	(segment
		(start 145.6 156.5)
		(end 150.6 156.5)
		(width 0.1)
		(layer "In9.Cu")
		(net 507)
	)
	(segment
		(start 144.343835 156.107)
		(end 145.207 156.107)
		(width 0.1)
		(layer "In9.Cu")
		(net 507)
	)
	(segment
		(start 132.65 156.7)
		(end 133.3 156.05)
		(width 0.1)
		(layer "In9.Cu")
		(net 507)
	)
	(segment
		(start 144.000835 156.45)
		(end 144.343835 156.107)
		(width 0.1)
		(layer "In9.Cu")
		(net 507)
	)
	(segment
		(start 133.3 156.05)
		(end 140.05 156.05)
		(width 0.1)
		(layer "In9.Cu")
		(net 507)
	)
	(segment
		(start 164.444668 153.625)
		(end 167.755331 153.625)
		(width 0.1)
		(layer "In9.Cu")
		(net 507)
	)
	(segment
		(start 167.905331 153.775)
		(end 168.294668 153.775)
		(width 0.1)
		(layer "In9.Cu")
		(net 507)
	)
	(segment
		(start 140.45 156.45)
		(end 144.000835 156.45)
		(width 0.1)
		(layer "In9.Cu")
		(net 507)
	)
	(segment
		(start 130 156.7)
		(end 132.65 156.7)
		(width 0.1)
		(layer "In9.Cu")
		(net 507)
	)
	(segment
		(start 145.207 156.107)
		(end 145.6 156.5)
		(width 0.1)
		(layer "In9.Cu")
		(net 507)
	)
	(segment
		(start 140.05 156.05)
		(end 140.45 156.45)
		(width 0.1)
		(layer "In9.Cu")
		(net 507)
	)
	(segment
		(start 168.755331 153.624999)
		(end 171.33033 151.05)
		(width 0.1)
		(layer "In9.Cu")
		(net 507)
	)
	(segment
		(start 164.294668 153.775)
		(end 164.444668 153.625)
		(width 0.1)
		(layer "In9.Cu")
		(net 507)
	)
	(segment
		(start 167.755331 153.625)
		(end 167.905331 153.775)
		(width 0.1)
		(layer "In9.Cu")
		(net 507)
	)
	(segment
		(start 150.6 156.5)
		(end 153.325 153.775)
		(width 0.1)
		(layer "In9.Cu")
		(net 507)
	)
	(segment
		(start 116.92 163.97)
		(end 122.73 163.97)
		(width 0.1)
		(layer "In9.Cu")
		(net 507)
	)
	(segment
		(start 168.444669 153.624999)
		(end 168.755331 153.624999)
		(width 0.1)
		(layer "In9.Cu")
		(net 507)
	)
	(segment
		(start 153.325 153.775)
		(end 164.294668 153.775)
		(width 0.1)
		(layer "In9.Cu")
		(net 507)
	)
	(segment
		(start 177.9995 147.9995)
		(end 177.5 147.5)
		(width 0.256)
		(layer "F.Cu")
		(net 508)
	)
	(via
		(at 177.5 147.5)
		(size 0.45)
		(drill 0.1)
		(layers "F.Cu" "B.Cu")
		(remove_unused_layers yes)
		(keep_end_layers yes)
		(zone_layer_connections)
		(net 508)
	)
	(segment
		(start 177.9995 146.9995)
		(end 177.5 146.5)
		(width 0.256)
		(layer "F.Cu")
		(net 509)
	)
	(via
		(at 177.5 146.5)
		(size 0.45)
		(drill 0.1)
		(layers "F.Cu" "B.Cu")
		(remove_unused_layers yes)
		(keep_end_layers yes)
		(zone_layer_connections)
		(net 509)
	)
	(segment
		(start 178.9995 165.0005)
		(end 178.5 165.5)
		(width 0.256)
		(layer "F.Cu")
		(net 510)
	)
	(via
		(at 178.5 165.5)
		(size 0.45)
		(drill 0.1)
		(layers "F.Cu" "B.Cu")
		(remove_unused_layers yes)
		(keep_end_layers yes)
		(zone_layer_connections)
		(net 510)
	)
	(segment
		(start 178.9995 164.0005)
		(end 178.5 164.5)
		(width 0.256)
		(layer "F.Cu")
		(net 511)
	)
	(via
		(at 178.5 164.5)
		(size 0.45)
		(drill 0.1)
		(layers "F.Cu" "B.Cu")
		(remove_unused_layers yes)
		(keep_end_layers yes)
		(zone_layer_connections)
		(net 511)
	)
	(segment
		(start 178.9995 160.0005)
		(end 178.5 160.5)
		(width 0.256)
		(layer "F.Cu")
		(net 512)
	)
	(via
		(at 178.5 160.5)
		(size 0.45)
		(drill 0.1)
		(layers "F.Cu" "B.Cu")
		(remove_unused_layers yes)
		(keep_end_layers yes)
		(zone_layer_connections)
		(net 512)
	)
	(segment
		(start 178.9995 159.0005)
		(end 178.5 159.5)
		(width 0.256)
		(layer "F.Cu")
		(net 513)
	)
	(via
		(at 178.5 159.5)
		(size 0.45)
		(drill 0.1)
		(layers "F.Cu" "B.Cu")
		(remove_unused_layers yes)
		(keep_end_layers yes)
		(zone_layer_connections)
		(net 513)
	)
	(segment
		(start 178.9995 155.0005)
		(end 178.5 155.5)
		(width 0.256)
		(layer "F.Cu")
		(net 514)
	)
	(via
		(at 178.5 155.5)
		(size 0.45)
		(drill 0.1)
		(layers "F.Cu" "B.Cu")
		(remove_unused_layers yes)
		(keep_end_layers yes)
		(zone_layer_connections)
		(net 514)
	)
	(segment
		(start 178.9995 153.000501)
		(end 178.500001 153.5)
		(width 0.256)
		(layer "F.Cu")
		(net 515)
	)
	(via
		(at 178.500001 153.5)
		(size 0.45)
		(drill 0.1)
		(layers "F.Cu" "B.Cu")
		(remove_unused_layers yes)
		(keep_end_layers yes)
		(zone_layer_connections)
		(net 515)
	)
	(segment
		(start 179.9995 162.0005)
		(end 179.499999 162.5)
		(width 0.256)
		(layer "F.Cu")
		(net 516)
	)
	(via
		(at 179.499999 162.5)
		(size 0.45)
		(drill 0.1)
		(layers "F.Cu" "B.Cu")
		(remove_unused_layers yes)
		(keep_end_layers yes)
		(zone_layer_connections)
		(net 516)
	)
	(segment
		(start 179.9995 161.0005)
		(end 179.5 161.5)
		(width 0.256)
		(layer "F.Cu")
		(net 517)
	)
	(via
		(at 179.5 161.5)
		(size 0.45)
		(drill 0.1)
		(layers "F.Cu" "B.Cu")
		(remove_unused_layers yes)
		(keep_end_layers yes)
		(zone_layer_connections)
		(net 517)
	)
	(segment
		(start 179.9995 156.0005)
		(end 179.5 156.5)
		(width 0.256)
		(layer "F.Cu")
		(net 518)
	)
	(via
		(at 179.5 156.5)
		(size 0.45)
		(drill 0.1)
		(layers "F.Cu" "B.Cu")
		(remove_unused_layers yes)
		(keep_end_layers yes)
		(zone_layer_connections)
		(net 518)
	)
	(segment
		(start 179.9995 155.0005)
		(end 179.5 155.5)
		(width 0.256)
		(layer "F.Cu")
		(net 519)
	)
	(via
		(at 179.5 155.5)
		(size 0.45)
		(drill 0.1)
		(layers "F.Cu" "B.Cu")
		(remove_unused_layers yes)
		(keep_end_layers yes)
		(zone_layer_connections)
		(net 519)
	)
	(segment
		(start 179.9995 154.0005)
		(end 179.5 154.5)
		(width 0.256)
		(layer "F.Cu")
		(net 520)
	)
	(via
		(at 179.5 154.5)
		(size 0.45)
		(drill 0.1)
		(layers "F.Cu" "B.Cu")
		(remove_unused_layers yes)
		(keep_end_layers yes)
		(zone_layer_connections)
		(net 520)
	)
	(segment
		(start 179.9995 143.9995)
		(end 179.5 143.5)
		(width 0.256)
		(layer "F.Cu")
		(net 521)
	)
	(via
		(at 179.5 143.5)
		(size 0.45)
		(drill 0.1)
		(layers "F.Cu" "B.Cu")
		(remove_unused_layers yes)
		(keep_end_layers yes)
		(zone_layer_connections)
		(net 521)
	)
	(segment
		(start 181 165)
		(end 180.5005 165.4995)
		(width 0.256)
		(layer "F.Cu")
		(net 522)
	)
	(via
		(at 180.5005 165.4995)
		(size 0.45)
		(drill 0.1)
		(layers "F.Cu" "B.Cu")
		(remove_unused_layers yes)
		(keep_end_layers yes)
		(zone_layer_connections)
		(net 522)
	)
	(segment
		(start 181 164)
		(end 180.5005 164.4995)
		(width 0.256)
		(layer "F.Cu")
		(net 523)
	)
	(via
		(at 180.5005 164.4995)
		(size 0.45)
		(drill 0.1)
		(layers "F.Cu" "B.Cu")
		(remove_unused_layers yes)
		(keep_end_layers yes)
		(zone_layer_connections)
		(net 523)
	)
	(segment
		(start 180.9995 160.000501)
		(end 180.5 160.5)
		(width 0.256)
		(layer "F.Cu")
		(net 524)
	)
	(via
		(at 180.5 160.5)
		(size 0.45)
		(drill 0.1)
		(layers "F.Cu" "B.Cu")
		(remove_unused_layers yes)
		(keep_end_layers yes)
		(zone_layer_connections)
		(net 524)
	)
	(segment
		(start 180.9995 159.0005)
		(end 180.5 159.5)
		(width 0.256)
		(layer "F.Cu")
		(net 525)
	)
	(via
		(at 180.5 159.5)
		(size 0.45)
		(drill 0.1)
		(layers "F.Cu" "B.Cu")
		(remove_unused_layers yes)
		(keep_end_layers yes)
		(zone_layer_connections)
		(net 525)
	)
	(segment
		(start 148.7 173.625)
		(end 149.265499 173.625)
		(width 0.1)
		(layer "F.Cu")
		(net 526)
	)
	(segment
		(start 235.974499 182.599)
		(end 236.381498 183.005999)
		(width 0.177)
		(layer "F.Cu")
		(net 526)
	)
	(segment
		(start 149.265499 173.625)
		(end 149.374499 173.734)
		(width 0.1)
		(layer "F.Cu")
		(net 526)
	)
	(segment
		(start 150.424499 173.734)
		(end 149.374499 173.734)
		(width 0.15)
		(layer "F.Cu")
		(net 526)
	)
	(segment
		(start 236.381498 183.005999)
		(end 237.902499 183.005999)
		(width 0.177)
		(layer "F.Cu")
		(net 526)
	)
	(via
		(at 235.974499 182.599)
		(size 0.45)
		(drill 0.1)
		(layers "F.Cu" "B.Cu")
		(remove_unused_layers yes)
		(keep_end_layers yes)
		(zone_layer_connections)
		(net 526)
	)
	(via
		(at 148.7 173.625)
		(size 0.45)
		(drill 0.1)
		(layers "F.Cu" "B.Cu")
		(remove_unused_layers yes)
		(keep_end_layers yes)
		(zone_layer_connections)
		(net 526)
	)
	(segment
		(start 235.974499 182.599)
		(end 236.374499 182.599)
		(width 0.15)
		(layer "B.Cu")
		(net 526)
	)
	(segment
		(start 236.374499 182.599)
		(end 237.224499 181.749)
		(width 0.15)
		(layer "B.Cu")
		(net 526)
	)
	(segment
		(start 237.224499 181.749)
		(end 237.224499 181.164)
		(width 0.15)
		(layer "B.Cu")
		(net 526)
	)
	(segment
		(start 237.224499 181.164)
		(end 237.939499 180.449)
		(width 0.15)
		(layer "B.Cu")
		(net 526)
	)
	(segment
		(start 155.4475 180.3725)
		(end 155.4475 182.0375)
		(width 0.1)
		(layer "In4.Cu")
		(net 526)
	)
	(segment
		(start 208.765 177.325)
		(end 233.000499 177.325)
		(width 0.1)
		(layer "In4.Cu")
		(net 526)
	)
	(segment
		(start 148.7 173.625)
		(end 155.4475 180.3725)
		(width 0.1)
		(layer "In4.Cu")
		(net 526)
	)
	(segment
		(start 235.124499 182.199499)
		(end 235.524 182.599)
		(width 0.1)
		(layer "In4.Cu")
		(net 526)
	)
	(segment
		(start 155.4475 182.0375)
		(end 156.82 183.41)
		(width 0.1)
		(layer "In4.Cu")
		(net 526)
	)
	(segment
		(start 235.524 182.599)
		(end 235.974499 182.599)
		(width 0.1)
		(layer "In4.Cu")
		(net 526)
	)
	(segment
		(start 202.68 183.41)
		(end 208.765 177.325)
		(width 0.1)
		(layer "In4.Cu")
		(net 526)
	)
	(segment
		(start 235.124499 179.449)
		(end 235.124499 182.199499)
		(width 0.1)
		(layer "In4.Cu")
		(net 526)
	)
	(segment
		(start 156.82 183.41)
		(end 202.68 183.41)
		(width 0.1)
		(layer "In4.Cu")
		(net 526)
	)
	(segment
		(start 233.000499 177.325)
		(end 235.124499 179.449)
		(width 0.1)
		(layer "In4.Cu")
		(net 526)
	)
	(segment
		(start 146.268499 173.625)
		(end 146.174499 173.719)
		(width 0.1)
		(layer "F.Cu")
		(net 527)
	)
	(segment
		(start 146.84 173.625)
		(end 146.268499 173.625)
		(width 0.1)
		(layer "F.Cu")
		(net 527)
	)
	(segment
		(start 145.124499 173.734)
		(end 146.159499 173.734)
		(width 0.15)
		(layer "F.Cu")
		(net 527)
	)
	(segment
		(start 236.629499 186.762)
		(end 236.635499 186.756)
		(width 0.177)
		(layer "F.Cu")
		(net 527)
	)
	(segment
		(start 146.159499 173.734)
		(end 146.174499 173.719)
		(width 0.15)
		(layer "F.Cu")
		(net 527)
	)
	(segment
		(start 236.635499 186.756)
		(end 237.902499 186.755999)
		(width 0.177)
		(layer "F.Cu")
		(net 527)
	)
	(via
		(at 146.84 173.625)
		(size 0.45)
		(drill 0.1)
		(layers "F.Cu" "B.Cu")
		(remove_unused_layers yes)
		(keep_end_layers yes)
		(zone_layer_connections)
		(net 527)
	)
	(via
		(at 236.629499 186.762)
		(size 0.45)
		(drill 0.1)
		(layers "F.Cu" "B.Cu")
		(remove_unused_layers yes)
		(keep_end_layers yes)
		(zone_layer_connections)
		(net 527)
	)
	(segment
		(start 237.939499 187.849)
		(end 237.074499 187.849)
		(width 0.15)
		(layer "B.Cu")
		(net 527)
	)
	(segment
		(start 236.629499 187.404)
		(end 236.629499 186.762)
		(width 0.15)
		(layer "B.Cu")
		(net 527)
	)
	(segment
		(start 237.074499 187.849)
		(end 236.629499 187.404)
		(width 0.15)
		(layer "B.Cu")
		(net 527)
	)
	(segment
		(start 235.820499 183.795)
		(end 235.820499 185.953)
		(width 0.1)
		(layer "In4.Cu")
		(net 527)
	)
	(segment
		(start 155.79 184.02)
		(end 203.18 184.02)
		(width 0.1)
		(layer "In4.Cu")
		(net 527)
	)
	(segment
		(start 147.495 173.625)
		(end 154.425 180.555)
		(width 0.1)
		(layer "In4.Cu")
		(net 527)
	)
	(segment
		(start 154.425 182.655)
		(end 155.79 184.02)
		(width 0.1)
		(layer "In4.Cu")
		(net 527)
	)
	(segment
		(start 154.425 180.555)
		(end 154.425 182.655)
		(width 0.1)
		(layer "In4.Cu")
		(net 527)
	)
	(segment
		(start 234.81275 179.46275)
		(end 234.81275 182.78725)
		(width 0.1)
		(layer "In4.Cu")
		(net 527)
	)
	(segment
		(start 232.975 177.625)
		(end 234.81275 179.46275)
		(width 0.1)
		(layer "In4.Cu")
		(net 527)
	)
	(segment
		(start 234.81275 182.78725)
		(end 235.820499 183.795)
		(width 0.1)
		(layer "In4.Cu")
		(net 527)
	)
	(segment
		(start 209.575 177.625)
		(end 232.975 177.625)
		(width 0.1)
		(layer "In4.Cu")
		(net 527)
	)
	(segment
		(start 235.820499 185.953)
		(end 236.629499 186.762)
		(width 0.1)
		(layer "In4.Cu")
		(net 527)
	)
	(segment
		(start 146.84 173.625)
		(end 147.495 173.625)
		(width 0.1)
		(layer "In4.Cu")
		(net 527)
	)
	(segment
		(start 203.18 184.02)
		(end 209.575 177.625)
		(width 0.1)
		(layer "In4.Cu")
		(net 527)
	)
	(segment
		(start 181.9995 154.0005)
		(end 181.5 154.5)
		(width 0.256)
		(layer "F.Cu")
		(net 528)
	)
	(segment
		(start 245.251 184.75)
		(end 245.2 184.699)
		(width 0.182)
		(layer "F.Cu")
		(net 528)
	)
	(segment
		(start 245.88 184.75)
		(end 245.251 184.75)
		(width 0.182)
		(layer "F.Cu")
		(net 528)
	)
	(via
		(at 181.5 154.5)
		(size 0.45)
		(drill 0.1)
		(layers "F.Cu" "B.Cu")
		(remove_unused_layers yes)
		(keep_end_layers yes)
		(zone_layer_connections)
		(net 528)
	)
	(via
		(at 245.2 184.699)
		(size 0.45)
		(drill 0.1)
		(layers "F.Cu" "B.Cu")
		(remove_unused_layers yes)
		(keep_end_layers yes)
		(zone_layer_connections)
		(net 528)
	)
	(segment
		(start 246.995 185.299)
		(end 246.395 184.699)
		(width 0.182)
		(layer "B.Cu")
		(net 528)
	)
	(segment
		(start 246.395 184.699)
		(end 245.2 184.699)
		(width 0.182)
		(layer "B.Cu")
		(net 528)
	)
	(segment
		(start 171.5 166)
		(end 171.5 174.5)
		(width 0.1)
		(layer "In2.Cu")
		(net 528)
	)
	(segment
		(start 222.975 185.475)
		(end 223.505 186.005)
		(width 0.1)
		(layer "In2.Cu")
		(net 528)
	)
	(segment
		(start 242.663 187.637)
		(end 244.175 186.125)
		(width 0.1)
		(layer "In2.Cu")
		(net 528)
	)
	(segment
		(start 182 155)
		(end 182 163.530331)
		(width 0.1)
		(layer "In2.Cu")
		(net 528)
	)
	(segment
		(start 244.175 185.35)
		(end 244.826 184.699)
		(width 0.1)
		(layer "In2.Cu")
		(net 528)
	)
	(segment
		(start 226.895 186.005)
		(end 227.5 185.4)
		(width 0.1)
		(layer "In2.Cu")
		(net 528)
	)
	(segment
		(start 244.175 186.125)
		(end 244.175 185.35)
		(width 0.1)
		(layer "In2.Cu")
		(net 528)
	)
	(segment
		(start 181.530331 164)
		(end 173.5 164)
		(width 0.1)
		(layer "In2.Cu")
		(net 528)
	)
	(segment
		(start 244.826 184.699)
		(end 245.2 184.699)
		(width 0.1)
		(layer "In2.Cu")
		(net 528)
	)
	(segment
		(start 173 176)
		(end 184 176)
		(width 0.1)
		(layer "In2.Cu")
		(net 528)
	)
	(segment
		(start 227.5 185.4)
		(end 234.1 185.4)
		(width 0.1)
		(layer "In2.Cu")
		(net 528)
	)
	(segment
		(start 184 176)
		(end 193 185)
		(width 0.1)
		(layer "In2.Cu")
		(net 528)
	)
	(segment
		(start 236.337 187.637)
		(end 242.663 187.637)
		(width 0.1)
		(layer "In2.Cu")
		(net 528)
	)
	(segment
		(start 223.505 186.005)
		(end 226.895 186.005)
		(width 0.1)
		(layer "In2.Cu")
		(net 528)
	)
	(segment
		(start 193 185)
		(end 217 185)
		(width 0.1)
		(layer "In2.Cu")
		(net 528)
	)
	(segment
		(start 182 163.530331)
		(end 181.530331 164)
		(width 0.1)
		(layer "In2.Cu")
		(net 528)
	)
	(segment
		(start 217 185)
		(end 217.475 185.475)
		(width 0.1)
		(layer "In2.Cu")
		(net 528)
	)
	(segment
		(start 234.1 185.4)
		(end 236.337 187.637)
		(width 0.1)
		(layer "In2.Cu")
		(net 528)
	)
	(segment
		(start 181.5 154.5)
		(end 182 155)
		(width 0.1)
		(layer "In2.Cu")
		(net 528)
	)
	(segment
		(start 171.5 174.5)
		(end 173 176)
		(width 0.1)
		(layer "In2.Cu")
		(net 528)
	)
	(segment
		(start 173.5 164)
		(end 171.5 166)
		(width 0.1)
		(layer "In2.Cu")
		(net 528)
	)
	(segment
		(start 217.475 185.475)
		(end 222.975 185.475)
		(width 0.1)
		(layer "In2.Cu")
		(net 528)
	)
	(segment
		(start 180.9995 143.9995)
		(end 180.5 143.5)
		(width 0.256)
		(layer "F.Cu")
		(net 529)
	)
	(via
		(at 180.5 143.5)
		(size 0.45)
		(drill 0.1)
		(layers "F.Cu" "B.Cu")
		(remove_unused_layers yes)
		(keep_end_layers yes)
		(zone_layer_connections)
		(net 529)
	)
	(segment
		(start 114.806 172.842)
		(end 115.486 172.842)
		(width 0.201)
		(layer "F.Cu")
		(net 530)
	)
	(segment
		(start 120.851 182.553)
		(end 120.006 182.553)
		(width 0.201)
		(layer "F.Cu")
		(net 530)
	)
	(via
		(at 120.006 182.553)
		(size 0.45)
		(drill 0.1)
		(layers "F.Cu" "B.Cu")
		(remove_unused_layers yes)
		(keep_end_layers yes)
		(zone_layer_connections)
		(net 530)
	)
	(via
		(at 115.486 172.842)
		(size 0.45)
		(drill 0.1)
		(layers "F.Cu" "B.Cu")
		(remove_unused_layers yes)
		(keep_end_layers yes)
		(zone_layer_connections)
		(net 530)
	)
	(segment
		(start 119.387 182.553)
		(end 113.946 177.112)
		(width 0.201)
		(layer "B.Cu")
		(net 530)
	)
	(segment
		(start 120.006 182.553)
		(end 119.387 182.553)
		(width 0.201)
		(layer "B.Cu")
		(net 530)
	)
	(segment
		(start 113.946 174.382)
		(end 115.486 172.842)
		(width 0.201)
		(layer "B.Cu")
		(net 530)
	)
	(segment
		(start 113.946 177.112)
		(end 113.946 174.382)
		(width 0.201)
		(layer "B.Cu")
		(net 530)
	)
	(segment
		(start 161.81 158.984999)
		(end 161.81 157.679999)
		(width 0.256)
		(layer "F.Cu")
		(net 531)
	)
	(segment
		(start 161.81 157.679999)
		(end 162.46 157.679999)
		(width 0.256)
		(layer "F.Cu")
		(net 531)
	)
	(segment
		(start 175.9995 153.0005)
		(end 175.5 153.5)
		(width 0.256)
		(layer "F.Cu")
		(net 531)
	)
	(via
		(at 162.46 157.679999)
		(size 0.45)
		(drill 0.1)
		(layers "F.Cu" "B.Cu")
		(remove_unused_layers yes)
		(keep_end_layers yes)
		(zone_layer_connections)
		(net 531)
	)
	(via
		(at 175.5 153.5)
		(size 0.45)
		(drill 0.1)
		(layers "F.Cu" "B.Cu")
		(remove_unused_layers yes)
		(keep_end_layers yes)
		(zone_layer_connections)
		(net 531)
	)
	(segment
		(start 162.739999 157.4)
		(end 162.46 157.679999)
		(width 0.1)
		(layer "In2.Cu")
		(net 531)
	)
	(segment
		(start 175.5 153.5)
		(end 174.25 153.5)
		(width 0.1)
		(layer "In2.Cu")
		(net 531)
	)
	(segment
		(start 174.25 153.5)
		(end 170.35 157.4)
		(width 0.1)
		(layer "In2.Cu")
		(net 531)
	)
	(segment
		(start 170.35 157.4)
		(end 162.739999 157.4)
		(width 0.1)
		(layer "In2.Cu")
		(net 531)
	)
	(segment
		(start 181.9995 155.0005)
		(end 181.499999 155.5)
		(width 0.256)
		(layer "F.Cu")
		(net 532)
	)
	(via
		(at 181.499999 155.5)
		(size 0.45)
		(drill 0.1)
		(layers "F.Cu" "B.Cu")
		(remove_unused_layers yes)
		(keep_end_layers yes)
		(zone_layer_connections)
		(net 532)
	)
	(segment
		(start 240.700499 170.2)
		(end 241.597498 170.2)
		(width 0.256)
		(layer "F.Cu")
		(net 533)
	)
	(segment
		(start 212.05 141.3)
		(end 211.175 141.3)
		(width 0.1)
		(layer "F.Cu")
		(net 533)
	)
	(segment
		(start 255.924499 151.149)
		(end 255.946 151.170501)
		(width 0.182)
		(layer "F.Cu")
		(net 533)
	)
	(segment
		(start 230.831802 140.831802)
		(end 229.418198 139.418198)
		(width 0.1)
		(layer "F.Cu")
		(net 533)
	)
	(segment
		(start 237.025999 165.3485)
		(end 236.4985 165.3485)
		(width 0.1)
		(layer "F.Cu")
		(net 533)
	)
	(segment
		(start 255.946 151.170501)
		(end 255.946 152.1705)
		(width 0.182)
		(layer "F.Cu")
		(net 533)
	)
	(segment
		(start 240.025 152.95)
		(end 240.024499 152.950501)
		(width 0.256)
		(layer "F.Cu")
		(net 533)
	)
	(segment
		(start 236.25 162.35)
		(end 230.831802 156.931802)
		(width 0.1)
		(layer "F.Cu")
		(net 533)
	)
	(segment
		(start 240.024499 152.950501)
		(end 240.024499 153.8475)
		(width 0.256)
		(layer "F.Cu")
		(net 533)
	)
	(segment
		(start 241.597498 170.2)
		(end 241.597999 170.200501)
		(width 0.256)
		(layer "F.Cu")
		(net 533)
	)
	(segment
		(start 213.931802 139.418198)
		(end 212.05 141.3)
		(width 0.1)
		(layer "F.Cu")
		(net 533)
	)
	(segment
		(start 230.831802 156.931802)
		(end 230.831802 140.831802)
		(width 0.1)
		(layer "F.Cu")
		(net 533)
	)
	(segment
		(start 236.25 165.1)
		(end 236.25 162.35)
		(width 0.1)
		(layer "F.Cu")
		(net 533)
	)
	(segment
		(start 241.597498 175.75)
		(end 241.597999 175.750501)
		(width 0.256)
		(layer "F.Cu")
		(net 533)
	)
	(segment
		(start 237.026499 165.349001)
		(end 237.025999 165.3485)
		(width 0.256)
		(layer "F.Cu")
		(net 533)
	)
	(segment
		(start 240.700499 175.75)
		(end 241.597498 175.75)
		(width 0.256)
		(layer "F.Cu")
		(net 533)
	)
	(segment
		(start 241.418499 186.255)
		(end 241.424499 186.249)
		(width 0.177)
		(layer "F.Cu")
		(net 533)
	)
	(segment
		(start 236.4985 165.3485)
		(end 236.25 165.1)
		(width 0.1)
		(layer "F.Cu")
		(net 533)
	)
	(segment
		(start 229.418198 139.418198)
		(end 213.931802 139.418198)
		(width 0.1)
		(layer "F.Cu")
		(net 533)
	)
	(segment
		(start 237.923499 165.349)
		(end 237.026499 165.349001)
		(width 0.256)
		(layer "F.Cu")
		(net 533)
	)
	(segment
		(start 240.651499 186.255)
		(end 241.418499 186.255)
		(width 0.177)
		(layer "F.Cu")
		(net 533)
	)
	(segment
		(start 255.973 169.6215)
		(end 255.973 168.549)
		(width 0.182)
		(layer "F.Cu")
		(net 533)
	)
	(via
		(at 216.300001 181.445001)
		(size 0.45)
		(drill 0.1)
		(layers "F.Cu" "B.Cu")
		(remove_unused_layers yes)
		(keep_end_layers yes)
		(zone_layer_connections)
		(net 533)
	)
	(via
		(at 237.025999 165.3485)
		(size 0.45)
		(drill 0.1)
		(layers "F.Cu" "B.Cu")
		(remove_unused_layers yes)
		(keep_end_layers yes)
		(zone_layer_connections)
		(net 533)
	)
	(via
		(at 211.175 141.3)
		(size 0.45)
		(drill 0.1)
		(layers "F.Cu" "B.Cu")
		(net 533)
	)
	(via
		(at 240.025 152.95)
		(size 0.45)
		(drill 0.1)
		(layers "F.Cu" "B.Cu")
		(remove_unused_layers yes)
		(keep_end_layers yes)
		(zone_layer_connections)
		(net 533)
	)
	(via
		(at 241.597999 175.750501)
		(size 0.45)
		(drill 0.1)
		(layers "F.Cu" "B.Cu")
		(remove_unused_layers yes)
		(keep_end_layers yes)
		(zone_layer_connections)
		(net 533)
	)
	(via
		(at 255.973 168.549)
		(size 0.45)
		(drill 0.1)
		(layers "F.Cu" "B.Cu")
		(remove_unused_layers yes)
		(keep_end_layers yes)
		(zone_layer_connections)
		(net 533)
	)
	(via
		(at 226.995001 181.440001)
		(size 0.45)
		(drill 0.1)
		(layers "F.Cu" "B.Cu")
		(remove_unused_layers yes)
		(keep_end_layers yes)
		(zone_layer_connections)
		(net 533)
	)
	(via
		(at 241.424499 186.249)
		(size 0.45)
		(drill 0.1)
		(layers "F.Cu" "B.Cu")
		(remove_unused_layers yes)
		(keep_end_layers yes)
		(zone_layer_connections)
		(net 533)
	)
	(via
		(at 255.924499 151.149)
		(size 0.45)
		(drill 0.1)
		(layers "F.Cu" "B.Cu")
		(remove_unused_layers yes)
		(keep_end_layers yes)
		(zone_layer_connections)
		(net 533)
	)
	(via
		(at 241.597999 170.200501)
		(size 0.45)
		(drill 0.1)
		(layers "F.Cu" "B.Cu")
		(remove_unused_layers yes)
		(keep_end_layers yes)
		(zone_layer_connections)
		(net 533)
	)
	(segment
		(start 207.801 139.4545)
		(end 209.3295 139.4545)
		(width 0.1)
		(layer "B.Cu")
		(net 533)
	)
	(segment
		(start 241.424499 186.249)
		(end 240.424499 186.249)
		(width 0.1)
		(layer "B.Cu")
		(net 533)
	)
	(segment
		(start 238.909499 186.849)
		(end 238.909499 188.849)
		(width 0.15)
		(layer "B.Cu")
		(net 533)
	)
	(segment
		(start 239.824499 186.849)
		(end 238.909499 186.849)
		(width 0.1)
		(layer "B.Cu")
		(net 533)
	)
	(segment
		(start 209.3295 139.4545)
		(end 211.175 141.3)
		(width 0.1)
		(layer "B.Cu")
		(net 533)
	)
	(segment
		(start 240.424499 186.249)
		(end 239.824499 186.849)
		(width 0.1)
		(layer "B.Cu")
		(net 533)
	)
	(segment
		(start 254.824499 160.549)
		(end 256.424499 160.549)
		(width 0.1)
		(layer "In2.Cu")
		(net 533)
	)
	(segment
		(start 240.074499 152.900501)
		(end 240.800501 152.900501)
		(width 0.1)
		(layer "In2.Cu")
		(net 533)
	)
	(segment
		(start 226.290001 181.440001)
		(end 225.585 180.735)
		(width 0.114)
		(layer "In2.Cu")
		(net 533)
	)
	(segment
		(start 241.424499 186.249)
		(end 240.649 186.249)
		(width 0.1)
		(layer "In2.Cu")
		(net 533)
	)
	(segment
		(start 226.995001 181.440001)
		(end 226.290001 181.440001)
		(width 0.114)
		(layer "In2.Cu")
		(net 533)
	)
	(segment
		(start 237.877915 164.077915)
		(end 237.877915 164.496584)
		(width 0.1)
		(layer "In2.Cu")
		(net 533)
	)
	(segment
		(start 238.15 165.9)
		(end 241.65 169.4)
		(width 0.1)
		(layer "In2.Cu")
		(net 533)
	)
	(segment
		(start 241.65 169.4)
		(end 241.65 170.1485)
		(width 0.1)
		(layer "In2.Cu")
		(net 533)
	)
	(segment
		(start 258.45 158.523499)
		(end 258.45 153.674501)
		(width 0.1)
		(layer "In2.Cu")
		(net 533)
	)
	(segment
		(start 240.800501 152.900501)
		(end 240.9 153)
		(width 0.1)
		(layer "In2.Cu")
		(net 533)
	)
	(segment
		(start 241.597999 170.200501)
		(end 241.972999 170.575501)
		(width 0.1)
		(layer "In2.Cu")
		(net 533)
	)
	(segment
		(start 240.4 161.55583)
		(end 237.877915 164.077915)
		(width 0.1)
		(layer "In2.Cu")
		(net 533)
	)
	(segment
		(start 232.425 184.35)
		(end 229.515001 181.440001)
		(width 0.1)
		(layer "In2.Cu")
		(net 533)
	)
	(segment
		(start 241.972999 170.575501)
		(end 241.972999 171.353832)
		(width 0.1)
		(layer "In2.Cu")
		(net 533)
	)
	(segment
		(start 241.65 171.676831)
		(end 241.65 175.6985)
		(width 0.1)
		(layer "In2.Cu")
		(net 533)
	)
	(segment
		(start 240.9 153)
		(end 240.9 156.690672)
		(width 0.1)
		(layer "In2.Cu")
		(net 533)
	)
	(segment
		(start 255.973 169.002)
		(end 255.577499 169.397501)
		(width 0.1)
		(layer "In2.Cu")
		(net 533)
	)
	(segment
		(start 242.85 177.002502)
		(end 241.597999 175.750501)
		(width 0.1)
		(layer "In2.Cu")
		(net 533)
	)
	(segment
		(start 254.073 169.397501)
		(end 253.524499 168.849)
		(width 0.1)
		(layer "In2.Cu")
		(net 533)
	)
	(segment
		(start 237.577499 165.9)
		(end 238.15 165.9)
		(width 0.1)
		(layer "In2.Cu")
		(net 533)
	)
	(segment
		(start 241.424499 185.825501)
		(end 242.85 184.4)
		(width 0.1)
		(layer "In2.Cu")
		(net 533)
	)
	(segment
		(start 241.424499 186.249)
		(end 241.424499 185.825501)
		(width 0.1)
		(layer "In2.Cu")
		(net 533)
	)
	(segment
		(start 241.65 170.1485)
		(end 241.597999 170.200501)
		(width 0.1)
		(layer "In2.Cu")
		(net 533)
	)
	(segment
		(start 242.85 184.4)
		(end 242.85 177.002502)
		(width 0.1)
		(layer "In2.Cu")
		(net 533)
	)
	(segment
		(start 237.025999 165.3485)
		(end 237.577499 165.9)
		(width 0.1)
		(layer "In2.Cu")
		(net 533)
	)
	(segment
		(start 241.972999 171.353832)
		(end 241.65 171.676831)
		(width 0.1)
		(layer "In2.Cu")
		(net 533)
	)
	(segment
		(start 253.524499 168.849)
		(end 253.524499 161.849)
		(width 0.1)
		(layer "In2.Cu")
		(net 533)
	)
	(segment
		(start 255.973 168.549)
		(end 255.973 169.002)
		(width 0.1)
		(layer "In2.Cu")
		(net 533)
	)
	(segment
		(start 240.4 157.190672)
		(end 240.4 161.55583)
		(width 0.1)
		(layer "In2.Cu")
		(net 533)
	)
	(segment
		(start 258.45 153.674501)
		(end 255.924499 151.149)
		(width 0.1)
		(layer "In2.Cu")
		(net 533)
	)
	(segment
		(start 240.025 152.95)
		(end 240.074499 152.900501)
		(width 0.1)
		(layer "In2.Cu")
		(net 533)
	)
	(segment
		(start 253.524499 161.849)
		(end 254.824499 160.549)
		(width 0.1)
		(layer "In2.Cu")
		(net 533)
	)
	(segment
		(start 238.75 184.35)
		(end 232.425 184.35)
		(width 0.1)
		(layer "In2.Cu")
		(net 533)
	)
	(segment
		(start 229.515001 181.440001)
		(end 226.995001 181.440001)
		(width 0.1)
		(layer "In2.Cu")
		(net 533)
	)
	(segment
		(start 256.424499 160.549)
		(end 258.45 158.523499)
		(width 0.1)
		(layer "In2.Cu")
		(net 533)
	)
	(segment
		(start 241.65 175.6985)
		(end 241.597999 175.750501)
		(width 0.1)
		(layer "In2.Cu")
		(net 533)
	)
	(segment
		(start 221.097499 181.445001)
		(end 216.300001 181.445001)
		(width 0.114)
		(layer "In2.Cu")
		(net 533)
	)
	(segment
		(start 225.585 180.735)
		(end 221.8075 180.735)
		(width 0.114)
		(layer "In2.Cu")
		(net 533)
	)
	(segment
		(start 255.577499 169.397501)
		(end 254.073 169.397501)
		(width 0.1)
		(layer "In2.Cu")
		(net 533)
	)
	(segment
		(start 240.649 186.249)
		(end 238.75 184.35)
		(width 0.1)
		(layer "In2.Cu")
		(net 533)
	)
	(segment
		(start 237.877915 164.496584)
		(end 237.025999 165.3485)
		(width 0.1)
		(layer "In2.Cu")
		(net 533)
	)
	(segment
		(start 221.8075 180.735)
		(end 221.097499 181.445001)
		(width 0.114)
		(layer "In2.Cu")
		(net 533)
	)
	(segment
		(start 240.9 156.690672)
		(end 240.4 157.190672)
		(width 0.1)
		(layer "In2.Cu")
		(net 533)
	)
	(segment
		(start 243.665 149.025)
		(end 253.800499 149.025)
		(width 0.1)
		(layer "In4.Cu")
		(net 533)
	)
	(segment
		(start 240.025 152.95)
		(end 240.8 152.175)
		(width 0.1)
		(layer "In4.Cu")
		(net 533)
	)
	(segment
		(start 253.800499 149.025)
		(end 255.924499 151.149)
		(width 0.1)
		(layer "In4.Cu")
		(net 533)
	)
	(segment
		(start 240.8 151.89)
		(end 243.665 149.025)
		(width 0.1)
		(layer "In4.Cu")
		(net 533)
	)
	(segment
		(start 240.8 152.175)
		(end 240.8 151.89)
		(width 0.1)
		(layer "In4.Cu")
		(net 533)
	)
	(segment
		(start 155.92 160.299999)
		(end 155.43 160.789999)
		(width 0.256)
		(layer "F.Cu")
		(net 534)
	)
	(segment
		(start 156.995 160.299999)
		(end 155.92 160.299999)
		(width 0.256)
		(layer "F.Cu")
		(net 534)
	)
	(segment
		(start 194.0005 147.9995)
		(end 194.499999 147.5)
		(width 0.256)
		(layer "F.Cu")
		(net 535)
	)
	(via
		(at 194.499999 147.5)
		(size 0.45)
		(drill 0.1)
		(layers "F.Cu" "B.Cu")
		(remove_unused_layers yes)
		(keep_end_layers yes)
		(zone_layer_connections)
		(net 535)
	)
	(segment
		(start 197 141.8)
		(end 197 137.8)
		(width 0.198)
		(layer "B.Cu")
		(net 535)
	)
	(segment
		(start 197 137.8)
		(end 196.5 137.3)
		(width 0.198)
		(layer "B.Cu")
		(net 535)
	)
	(segment
		(start 196.8 142)
		(end 197 141.8)
		(width 0.198)
		(layer "B.Cu")
		(net 535)
	)
	(segment
		(start 194.499999 147.500999)
		(end 195 148.001)
		(width 0.256)
		(layer "B.Cu")
		(net 535)
	)
	(segment
		(start 196 142.2)
		(end 196.2 142)
		(width 0.198)
		(layer "B.Cu")
		(net 535)
	)
	(segment
		(start 194.499999 147.5)
		(end 194.499999 147.500999)
		(width 0.256)
		(layer "B.Cu")
		(net 535)
	)
	(segment
		(start 196 148)
		(end 195 148)
		(width 0.198)
		(layer "B.Cu")
		(net 535)
	)
	(segment
		(start 196 148)
		(end 196 142.2)
		(width 0.198)
		(layer "B.Cu")
		(net 535)
	)
	(segment
		(start 196.2 142)
		(end 196.8 142)
		(width 0.198)
		(layer "B.Cu")
		(net 535)
	)
	(segment
		(start 193.0005 147.9995)
		(end 193.500001 147.5)
		(width 0.256)
		(layer "F.Cu")
		(net 536)
	)
	(via
		(at 193.500001 147.5)
		(size 0.45)
		(drill 0.1)
		(layers "F.Cu" "B.Cu")
		(remove_unused_layers yes)
		(keep_end_layers yes)
		(zone_layer_connections)
		(net 536)
	)
	(segment
		(start 194.701 146.999)
		(end 195 146.7)
		(width 0.198)
		(layer "B.Cu")
		(net 536)
	)
	(segment
		(start 195 137.8)
		(end 195.5 137.3)
		(width 0.198)
		(layer "B.Cu")
		(net 536)
	)
	(segment
		(start 194 147.000001)
		(end 193.500001 147.5)
		(width 0.198)
		(layer "B.Cu")
		(net 536)
	)
	(segment
		(start 193 146.999999)
		(end 193.500001 147.5)
		(width 0.198)
		(layer "B.Cu")
		(net 536)
	)
	(segment
		(start 194 146.999)
		(end 194.701 146.999)
		(width 0.198)
		(layer "B.Cu")
		(net 536)
	)
	(segment
		(start 195 146.7)
		(end 195 137.8)
		(width 0.198)
		(layer "B.Cu")
		(net 536)
	)
	(segment
		(start 193 146.999)
		(end 193 146.999999)
		(width 0.198)
		(layer "B.Cu")
		(net 536)
	)
	(segment
		(start 194 146.999)
		(end 194 147.000001)
		(width 0.198)
		(layer "B.Cu")
		(net 536)
	)
	(segment
		(start 181.9995 143.9995)
		(end 181.5 143.5)
		(width 0.256)
		(layer "F.Cu")
		(net 537)
	)
	(via
		(at 181.5 143.5)
		(size 0.45)
		(drill 0.1)
		(layers "F.Cu" "B.Cu")
		(remove_unused_layers yes)
		(keep_end_layers yes)
		(zone_layer_connections)
		(net 537)
	)
	(segment
		(start 182.9995 160.0005)
		(end 182.5 160.5)
		(width 0.256)
		(layer "F.Cu")
		(net 538)
	)
	(via
		(at 182.5 160.5)
		(size 0.45)
		(drill 0.1)
		(layers "F.Cu" "B.Cu")
		(remove_unused_layers yes)
		(keep_end_layers yes)
		(zone_layer_connections)
		(net 538)
	)
	(segment
		(start 182.9995 159.0005)
		(end 182.5 159.5)
		(width 0.256)
		(layer "F.Cu")
		(net 539)
	)
	(via
		(at 182.5 159.5)
		(size 0.45)
		(drill 0.1)
		(layers "F.Cu" "B.Cu")
		(remove_unused_layers yes)
		(keep_end_layers yes)
		(zone_layer_connections)
		(net 539)
	)
	(segment
		(start 182.9995 157.0005)
		(end 182.5 157.5)
		(width 0.256)
		(layer "F.Cu")
		(net 540)
	)
	(via
		(at 182.5 157.5)
		(size 0.45)
		(drill 0.1)
		(layers "F.Cu" "B.Cu")
		(remove_unused_layers yes)
		(keep_end_layers yes)
		(zone_layer_connections)
		(net 540)
	)
	(segment
		(start 182.9995 155.0005)
		(end 182.5 155.5)
		(width 0.256)
		(layer "F.Cu")
		(net 541)
	)
	(via
		(at 182.5 155.5)
		(size 0.45)
		(drill 0.1)
		(layers "F.Cu" "B.Cu")
		(remove_unused_layers yes)
		(keep_end_layers yes)
		(zone_layer_connections)
		(net 541)
	)
	(segment
		(start 155.93 162.299999)
		(end 155.43 161.799999)
		(width 0.256)
		(layer "F.Cu")
		(net 542)
	)
	(segment
		(start 156.995 162.299999)
		(end 155.93 162.299999)
		(width 0.256)
		(layer "F.Cu")
		(net 542)
	)
	(segment
		(start 170.725 157.525)
		(end 170.235001 157.035001)
		(width 0.16)
		(layer "F.Cu")
		(net 543)
	)
	(segment
		(start 176.999499 146.9995)
		(end 176.5 146.5)
		(width 0.256)
		(layer "F.Cu")
		(net 543)
	)
	(segment
		(start 170.235001 156.769999)
		(end 170.355 156.65)
		(width 0.16)
		(layer "F.Cu")
		(net 543)
	)
	(segment
		(start 170.235001 157.035001)
		(end 170.235001 156.769999)
		(width 0.16)
		(layer "F.Cu")
		(net 543)
	)
	(segment
		(start 170.725 157.525)
		(end 170.725 157.46)
		(width 0.1)
		(layer "F.Cu")
		(net 543)
	)
	(via
		(at 170.355 156.65)
		(size 0.45)
		(drill 0.1)
		(layers "F.Cu" "B.Cu")
		(remove_unused_layers yes)
		(keep_end_layers yes)
		(zone_layer_connections)
		(net 543)
	)
	(via
		(at 176.5 146.5)
		(size 0.45)
		(drill 0.1)
		(layers "F.Cu" "B.Cu")
		(remove_unused_layers yes)
		(keep_end_layers yes)
		(zone_layer_connections)
		(net 543)
	)
	(segment
		(start 170.235001 156.530001)
		(end 170.235001 155.434203)
		(width 0.16)
		(layer "B.Cu")
		(net 543)
	)
	(segment
		(start 170.737066 155.247102)
		(end 170.737067 155.247102)
		(width 0.16)
		(layer "B.Cu")
		(net 543)
	)
	(segment
		(start 171.161328 154.507871)
		(end 171.161329 154.507871)
		(width 0.16)
		(layer "B.Cu")
		(net 543)
	)
	(segment
		(start 171.605 148.014204)
		(end 173.469204 146.15)
		(width 0.16)
		(layer "B.Cu")
		(net 543)
	)
	(segment
		(start 170.355 156.65)
		(end 170.235001 156.530001)
		(width 0.16)
		(layer "B.Cu")
		(net 543)
	)
	(segment
		(start 174.898488 146.1)
		(end 174.830046 146.168442)
		(width 0.1)
		(layer "B.Cu")
		(net 543)
	)
	(segment
		(start 171.16133 154.822837)
		(end 171.161329 154.822836)
		(width 0.16)
		(layer "B.Cu")
		(net 543)
	)
	(segment
		(start 173.469204 146.15)
		(end 174.811604 146.15)
		(width 0.16)
		(layer "B.Cu")
		(net 543)
	)
	(segment
		(start 171.161331 154.822838)
		(end 171.16133 154.822837)
		(width 0.16)
		(layer "B.Cu")
		(net 543)
	)
	(segment
		(start 176.1 146.1)
		(end 174.898488 146.1)
		(width 0.1)
		(layer "B.Cu")
		(net 543)
	)
	(segment
		(start 170.235001 155.434203)
		(end 170.422102 155.247102)
		(width 0.16)
		(layer "B.Cu")
		(net 543)
	)
	(segment
		(start 176.5 146.5)
		(end 176.1 146.1)
		(width 0.1)
		(layer "B.Cu")
		(net 543)
	)
	(segment
		(start 171.052032 155.247102)
		(end 171.16133 155.137803)
		(width 0.16)
		(layer "B.Cu")
		(net 543)
	)
	(segment
		(start 171.052032 155.247103)
		(end 171.052032 155.247102)
		(width 0.16)
		(layer "B.Cu")
		(net 543)
	)
	(segment
		(start 171.605 154.064204)
		(end 171.605 148.014204)
		(width 0.16)
		(layer "B.Cu")
		(net 543)
	)
	(segment
		(start 171.161329 154.507871)
		(end 171.605 154.064204)
		(width 0.16)
		(layer "B.Cu")
		(net 543)
	)
	(arc
		(start 171.16133 155.137803)
		(mid 171.226562 154.980321)
		(end 171.161331 154.822838)
		(width 0.16)
		(layer "B.Cu")
		(net 543)
	)
	(arc
		(start 170.422102 155.247102)
		(mid 170.579584 155.181871)
		(end 170.737066 155.247102)
		(width 0.16)
		(layer "B.Cu")
		(net 543)
	)
	(arc
		(start 170.737067 155.247102)
		(mid 170.894549 155.312334)
		(end 171.052032 155.247103)
		(width 0.16)
		(layer "B.Cu")
		(net 543)
	)
	(arc
		(start 171.161329 154.822836)
		(mid 171.096097 154.665354)
		(end 171.161328 154.507871)
		(width 0.16)
		(layer "B.Cu")
		(net 543)
	)
	(segment
		(start 176.9995 145.9995)
		(end 176.5 145.5)
		(width 0.256)
		(layer "F.Cu")
		(net 544)
	)
	(segment
		(start 169.924999 156.995001)
		(end 169.924999 156.769999)
		(width 0.16)
		(layer "F.Cu")
		(net 544)
	)
	(segment
		(start 169.435 157.485)
		(end 169.924999 156.995001)
		(width 0.16)
		(layer "F.Cu")
		(net 544)
	)
	(segment
		(start 169.435 157.525)
		(end 169.435 157.485)
		(width 0.16)
		(layer "F.Cu")
		(net 544)
	)
	(segment
		(start 169.435 157.525)
		(end 169.435 157.46)
		(width 0.1)
		(layer "F.Cu")
		(net 544)
	)
	(segment
		(start 169.924999 156.769999)
		(end 169.805 156.65)
		(width 0.16)
		(layer "F.Cu")
		(net 544)
	)
	(via
		(at 176.5 145.5)
		(size 0.45)
		(drill 0.1)
		(layers "F.Cu" "B.Cu")
		(remove_unused_layers yes)
		(keep_end_layers yes)
		(zone_layer_connections)
		(net 544)
	)
	(via
		(at 169.805 156.65)
		(size 0.45)
		(drill 0.1)
		(layers "F.Cu" "B.Cu")
		(remove_unused_layers yes)
		(keep_end_layers yes)
		(zone_layer_connections)
		(net 544)
	)
	(segment
		(start 169.924999 156.530001)
		(end 169.924999 155.305797)
		(width 0.16)
		(layer "B.Cu")
		(net 544)
	)
	(segment
		(start 176.5 145.5)
		(end 176.5 145.525)
		(width 0.1)
		(layer "B.Cu")
		(net 544)
	)
	(segment
		(start 169.924999 155.305797)
		(end 171.295 153.935796)
		(width 0.16)
		(layer "B.Cu")
		(net 544)
	)
	(segment
		(start 171.295 147.885796)
		(end 173.330796 145.85)
		(width 0.16)
		(layer "B.Cu")
		(net 544)
	)
	(segment
		(start 173.330796 145.85)
		(end 174.821604 145.85)
		(width 0.16)
		(layer "B.Cu")
		(net 544)
	)
	(segment
		(start 176.5 145.525)
		(end 176.125 145.9)
		(width 0.1)
		(layer "B.Cu")
		(net 544)
	)
	(segment
		(start 169.805 156.65)
		(end 169.924999 156.530001)
		(width 0.16)
		(layer "B.Cu")
		(net 544)
	)
	(segment
		(start 174.871604 145.9)
		(end 174.821604 145.85)
		(width 0.1)
		(layer "B.Cu")
		(net 544)
	)
	(segment
		(start 176.125 145.9)
		(end 174.871604 145.9)
		(width 0.1)
		(layer "B.Cu")
		(net 544)
	)
	(segment
		(start 171.295 153.935796)
		(end 171.295 147.885796)
		(width 0.16)
		(layer "B.Cu")
		(net 544)
	)
	(segment
		(start 183.9995 147.9995)
		(end 183.5 147.5)
		(width 0.256)
		(layer "F.Cu")
		(net 545)
	)
	(via
		(at 183.5 147.5)
		(size 0.45)
		(drill 0.1)
		(layers "F.Cu" "B.Cu")
		(remove_unused_layers yes)
		(keep_end_layers yes)
		(zone_layer_connections)
		(net 545)
	)
	(segment
		(start 183.499 147.5)
		(end 183 147.001)
		(width 0.256)
		(layer "B.Cu")
		(net 545)
	)
	(segment
		(start 184.001 146)
		(end 184.001 146.999)
		(width 0.198)
		(layer "B.Cu")
		(net 545)
	)
	(segment
		(start 184.001 146)
		(end 184.001 137.301)
		(width 0.198)
		(layer "B.Cu")
		(net 545)
	)
	(segment
		(start 184.001 146.999)
		(end 183.5 147.5)
		(width 0.198)
		(layer "B.Cu")
		(net 545)
	)
	(segment
		(start 184.001 137.301)
		(end 184 137.3)
		(width 0.198)
		(layer "B.Cu")
		(net 545)
	)
	(segment
		(start 183.5 147.5)
		(end 183.499 147.5)
		(width 0.256)
		(layer "B.Cu")
		(net 545)
	)
	(segment
		(start 183.9995 149.9995)
		(end 183.5 149.500001)
		(width 0.256)
		(layer "F.Cu")
		(net 546)
	)
	(via
		(at 183.5 149.500001)
		(size 0.45)
		(drill 0.1)
		(layers "F.Cu" "B.Cu")
		(remove_unused_layers yes)
		(keep_end_layers yes)
		(zone_layer_connections)
		(net 546)
	)
	(segment
		(start 183 150.000001)
		(end 183.5 149.500001)
		(width 0.256)
		(layer "B.Cu")
		(net 546)
	)
	(segment
		(start 181.998 149)
		(end 181.998 143.202)
		(width 0.198)
		(layer "B.Cu")
		(net 546)
	)
	(segment
		(start 181.998 143.202)
		(end 182.2 143)
		(width 0.198)
		(layer "B.Cu")
		(net 546)
	)
	(segment
		(start 183 150.019)
		(end 183 150.000001)
		(width 0.256)
		(layer "B.Cu")
		(net 546)
	)
	(segment
		(start 183 142.8)
		(end 183 137.3)
		(width 0.198)
		(layer "B.Cu")
		(net 546)
	)
	(segment
		(start 183.5 149.500001)
		(end 182.999999 149)
		(width 0.198)
		(layer "B.Cu")
		(net 546)
	)
	(segment
		(start 182.8 143)
		(end 183 142.8)
		(width 0.198)
		(layer "B.Cu")
		(net 546)
	)
	(segment
		(start 182.2 143)
		(end 182.8 143)
		(width 0.198)
		(layer "B.Cu")
		(net 546)
	)
	(segment
		(start 182.999999 149)
		(end 181.998 149)
		(width 0.198)
		(layer "B.Cu")
		(net 546)
	)
	(segment
		(start 201.0005 142.9995)
		(end 201.5 142.5)
		(width 0.256)
		(layer "F.Cu")
		(net 547)
	)
	(via
		(at 201.5 142.5)
		(size 0.45)
		(drill 0.1)
		(layers "F.Cu" "B.Cu")
		(remove_unused_layers yes)
		(keep_end_layers yes)
		(zone_layer_connections)
		(net 547)
	)
	(segment
		(start 201 142)
		(end 201.5 142.5)
		(width 0.256)
		(layer "B.Cu")
		(net 547)
	)
	(segment
		(start 194.0005 144.9995)
		(end 194.5 144.5)
		(width 0.256)
		(layer "F.Cu")
		(net 548)
	)
	(via
		(at 194.5 144.5)
		(size 0.45)
		(drill 0.1)
		(layers "F.Cu" "B.Cu")
		(remove_unused_layers yes)
		(keep_end_layers yes)
		(zone_layer_connections)
		(net 548)
	)
	(segment
		(start 194 144)
		(end 194.5 144.5)
		(width 0.256)
		(layer "B.Cu")
		(net 548)
	)
	(segment
		(start 177.9995 153.0005)
		(end 177.5 153.5)
		(width 0.256)
		(layer "F.Cu")
		(net 549)
	)
	(segment
		(start 127.801 182.553)
		(end 128.716 182.553)
		(width 0.201)
		(layer "F.Cu")
		(net 549)
	)
	(via
		(at 128.716 182.553)
		(size 0.45)
		(drill 0.1)
		(layers "F.Cu" "B.Cu")
		(remove_unused_layers yes)
		(keep_end_layers yes)
		(zone_layer_connections)
		(net 549)
	)
	(via
		(at 177.5 153.5)
		(size 0.45)
		(drill 0.1)
		(layers "F.Cu" "B.Cu")
		(remove_unused_layers yes)
		(keep_end_layers yes)
		(zone_layer_connections)
		(net 549)
	)
	(segment
		(start 177.5 153.5)
		(end 177 154)
		(width 0.1)
		(layer "In9.Cu")
		(net 549)
	)
	(segment
		(start 131.6 168.5)
		(end 129.8 170.3)
		(width 0.1)
		(layer "In9.Cu")
		(net 549)
	)
	(segment
		(start 129.8 170.3)
		(end 129.8 174.2)
		(width 0.1)
		(layer "In9.Cu")
		(net 549)
	)
	(segment
		(start 127.5 181.2385)
		(end 128.716 182.4545)
		(width 0.1)
		(layer "In9.Cu")
		(net 549)
	)
	(segment
		(start 135.5 164.1)
		(end 135.5 166)
		(width 0.1)
		(layer "In9.Cu")
		(net 549)
	)
	(segment
		(start 177 154)
		(end 177 154.7)
		(width 0.1)
		(layer "In9.Cu")
		(net 549)
	)
	(segment
		(start 137.1 162.5)
		(end 135.5 164.1)
		(width 0.1)
		(layer "In9.Cu")
		(net 549)
	)
	(segment
		(start 151.975 157.725)
		(end 151.47 158.23)
		(width 0.1)
		(layer "In9.Cu")
		(net 549)
	)
	(segment
		(start 142 159.2)
		(end 138.7 162.5)
		(width 0.1)
		(layer "In9.Cu")
		(net 549)
	)
	(segment
		(start 177 154.7)
		(end 176.7 155)
		(width 0.1)
		(layer "In9.Cu")
		(net 549)
	)
	(segment
		(start 133 168.5)
		(end 131.6 168.5)
		(width 0.1)
		(layer "In9.Cu")
		(net 549)
	)
	(segment
		(start 159.624999 158.324999)
		(end 159.025 157.725)
		(width 0.1)
		(layer "In9.Cu")
		(net 549)
	)
	(segment
		(start 138.7 162.5)
		(end 137.1 162.5)
		(width 0.1)
		(layer "In9.Cu")
		(net 549)
	)
	(segment
		(start 144 159.2)
		(end 142 159.2)
		(width 0.1)
		(layer "In9.Cu")
		(net 549)
	)
	(segment
		(start 159.025 157.725)
		(end 151.975 157.725)
		(width 0.1)
		(layer "In9.Cu")
		(net 549)
	)
	(segment
		(start 144.97 158.23)
		(end 144 159.2)
		(width 0.1)
		(layer "In9.Cu")
		(net 549)
	)
	(segment
		(start 127.5 176.5)
		(end 127.5 181.2385)
		(width 0.1)
		(layer "In9.Cu")
		(net 549)
	)
	(segment
		(start 151.47 158.23)
		(end 144.97 158.23)
		(width 0.1)
		(layer "In9.Cu")
		(net 549)
	)
	(segment
		(start 170 155)
		(end 166.675001 158.324999)
		(width 0.1)
		(layer "In9.Cu")
		(net 549)
	)
	(segment
		(start 176.7 155)
		(end 170 155)
		(width 0.1)
		(layer "In9.Cu")
		(net 549)
	)
	(segment
		(start 129.8 174.2)
		(end 127.5 176.5)
		(width 0.1)
		(layer "In9.Cu")
		(net 549)
	)
	(segment
		(start 135.5 166)
		(end 133 168.5)
		(width 0.1)
		(layer "In9.Cu")
		(net 549)
	)
	(segment
		(start 166.675001 158.324999)
		(end 159.624999 158.324999)
		(width 0.1)
		(layer "In9.Cu")
		(net 549)
	)
	(segment
		(start 182.9995 154.000499)
		(end 182.5 154.5)
		(width 0.256)
		(layer "F.Cu")
		(net 550)
	)
	(via
		(at 182.5 154.5)
		(size 0.45)
		(drill 0.1)
		(layers "F.Cu" "B.Cu")
		(remove_unused_layers yes)
		(keep_end_layers yes)
		(zone_layer_connections)
		(net 550)
	)
	(via
		(at 120.222334 169.127666)
		(size 0.45)
		(drill 0.1)
		(layers "F.Cu" "B.Cu")
		(remove_unused_layers yes)
		(keep_end_layers yes)
		(zone_layer_connections)
		(net 550)
	)
	(segment
		(start 118.35 167.975)
		(end 118.35 167.22)
		(width 0.15)
		(layer "B.Cu")
		(net 550)
	)
	(segment
		(start 119.502666 169.127666)
		(end 118.35 167.975)
		(width 0.15)
		(layer "B.Cu")
		(net 550)
	)
	(segment
		(start 120.222334 169.127666)
		(end 119.502666 169.127666)
		(width 0.15)
		(layer "B.Cu")
		(net 550)
	)
	(segment
		(start 170.975 152.95)
		(end 167.775 156.15)
		(width 0.1)
		(layer "In9.Cu")
		(net 550)
	)
	(segment
		(start 136.2 161.2)
		(end 127.9 169.5)
		(width 0.1)
		(layer "In9.Cu")
		(net 550)
	)
	(segment
		(start 142.05 157.875)
		(end 141.025 157.875)
		(width 0.1)
		(layer "In9.Cu")
		(net 550)
	)
	(segment
		(start 122.077666 169.127666)
		(end 120.222334 169.127666)
		(width 0.1)
		(layer "In9.Cu")
		(net 550)
	)
	(segment
		(start 152.512842 155.6)
		(end 150.538842 157.574)
		(width 0.1)
		(layer "In9.Cu")
		(net 550)
	)
	(segment
		(start 127.9 169.5)
		(end 122.45 169.5)
		(width 0.1)
		(layer "In9.Cu")
		(net 550)
	)
	(segment
		(start 182 155)
		(end 179.3 155)
		(width 0.1)
		(layer "In9.Cu")
		(net 550)
	)
	(segment
		(start 141.025 157.875)
		(end 137.7 161.2)
		(width 0.1)
		(layer "In9.Cu")
		(net 550)
	)
	(segment
		(start 179 153.3)
		(end 178.65 152.95)
		(width 0.1)
		(layer "In9.Cu")
		(net 550)
	)
	(segment
		(start 137.7 161.2)
		(end 136.2 161.2)
		(width 0.1)
		(layer "In9.Cu")
		(net 550)
	)
	(segment
		(start 167.775 156.15)
		(end 163.55 156.15)
		(width 0.1)
		(layer "In9.Cu")
		(net 550)
	)
	(segment
		(start 163 155.6)
		(end 152.512842 155.6)
		(width 0.1)
		(layer "In9.Cu")
		(net 550)
	)
	(segment
		(start 122.45 169.5)
		(end 122.077666 169.127666)
		(width 0.1)
		(layer "In9.Cu")
		(net 550)
	)
	(segment
		(start 179 154.7)
		(end 179 153.3)
		(width 0.1)
		(layer "In9.Cu")
		(net 550)
	)
	(segment
		(start 178.65 152.95)
		(end 170.975 152.95)
		(width 0.1)
		(layer "In9.Cu")
		(net 550)
	)
	(segment
		(start 179.3 155)
		(end 179 154.7)
		(width 0.1)
		(layer "In9.Cu")
		(net 550)
	)
	(segment
		(start 163.55 156.15)
		(end 163 155.6)
		(width 0.1)
		(layer "In9.Cu")
		(net 550)
	)
	(segment
		(start 150.538842 157.574)
		(end 142.351 157.574)
		(width 0.1)
		(layer "In9.Cu")
		(net 550)
	)
	(segment
		(start 182.5 154.5)
		(end 182 155)
		(width 0.1)
		(layer "In9.Cu")
		(net 550)
	)
	(segment
		(start 142.351 157.574)
		(end 142.05 157.875)
		(width 0.1)
		(layer "In9.Cu")
		(net 550)
	)
	(segment
		(start 184.999501 160.0005)
		(end 184.5 160.5)
		(width 0.256)
		(layer "F.Cu")
		(net 551)
	)
	(via
		(at 184.5 160.5)
		(size 0.45)
		(drill 0.1)
		(layers "F.Cu" "B.Cu")
		(remove_unused_layers yes)
		(keep_end_layers yes)
		(zone_layer_connections)
		(net 551)
	)
	(segment
		(start 184.9995 159.0005)
		(end 184.5 159.5)
		(width 0.256)
		(layer "F.Cu")
		(net 552)
	)
	(via
		(at 184.5 159.5)
		(size 0.45)
		(drill 0.1)
		(layers "F.Cu" "B.Cu")
		(remove_unused_layers yes)
		(keep_end_layers yes)
		(zone_layer_connections)
		(net 552)
	)
	(segment
		(start 193.0005 150.9995)
		(end 193.5 150.5)
		(width 0.256)
		(layer "F.Cu")
		(net 553)
	)
	(segment
		(start 191.0005 157.0005)
		(end 191.5 157.500001)
		(width 0.256)
		(layer "F.Cu")
		(net 553)
	)
	(segment
		(start 190.0005 154.0005)
		(end 190.5 154.5)
		(width 0.256)
		(layer "F.Cu")
		(net 553)
	)
	(segment
		(start 193.0005 148.9995)
		(end 193.5 148.5)
		(width 0.256)
		(layer "F.Cu")
		(net 553)
	)
	(segment
		(start 190.0005 149.9995)
		(end 190.5 149.5)
		(width 0.256)
		(layer "F.Cu")
		(net 553)
	)
	(segment
		(start 186.9995 153.0005)
		(end 186.5 153.5)
		(width 0.256)
		(layer "F.Cu")
		(net 553)
	)
	(segment
		(start 193.0005 153.0005)
		(end 193.5 153.5)
		(width 0.256)
		(layer "F.Cu")
		(net 553)
	)
	(segment
		(start 184.9995 150.999501)
		(end 184.5 150.5)
		(width 0.256)
		(layer "F.Cu")
		(net 553)
	)
	(segment
		(start 190.000499 156.0005)
		(end 190.5 156.5)
		(width 0.256)
		(layer "F.Cu")
		(net 553)
	)
	(segment
		(start 192.0005 154.000499)
		(end 192.5 154.5)
		(width 0.256)
		(layer "F.Cu")
		(net 553)
	)
	(segment
		(start 191.0005 155.0005)
		(end 191.5 155.5)
		(width 0.256)
		(layer "F.Cu")
		(net 553)
	)
	(segment
		(start 192.0005 149.999499)
		(end 192.5 149.5)
		(width 0.256)
		(layer "F.Cu")
		(net 553)
	)
	(segment
		(start 193.0005 155.0005)
		(end 193.500001 155.5)
		(width 0.256)
		(layer "F.Cu")
		(net 553)
	)
	(segment
		(start 184.9995 155.0005)
		(end 184.5 155.5)
		(width 0.256)
		(layer "F.Cu")
		(net 553)
	)
	(segment
		(start 185.999499 151.9995)
		(end 185.5 151.500001)
		(width 0.256)
		(layer "F.Cu")
		(net 553)
	)
	(segment
		(start 189.0005 155.0005)
		(end 189.499999 155.5)
		(width 0.256)
		(layer "F.Cu")
		(net 553)
	)
	(segment
		(start 186.9995 155.0005)
		(end 186.5 155.5)
		(width 0.256)
		(layer "F.Cu")
		(net 553)
	)
	(segment
		(start 186.9995 148.9995)
		(end 186.5 148.5)
		(width 0.256)
		(layer "F.Cu")
		(net 553)
	)
	(segment
		(start 191.0005 148.9995)
		(end 191.5 148.5)
		(width 0.256)
		(layer "F.Cu")
		(net 553)
	)
	(segment
		(start 185.999499 156.0005)
		(end 185.5 156.5)
		(width 0.256)
		(layer "F.Cu")
		(net 553)
	)
	(segment
		(start 184.9995 148.9995)
		(end 184.5 148.5)
		(width 0.256)
		(layer "F.Cu")
		(net 553)
	)
	(segment
		(start 191.0005 150.9995)
		(end 191.5 150.5)
		(width 0.256)
		(layer "F.Cu")
		(net 553)
	)
	(segment
		(start 190.0005 157.0005)
		(end 190.5 157.5)
		(width 0.256)
		(layer "F.Cu")
		(net 553)
	)
	(segment
		(start 184.9995 153.0005)
		(end 184.5 153.5)
		(width 0.256)
		(layer "F.Cu")
		(net 553)
	)
	(segment
		(start 192.0005 156.0005)
		(end 192.5 156.5)
		(width 0.256)
		(layer "F.Cu")
		(net 553)
	)
	(segment
		(start 189.0005 157.0005)
		(end 189.5 157.5)
		(width 0.256)
		(layer "F.Cu")
		(net 553)
	)
	(segment
		(start 192.0005 157.0005)
		(end 192.5 157.5)
		(width 0.256)
		(layer "F.Cu")
		(net 553)
	)
	(segment
		(start 193.0005 157.0005)
		(end 193.5 157.5)
		(width 0.256)
		(layer "F.Cu")
		(net 553)
	)
	(segment
		(start 189.0005 150.999501)
		(end 189.5 150.5)
		(width 0.256)
		(layer "F.Cu")
		(net 553)
	)
	(segment
		(start 185.9995 157.0005)
		(end 185.5 157.5)
		(width 0.256)
		(layer "F.Cu")
		(net 553)
	)
	(segment
		(start 185.9995 154.0005)
		(end 185.5 154.5)
		(width 0.256)
		(layer "F.Cu")
		(net 553)
	)
	(segment
		(start 186.9995 150.9995)
		(end 186.5 150.5)
		(width 0.256)
		(layer "F.Cu")
		(net 553)
	)
	(segment
		(start 185.9995 149.9995)
		(end 185.5 149.5)
		(width 0.256)
		(layer "F.Cu")
		(net 553)
	)
	(segment
		(start 187.9995 149.999499)
		(end 187.500001 149.5)
		(width 0.256)
		(layer "F.Cu")
		(net 553)
	)
	(segment
		(start 189.0005 148.9995)
		(end 189.5 148.5)
		(width 0.256)
		(layer "F.Cu")
		(net 553)
	)
	(segment
		(start 186.9995 157.0005)
		(end 186.5 157.5)
		(width 0.256)
		(layer "F.Cu")
		(net 553)
	)
	(segment
		(start 187.9995 156.0005)
		(end 187.5 156.5)
		(width 0.256)
		(layer "F.Cu")
		(net 553)
	)
	(segment
		(start 187.9995 157.0005)
		(end 187.500001 157.5)
		(width 0.256)
		(layer "F.Cu")
		(net 553)
	)
	(segment
		(start 188 154)
		(end 187.5005 154.4995)
		(width 0.256)
		(layer "F.Cu")
		(net 553)
	)
	(segment
		(start 192.0005 151.9995)
		(end 192.5 151.5)
		(width 0.256)
		(layer "F.Cu")
		(net 553)
	)
	(via
		(at 212.700001 167.675004)
		(size 0.45)
		(drill 0.1)
		(layers "F.Cu" "B.Cu")
		(remove_unused_layers yes)
		(keep_end_layers yes)
		(zone_layer_connections "In2.Cu" "In4.Cu" "In6.Cu" "In9.Cu")
		(net 553)
	)
	(via
		(at 204.5 157.5)
		(size 0.45)
		(drill 0.1)
		(layers "F.Cu" "B.Cu")
		(remove_unused_layers yes)
		(keep_end_layers yes)
		(zone_layer_connections "In6.Cu" "In9.Cu")
		(net 553)
	)
	(via
		(at 211.619999 161.1)
		(size 0.45)
		(drill 0.1)
		(layers "F.Cu" "B.Cu")
		(remove_unused_layers yes)
		(keep_end_layers yes)
		(zone_layer_connections "In2.Cu" "In4.Cu" "In6.Cu" "In9.Cu")
		(net 553)
	)
	(via
		(at 209.499999 167.700004)
		(size 0.45)
		(drill 0.1)
		(layers "F.Cu" "B.Cu")
		(remove_unused_layers yes)
		(keep_end_layers yes)
		(zone_layer_connections "In2.Cu" "In4.Cu" "In6.Cu" "In9.Cu")
		(net 553)
	)
	(via
		(at 192.5 157.5)
		(size 0.45)
		(drill 0.1)
		(layers "F.Cu" "B.Cu")
		(remove_unused_layers yes)
		(keep_end_layers yes)
		(zone_layer_connections "In2.Cu" "In4.Cu" "In6.Cu" "In9.Cu")
		(net 553)
	)
	(via
		(at 187.5 156.5)
		(size 0.45)
		(drill 0.1)
		(layers "F.Cu" "B.Cu")
		(remove_unused_layers yes)
		(keep_end_layers yes)
		(zone_layer_connections "In2.Cu" "In4.Cu" "In6.Cu" "In9.Cu")
		(net 553)
	)
	(via
		(at 219.079998 161.575)
		(size 0.45)
		(drill 0.1)
		(layers "F.Cu" "B.Cu")
		(remove_unused_layers yes)
		(keep_end_layers yes)
		(zone_layer_connections "In2.Cu" "In4.Cu" "In6.Cu" "In9.Cu")
		(net 553)
	)
	(via
		(at 209.15 160.025)
		(size 0.45)
		(drill 0.1)
		(layers "F.Cu" "B.Cu")
		(remove_unused_layers yes)
		(keep_end_layers yes)
		(zone_layer_connections "In2.Cu" "In4.Cu" "In6.Cu" "In9.Cu")
		(net 553)
	)
	(via
		(at 185.5 151.500001)
		(size 0.45)
		(drill 0.1)
		(layers "F.Cu" "B.Cu")
		(remove_unused_layers yes)
		(keep_end_layers yes)
		(zone_layer_connections "In4.Cu" "In6.Cu" "In9.Cu")
		(net 553)
	)
	(via
		(at 193.5 153.5)
		(size 0.45)
		(drill 0.1)
		(layers "F.Cu" "B.Cu")
		(remove_unused_layers yes)
		(keep_end_layers yes)
		(zone_layer_connections "In4.Cu" "In6.Cu" "In9.Cu")
		(net 553)
	)
	(via
		(at 203.5 160.4995)
		(size 0.45)
		(drill 0.1)
		(layers "F.Cu" "B.Cu")
		(remove_unused_layers yes)
		(keep_end_layers yes)
		(zone_layer_connections "In2.Cu" "In4.Cu" "In6.Cu" "In9.Cu")
		(net 553)
	)
	(via
		(at 228.949999 166.025)
		(size 0.45)
		(drill 0.1)
		(layers "F.Cu" "B.Cu")
		(remove_unused_layers yes)
		(keep_end_layers yes)
		(zone_layer_connections "In2.Cu" "In4.Cu" "In6.Cu" "In9.Cu")
		(net 553)
	)
	(via
		(at 184.5 155.5)
		(size 0.45)
		(drill 0.1)
		(layers "F.Cu" "B.Cu")
		(remove_unused_layers yes)
		(keep_end_layers yes)
		(zone_layer_connections "In2.Cu" "In4.Cu" "In6.Cu" "In9.Cu")
		(net 553)
	)
	(via
		(at 212.719998 161.65)
		(size 0.45)
		(drill 0.1)
		(layers "F.Cu" "B.Cu")
		(remove_unused_layers yes)
		(keep_end_layers yes)
		(zone_layer_connections "In2.Cu" "In4.Cu" "In6.Cu" "In9.Cu")
		(net 553)
	)
	(via
		(at 214.039997 164.45)
		(size 0.45)
		(drill 0.1)
		(layers "F.Cu" "B.Cu")
		(remove_unused_layers yes)
		(keep_end_layers yes)
		(zone_layer_connections "In2.Cu" "In4.Cu" "In6.Cu" "In9.Cu")
		(net 553)
	)
	(via
		(at 211.619999 167.675004)
		(size 0.45)
		(drill 0.1)
		(layers "F.Cu" "B.Cu")
		(remove_unused_layers yes)
		(keep_end_layers yes)
		(zone_layer_connections "In2.Cu" "In4.Cu" "In6.Cu" "In9.Cu")
		(net 553)
	)
	(via
		(at 223.28 165.474998)
		(size 0.45)
		(drill 0.1)
		(layers "F.Cu" "B.Cu")
		(remove_unused_layers yes)
		(keep_end_layers yes)
		(zone_layer_connections "In2.Cu" "In4.Cu" "In6.Cu" "In9.Cu")
		(net 553)
	)
	(via
		(at 191.5 148.5)
		(size 0.45)
		(drill 0.1)
		(layers "F.Cu" "B.Cu")
		(remove_unused_layers yes)
		(keep_end_layers yes)
		(zone_layer_connections "In4.Cu" "In6.Cu" "In9.Cu")
		(net 553)
	)
	(via
		(at 216.94 165.500001)
		(size 0.45)
		(drill 0.1)
		(layers "F.Cu" "B.Cu")
		(remove_unused_layers yes)
		(keep_end_layers yes)
		(zone_layer_connections "In2.Cu" "In4.Cu" "In6.Cu" "In9.Cu")
		(net 553)
	)
	(via
		(at 219.279998 164.45)
		(size 0.45)
		(drill 0.1)
		(layers "F.Cu" "B.Cu")
		(remove_unused_layers yes)
		(keep_end_layers yes)
		(zone_layer_connections "In2.Cu" "In4.Cu" "In6.Cu" "In9.Cu")
		(net 553)
	)
	(via
		(at 216.959998 161.6)
		(size 0.45)
		(drill 0.1)
		(layers "F.Cu" "B.Cu")
		(remove_unused_layers yes)
		(keep_end_layers yes)
		(zone_layer_connections "In2.Cu" "In4.Cu" "In6.Cu" "In9.Cu")
		(net 553)
	)
	(via
		(at 230.04 166.15)
		(size 0.45)
		(drill 0.1)
		(layers "F.Cu" "B.Cu")
		(remove_unused_layers yes)
		(keep_end_layers yes)
		(zone_layer_connections "In2.Cu" "In4.Cu" "In6.Cu" "In9.Cu")
		(net 553)
	)
	(via
		(at 187.500001 157.5)
		(size 0.45)
		(drill 0.1)
		(layers "F.Cu" "B.Cu")
		(remove_unused_layers yes)
		(keep_end_layers yes)
		(zone_layer_connections "In2.Cu" "In4.Cu" "In6.Cu" "In9.Cu")
		(net 553)
	)
	(via
		(at 208.479998 165.45)
		(size 0.45)
		(drill 0.1)
		(layers "F.Cu" "B.Cu")
		(remove_unused_layers yes)
		(keep_end_layers yes)
		(zone_layer_connections "In2.Cu" "In4.Cu" "In6.Cu" "In9.Cu")
		(net 553)
	)
	(via
		(at 213.799999 163.4)
		(size 0.45)
		(drill 0.1)
		(layers "F.Cu" "B.Cu")
		(remove_unused_layers yes)
		(keep_end_layers yes)
		(zone_layer_connections "In2.Cu" "In4.Cu" "In6.Cu" "In9.Cu")
		(net 553)
	)
	(via
		(at 205.9 164.775)
		(size 0.45)
		(drill 0.1)
		(layers "F.Cu" "B.Cu")
		(remove_unused_layers yes)
		(keep_end_layers yes)
		(zone_layer_connections "In2.Cu" "In4.Cu" "In6.Cu" "In9.Cu")
		(net 553)
	)
	(via
		(at 186.5 157.5)
		(size 0.45)
		(drill 0.1)
		(layers "F.Cu" "B.Cu")
		(remove_unused_layers yes)
		(keep_end_layers yes)
		(zone_layer_connections "In2.Cu" "In4.Cu" "In6.Cu" "In9.Cu")
		(net 553)
	)
	(via
		(at 208.480001 167.6)
		(size 0.45)
		(drill 0.1)
		(layers "F.Cu" "B.Cu")
		(remove_unused_layers yes)
		(keep_end_layers yes)
		(zone_layer_connections "In2.Cu" "In4.Cu" "In6.Cu" "In9.Cu")
		(net 553)
	)
	(via
		(at 205.85 168.4)
		(size 0.45)
		(drill 0.1)
		(layers "F.Cu" "B.Cu")
		(remove_unused_layers yes)
		(keep_end_layers yes)
		(zone_layer_connections "In2.Cu" "In4.Cu" "In6.Cu" "In9.Cu")
		(net 553)
	)
	(via
		(at 186.5 155.5)
		(size 0.45)
		(drill 0.1)
		(layers "F.Cu" "B.Cu")
		(remove_unused_layers yes)
		(keep_end_layers yes)
		(zone_layer_connections "In2.Cu" "In4.Cu" "In6.Cu" "In9.Cu")
		(net 553)
	)
	(via
		(at 190.5 156.5)
		(size 0.45)
		(drill 0.1)
		(layers "F.Cu" "B.Cu")
		(remove_unused_layers yes)
		(keep_end_layers yes)
		(zone_layer_connections "In2.Cu" "In4.Cu" "In6.Cu" "In9.Cu")
		(net 553)
	)
	(via
		(at 193.5 150.5)
		(size 0.45)
		(drill 0.1)
		(layers "F.Cu" "B.Cu")
		(remove_unused_layers yes)
		(keep_end_layers yes)
		(zone_layer_connections "In4.Cu" "In6.Cu" "In9.Cu")
		(net 553)
	)
	(via
		(at 208.719997 164.475006)
		(size 0.45)
		(drill 0.1)
		(layers "F.Cu" "B.Cu")
		(remove_unused_layers yes)
		(keep_end_layers yes)
		(zone_layer_connections "In2.Cu" "In4.Cu" "In6.Cu" "In9.Cu")
		(net 553)
	)
	(via
		(at 189.5 157.5)
		(size 0.45)
		(drill 0.1)
		(layers "F.Cu" "B.Cu")
		(remove_unused_layers yes)
		(keep_end_layers yes)
		(zone_layer_connections "In2.Cu" "In4.Cu" "In6.Cu" "In9.Cu")
		(net 553)
	)
	(via
		(at 220.139999 165.4)
		(size 0.45)
		(drill 0.1)
		(layers "F.Cu" "B.Cu")
		(remove_unused_layers yes)
		(keep_end_layers yes)
		(zone_layer_connections "In2.Cu" "In4.Cu" "In6.Cu" "In9.Cu")
		(net 553)
	)
	(via
		(at 189.5 150.5)
		(size 0.45)
		(drill 0.1)
		(layers "F.Cu" "B.Cu")
		(remove_unused_layers yes)
		(keep_end_layers yes)
		(zone_layer_connections "In2.Cu" "In4.Cu" "In6.Cu" "In9.Cu")
		(net 553)
	)
	(via
		(at 217.979999 161.025)
		(size 0.45)
		(drill 0.1)
		(layers "F.Cu" "B.Cu")
		(remove_unused_layers yes)
		(keep_end_layers yes)
		(zone_layer_connections "In2.Cu" "In4.Cu" "In6.Cu" "In9.Cu")
		(net 553)
	)
	(via
		(at 203.5 152.4995)
		(size 0.45)
		(drill 0.1)
		(layers "F.Cu" "B.Cu")
		(remove_unused_layers yes)
		(keep_end_layers yes)
		(zone_layer_connections "In6.Cu" "In9.Cu")
		(net 553)
	)
	(via
		(at 185.5 154.5)
		(size 0.45)
		(drill 0.1)
		(layers "F.Cu" "B.Cu")
		(remove_unused_layers yes)
		(keep_end_layers yes)
		(zone_layer_connections "In2.Cu" "In4.Cu" "In6.Cu" "In9.Cu")
		(net 553)
	)
	(via
		(at 226.849999 166.1)
		(size 0.45)
		(drill 0.1)
		(layers "F.Cu" "B.Cu")
		(remove_unused_layers yes)
		(keep_end_layers yes)
		(zone_layer_connections "In2.Cu" "In4.Cu" "In6.Cu" "In9.Cu")
		(net 553)
	)
	(via
		(at 225.84 166.2)
		(size 0.45)
		(drill 0.1)
		(layers "F.Cu" "B.Cu")
		(remove_unused_layers yes)
		(keep_end_layers yes)
		(zone_layer_connections "In2.Cu" "In4.Cu" "In6.Cu" "In9.Cu")
		(net 553)
	)
	(via
		(at 213.739999 161.075)
		(size 0.45)
		(drill 0.1)
		(layers "F.Cu" "B.Cu")
		(remove_unused_layers yes)
		(keep_end_layers yes)
		(zone_layer_connections "In2.Cu" "In4.Cu" "In6.Cu" "In9.Cu")
		(net 553)
	)
	(via
		(at 209.739997 166.600005)
		(size 0.45)
		(drill 0.1)
		(layers "F.Cu" "B.Cu")
		(remove_unused_layers yes)
		(keep_end_layers yes)
		(zone_layer_connections "In2.Cu" "In4.Cu" "In6.Cu" "In9.Cu")
		(net 553)
	)
	(via
		(at 193.5 148.5)
		(size 0.45)
		(drill 0.1)
		(layers "F.Cu" "B.Cu")
		(remove_unused_layers yes)
		(keep_end_layers yes)
		(zone_layer_connections "In4.Cu" "In6.Cu" "In9.Cu")
		(net 553)
	)
	(via
		(at 224.3 165.449998)
		(size 0.45)
		(drill 0.1)
		(layers "F.Cu" "B.Cu")
		(remove_unused_layers yes)
		(keep_end_layers yes)
		(zone_layer_connections "In2.Cu" "In4.Cu" "In6.Cu" "In9.Cu")
		(net 553)
	)
	(via
		(at 209.499999 161.125)
		(size 0.45)
		(drill 0.1)
		(layers "F.Cu" "B.Cu")
		(remove_unused_layers yes)
		(keep_end_layers yes)
		(zone_layer_connections "In2.Cu" "In4.Cu" "In6.Cu" "In9.Cu")
		(net 553)
	)
	(via
		(at 191.5 157.500001)
		(size 0.45)
		(drill 0.1)
		(layers "F.Cu" "B.Cu")
		(remove_unused_layers yes)
		(keep_end_layers yes)
		(zone_layer_connections "In2.Cu" "In4.Cu" "In6.Cu" "In9.Cu")
		(net 553)
	)
	(via
		(at 223.28 163.4)
		(size 0.45)
		(drill 0.1)
		(layers "F.Cu" "B.Cu")
		(remove_unused_layers yes)
		(keep_end_layers yes)
		(zone_layer_connections "In2.Cu" "In4.Cu" "In6.Cu" "In9.Cu")
		(net 553)
	)
	(via
		(at 208.479998 161.250007)
		(size 0.45)
		(drill 0.1)
		(layers "F.Cu" "B.Cu")
		(remove_unused_layers yes)
		(keep_end_layers yes)
		(zone_layer_connections "In2.Cu" "In4.Cu" "In6.Cu" "In9.Cu")
		(net 553)
	)
	(via
		(at 226.299999 166.95)
		(size 0.45)
		(drill 0.1)
		(layers "F.Cu" "B.Cu")
		(remove_unused_layers yes)
		(keep_end_layers yes)
		(zone_layer_connections "In2.Cu" "In4.Cu" "In6.Cu" "In9.Cu")
		(net 553)
	)
	(via
		(at 205.8 177.3)
		(size 0.45)
		(drill 0.1)
		(layers "F.Cu" "B.Cu")
		(remove_unused_layers yes)
		(keep_end_layers yes)
		(zone_layer_connections "In2.Cu" "In4.Cu" "In6.Cu" "In9.Cu")
		(net 553)
	)
	(via
		(at 221.16 165.5)
		(size 0.45)
		(drill 0.1)
		(layers "F.Cu" "B.Cu")
		(remove_unused_layers yes)
		(keep_end_layers yes)
		(zone_layer_connections "In2.Cu" "In4.Cu" "In6.Cu" "In9.Cu")
		(net 553)
	)
	(via
		(at 223.65 166.2)
		(size 0.45)
		(drill 0.1)
		(layers "F.Cu" "B.Cu")
		(remove_unused_layers yes)
		(keep_end_layers yes)
		(zone_layer_connections "In2.Cu" "In4.Cu" "In6.Cu" "In9.Cu")
		(net 553)
	)
	(via
		(at 184.5 150.5)
		(size 0.45)
		(drill 0.1)
		(layers "F.Cu" "B.Cu")
		(remove_unused_layers yes)
		(keep_end_layers yes)
		(zone_layer_connections "In2.Cu" "In4.Cu" "In6.Cu" "In9.Cu")
		(net 553)
	)
	(via
		(at 185.5 156.5)
		(size 0.45)
		(drill 0.1)
		(layers "F.Cu" "B.Cu")
		(remove_unused_layers yes)
		(keep_end_layers yes)
		(zone_layer_connections "In2.Cu" "In4.Cu" "In6.Cu" "In9.Cu")
		(net 553)
	)
	(via
		(at 205.8 175.45)
		(size 0.45)
		(drill 0.1)
		(layers "F.Cu" "B.Cu")
		(remove_unused_layers yes)
		(keep_end_layers yes)
		(zone_layer_connections "In2.Cu" "In4.Cu" "In6.Cu" "In9.Cu")
		(net 553)
	)
	(via
		(at 192.5 149.5)
		(size 0.45)
		(drill 0.1)
		(layers "F.Cu" "B.Cu")
		(remove_unused_layers yes)
		(keep_end_layers yes)
		(zone_layer_connections "In4.Cu" "In6.Cu" "In9.Cu")
		(net 553)
	)
	(via
		(at 227.36 165.374998)
		(size 0.45)
		(drill 0.1)
		(layers "F.Cu" "B.Cu")
		(remove_unused_layers yes)
		(keep_end_layers yes)
		(zone_layer_connections "In2.Cu" "In4.Cu" "In6.Cu" "In9.Cu")
		(net 553)
	)
	(via
		(at 213.86 166.28)
		(size 0.45)
		(drill 0.1)
		(layers "F.Cu" "B.Cu")
		(remove_unused_layers yes)
		(keep_end_layers yes)
		(zone_layer_connections "In2.Cu" "In4.Cu" "In6.Cu" "In9.Cu")
		(net 553)
	)
	(via
		(at 227.85 166.15)
		(size 0.45)
		(drill 0.1)
		(layers "F.Cu" "B.Cu")
		(remove_unused_layers yes)
		(keep_end_layers yes)
		(zone_layer_connections "In2.Cu" "In4.Cu" "In6.Cu" "In9.Cu")
		(net 553)
	)
	(via
		(at 190.5 149.5)
		(size 0.45)
		(drill 0.1)
		(layers "F.Cu" "B.Cu")
		(remove_unused_layers yes)
		(keep_end_layers yes)
		(zone_layer_connections "In2.Cu" "In4.Cu" "In6.Cu" "In9.Cu")
		(net 553)
	)
	(via
		(at 222.285 176.11)
		(size 0.45)
		(drill 0.1)
		(layers "F.Cu" "B.Cu")
		(remove_unused_layers yes)
		(keep_end_layers yes)
		(zone_layer_connections)
		(net 553)
	)
	(via
		(at 191.5 155.5)
		(size 0.45)
		(drill 0.1)
		(layers "F.Cu" "B.Cu")
		(remove_unused_layers yes)
		(keep_end_layers yes)
		(zone_layer_connections "In2.Cu" "In4.Cu" "In6.Cu" "In9.Cu")
		(net 553)
	)
	(via
		(at 225.32 165.424998)
		(size 0.45)
		(drill 0.1)
		(layers "F.Cu" "B.Cu")
		(remove_unused_layers yes)
		(keep_end_layers yes)
		(zone_layer_connections "In2.Cu" "In4.Cu" "In6.Cu" "In9.Cu")
		(net 553)
	)
	(via
		(at 215.859999 161.05)
		(size 0.45)
		(drill 0.1)
		(layers "F.Cu" "B.Cu")
		(remove_unused_layers yes)
		(keep_end_layers yes)
		(zone_layer_connections "In2.Cu" "In4.Cu" "In6.Cu" "In9.Cu")
		(net 553)
	)
	(via
		(at 189.5 148.5)
		(size 0.45)
		(drill 0.1)
		(layers "F.Cu" "B.Cu")
		(remove_unused_layers yes)
		(keep_end_layers yes)
		(zone_layer_connections "In4.Cu" "In6.Cu" "In9.Cu")
		(net 553)
	)
	(via
		(at 229.4 165.3)
		(size 0.45)
		(drill 0.1)
		(layers "F.Cu" "B.Cu")
		(remove_unused_layers yes)
		(keep_end_layers yes)
		(zone_layer_connections "In2.Cu" "In4.Cu" "In6.Cu" "In9.Cu")
		(net 553)
	)
	(via
		(at 204.5 161.5)
		(size 0.45)
		(drill 0.1)
		(layers "F.Cu" "B.Cu")
		(remove_unused_layers yes)
		(keep_end_layers yes)
		(zone_layer_connections "In2.Cu" "In4.Cu" "In6.Cu" "In9.Cu")
		(net 553)
	)
	(via
		(at 231.7 165.65)
		(size 0.45)
		(drill 0.1)
		(layers "F.Cu" "B.Cu")
		(remove_unused_layers yes)
		(keep_end_layers yes)
		(zone_layer_connections "In2.Cu")
		(net 553)
	)
	(via
		(at 224.749999 166.075)
		(size 0.45)
		(drill 0.1)
		(layers "F.Cu" "B.Cu")
		(remove_unused_layers yes)
		(keep_end_layers yes)
		(zone_layer_connections "In2.Cu" "In4.Cu" "In6.Cu" "In9.Cu")
		(net 553)
	)
	(via
		(at 217.949999 165.4)
		(size 0.45)
		(drill 0.1)
		(layers "F.Cu" "B.Cu")
		(remove_unused_layers yes)
		(keep_end_layers yes)
		(zone_layer_connections "In2.Cu" "In4.Cu" "In6.Cu" "In9.Cu")
		(net 553)
	)
	(via
		(at 221.199998 161.55)
		(size 0.45)
		(drill 0.1)
		(layers "F.Cu" "B.Cu")
		(remove_unused_layers yes)
		(keep_end_layers yes)
		(zone_layer_connections "In2.Cu" "In4.Cu" "In6.Cu" "In9.Cu")
		(net 553)
	)
	(via
		(at 205.3 158.4)
		(size 0.45)
		(drill 0.1)
		(layers "F.Cu" "B.Cu")
		(remove_unused_layers yes)
		(keep_end_layers yes)
		(zone_layer_connections "In4.Cu" "In6.Cu" "In9.Cu")
		(net 553)
	)
	(via
		(at 210.6 167.55)
		(size 0.45)
		(drill 0.1)
		(layers "F.Cu" "B.Cu")
		(remove_unused_layers yes)
		(keep_end_layers yes)
		(zone_layer_connections "In2.Cu" "In4.Cu" "In6.Cu" "In9.Cu")
		(net 553)
	)
	(via
		(at 210.599998 161.675)
		(size 0.45)
		(drill 0.1)
		(layers "F.Cu" "B.Cu")
		(remove_unused_layers yes)
		(keep_end_layers yes)
		(zone_layer_connections "In2.Cu" "In4.Cu" "In6.Cu" "In9.Cu")
		(net 553)
	)
	(via
		(at 209.499999 165.550005)
		(size 0.45)
		(drill 0.1)
		(layers "F.Cu" "B.Cu")
		(remove_unused_layers yes)
		(keep_end_layers yes)
		(zone_layer_connections "In2.Cu" "In4.Cu" "In6.Cu" "In9.Cu")
		(net 553)
	)
	(via
		(at 186.5 148.5)
		(size 0.45)
		(drill 0.1)
		(layers "F.Cu" "B.Cu")
		(remove_unused_layers yes)
		(keep_end_layers yes)
		(zone_layer_connections "In4.Cu" "In6.Cu" "In9.Cu")
		(net 553)
	)
	(via
		(at 184.5 153.5)
		(size 0.45)
		(drill 0.1)
		(layers "F.Cu" "B.Cu")
		(remove_unused_layers yes)
		(keep_end_layers yes)
		(zone_layer_connections "In2.Cu" "In4.Cu" "In6.Cu" "In9.Cu")
		(net 553)
	)
	(via
		(at 187.500001 149.5)
		(size 0.45)
		(drill 0.1)
		(layers "F.Cu" "B.Cu")
		(remove_unused_layers yes)
		(keep_end_layers yes)
		(zone_layer_connections "In4.Cu" "In6.Cu" "In9.Cu")
		(net 553)
	)
	(via
		(at 227.3 167)
		(size 0.45)
		(drill 0.1)
		(layers "F.Cu" "B.Cu")
		(remove_unused_layers yes)
		(keep_end_layers yes)
		(zone_layer_connections "In2.Cu" "In4.Cu" "In6.Cu" "In9.Cu")
		(net 553)
	)
	(via
		(at 223.519998 164.45)
		(size 0.45)
		(drill 0.1)
		(layers "F.Cu" "B.Cu")
		(remove_unused_layers yes)
		(keep_end_layers yes)
		(zone_layer_connections "In2.Cu" "In4.Cu" "In6.Cu" "In9.Cu")
		(net 553)
	)
	(via
		(at 220.099999 161)
		(size 0.45)
		(drill 0.1)
		(layers "F.Cu" "B.Cu")
		(remove_unused_layers yes)
		(keep_end_layers yes)
		(zone_layer_connections "In2.Cu" "In4.Cu" "In6.Cu" "In9.Cu")
		(net 553)
	)
	(via
		(at 209.499999 163.400006)
		(size 0.45)
		(drill 0.1)
		(layers "F.Cu" "B.Cu")
		(remove_unused_layers yes)
		(keep_end_layers yes)
		(zone_layer_connections "In2.Cu" "In4.Cu" "In6.Cu" "In9.Cu")
		(net 553)
	)
	(via
		(at 219.04 165.525)
		(size 0.45)
		(drill 0.1)
		(layers "F.Cu" "B.Cu")
		(remove_unused_layers yes)
		(keep_end_layers yes)
		(zone_layer_connections "In2.Cu" "In4.Cu" "In6.Cu" "In9.Cu")
		(net 553)
	)
	(via
		(at 189.499999 155.5)
		(size 0.45)
		(drill 0.1)
		(layers "F.Cu" "B.Cu")
		(remove_unused_layers yes)
		(keep_end_layers yes)
		(zone_layer_connections "In2.Cu" "In4.Cu" "In6.Cu" "In9.Cu")
		(net 553)
	)
	(via
		(at 207.379999 165.575005)
		(size 0.45)
		(drill 0.1)
		(layers "F.Cu" "B.Cu")
		(remove_unused_layers yes)
		(keep_end_layers yes)
		(zone_layer_connections "In2.Cu" "In4.Cu" "In6.Cu" "In9.Cu")
		(net 553)
	)
	(via
		(at 209.739997 162.300007)
		(size 0.45)
		(drill 0.1)
		(layers "F.Cu" "B.Cu")
		(remove_unused_layers yes)
		(keep_end_layers yes)
		(zone_layer_connections "In2.Cu" "In4.Cu" "In6.Cu" "In9.Cu")
		(net 553)
	)
	(via
		(at 231.5 166.6)
		(size 0.45)
		(drill 0.1)
		(layers "F.Cu" "B.Cu")
		(remove_unused_layers yes)
		(keep_end_layers yes)
		(zone_layer_connections "In2.Cu")
		(net 553)
	)
	(via
		(at 205.85 170.25)
		(size 0.45)
		(drill 0.1)
		(layers "F.Cu" "B.Cu")
		(remove_unused_layers yes)
		(keep_end_layers yes)
		(zone_layer_connections "In2.Cu" "In4.Cu" "In6.Cu" "In9.Cu")
		(net 553)
	)
	(via
		(at 208.479998 163.400006)
		(size 0.45)
		(drill 0.1)
		(layers "F.Cu" "B.Cu")
		(remove_unused_layers yes)
		(keep_end_layers yes)
		(zone_layer_connections "In2.Cu" "In4.Cu" "In6.Cu" "In9.Cu")
		(net 553)
	)
	(via
		(at 207.619997 162.325007)
		(size 0.45)
		(drill 0.1)
		(layers "F.Cu" "B.Cu")
		(remove_unused_layers yes)
		(keep_end_layers yes)
		(zone_layer_connections "In2.Cu" "In4.Cu" "In6.Cu" "In9.Cu")
		(net 553)
	)
	(via
		(at 207.379999 163.425006)
		(size 0.45)
		(drill 0.1)
		(layers "F.Cu" "B.Cu")
		(remove_unused_layers yes)
		(keep_end_layers yes)
		(zone_layer_connections "In2.Cu" "In4.Cu" "In6.Cu" "In9.Cu")
		(net 553)
	)
	(via
		(at 205.825 171.925)
		(size 0.45)
		(drill 0.1)
		(layers "F.Cu" "B.Cu")
		(remove_unused_layers yes)
		(keep_end_layers yes)
		(zone_layer_connections "In2.Cu" "In4.Cu" "In6.Cu" "In9.Cu")
		(net 553)
	)
	(via
		(at 223.319998 161.075007)
		(size 0.45)
		(drill 0.1)
		(layers "F.Cu" "B.Cu")
		(remove_unused_layers yes)
		(keep_end_layers yes)
		(zone_layer_connections "In2.Cu" "In4.Cu" "In6.Cu" "In9.Cu")
		(net 553)
	)
	(via
		(at 177.5 166.45)
		(size 0.45)
		(drill 0.1)
		(layers "F.Cu" "B.Cu")
		(remove_unused_layers yes)
		(keep_end_layers yes)
		(zone_layer_connections "In4.Cu" "In6.Cu" "In9.Cu")
		(net 553)
	)
	(via
		(at 205.875 166.725)
		(size 0.45)
		(drill 0.1)
		(layers "F.Cu" "B.Cu")
		(remove_unused_layers yes)
		(keep_end_layers yes)
		(zone_layer_connections "In2.Cu" "In4.Cu" "In6.Cu" "In9.Cu")
		(net 553)
	)
	(via
		(at 185.5 157.5)
		(size 0.45)
		(drill 0.1)
		(layers "F.Cu" "B.Cu")
		(remove_unused_layers yes)
		(keep_end_layers yes)
		(zone_layer_connections "In2.Cu" "In4.Cu" "In6.Cu" "In9.Cu")
		(net 553)
	)
	(via
		(at 213.75 165.349997)
		(size 0.45)
		(drill 0.1)
		(layers "F.Cu" "B.Cu")
		(remove_unused_layers yes)
		(keep_end_layers yes)
		(zone_layer_connections "In2.Cu" "In4.Cu" "In6.Cu" "In9.Cu")
		(net 553)
	)
	(via
		(at 208.719997 162.325007)
		(size 0.45)
		(drill 0.1)
		(layers "F.Cu" "B.Cu")
		(remove_unused_layers yes)
		(keep_end_layers yes)
		(zone_layer_connections "In2.Cu" "In4.Cu" "In6.Cu" "In9.Cu")
		(net 553)
	)
	(via
		(at 208.719997 166.525)
		(size 0.45)
		(drill 0.1)
		(layers "F.Cu" "B.Cu")
		(remove_unused_layers yes)
		(keep_end_layers yes)
		(zone_layer_connections "In2.Cu" "In4.Cu" "In6.Cu" "In9.Cu")
		(net 553)
	)
	(via
		(at 223.519998 162.325)
		(size 0.45)
		(drill 0.1)
		(layers "F.Cu" "B.Cu")
		(remove_unused_layers yes)
		(keep_end_layers yes)
		(zone_layer_connections "In2.Cu" "In4.Cu" "In6.Cu" "In9.Cu")
		(net 553)
	)
	(via
		(at 209.739997 164.450006)
		(size 0.45)
		(drill 0.1)
		(layers "F.Cu" "B.Cu")
		(remove_unused_layers yes)
		(keep_end_layers yes)
		(zone_layer_connections "In2.Cu" "In4.Cu" "In6.Cu" "In9.Cu")
		(net 553)
	)
	(via
		(at 192.5 154.5)
		(size 0.45)
		(drill 0.1)
		(layers "F.Cu" "B.Cu")
		(remove_unused_layers yes)
		(keep_end_layers yes)
		(zone_layer_connections "In2.Cu" "In4.Cu" "In6.Cu" "In9.Cu")
		(net 553)
	)
	(via
		(at 205.2 160.5)
		(size 0.45)
		(drill 0.1)
		(layers "F.Cu" "B.Cu")
		(remove_unused_layers yes)
		(keep_end_layers yes)
		(zone_layer_connections "In2.Cu" "In4.Cu" "In6.Cu" "In9.Cu")
		(net 553)
	)
	(via
		(at 211.619999 165.525003)
		(size 0.45)
		(drill 0.1)
		(layers "F.Cu" "B.Cu")
		(remove_unused_layers yes)
		(keep_end_layers yes)
		(zone_layer_connections "In2.Cu" "In4.Cu" "In6.Cu" "In9.Cu")
		(net 553)
	)
	(via
		(at 226.34 165.399998)
		(size 0.45)
		(drill 0.1)
		(layers "F.Cu" "B.Cu")
		(remove_unused_layers yes)
		(keep_end_layers yes)
		(zone_layer_connections "In2.Cu" "In4.Cu" "In6.Cu" "In9.Cu")
		(net 553)
	)
	(via
		(at 211.859997 166.575005)
		(size 0.45)
		(drill 0.1)
		(layers "F.Cu" "B.Cu")
		(remove_unused_layers yes)
		(keep_end_layers yes)
		(zone_layer_connections "In2.Cu" "In4.Cu" "In6.Cu" "In9.Cu")
		(net 553)
	)
	(via
		(at 214.839998 161.625)
		(size 0.45)
		(drill 0.1)
		(layers "F.Cu" "B.Cu")
		(remove_unused_layers yes)
		(keep_end_layers yes)
		(zone_layer_connections "In2.Cu" "In4.Cu" "In6.Cu" "In9.Cu")
		(net 553)
	)
	(via
		(at 205.325 162.375)
		(size 0.45)
		(drill 0.1)
		(layers "F.Cu" "B.Cu")
		(remove_unused_layers yes)
		(keep_end_layers yes)
		(zone_layer_connections "In2.Cu" "In4.Cu" "In6.Cu" "In9.Cu")
		(net 553)
	)
	(via
		(at 206.359998 161.275007)
		(size 0.45)
		(drill 0.1)
		(layers "F.Cu" "B.Cu")
		(remove_unused_layers yes)
		(keep_end_layers yes)
		(zone_layer_connections "In2.Cu" "In4.Cu" "In6.Cu" "In9.Cu")
		(net 553)
	)
	(via
		(at 190.5 154.5)
		(size 0.45)
		(drill 0.1)
		(layers "F.Cu" "B.Cu")
		(remove_unused_layers yes)
		(keep_end_layers yes)
		(zone_layer_connections "In2.Cu" "In4.Cu" "In6.Cu" "In9.Cu")
		(net 553)
	)
	(via
		(at 186.5 153.5)
		(size 0.45)
		(drill 0.1)
		(layers "F.Cu" "B.Cu")
		(remove_unused_layers yes)
		(keep_end_layers yes)
		(zone_layer_connections "In2.Cu" "In4.Cu" "In6.Cu" "In9.Cu")
		(net 553)
	)
	(via
		(at 193.5 157.5)
		(size 0.45)
		(drill 0.1)
		(layers "F.Cu" "B.Cu")
		(remove_unused_layers yes)
		(keep_end_layers yes)
		(zone_layer_connections "In2.Cu" "In4.Cu" "In6.Cu" "In9.Cu")
		(net 553)
	)
	(via
		(at 212.82 166.48)
		(size 0.45)
		(drill 0.1)
		(layers "F.Cu" "B.Cu")
		(remove_unused_layers yes)
		(keep_end_layers yes)
		(zone_layer_connections "In2.Cu" "In4.Cu" "In6.Cu" "In9.Cu")
		(net 553)
	)
	(via
		(at 192.5 156.5)
		(size 0.45)
		(drill 0.1)
		(layers "F.Cu" "B.Cu")
		(remove_unused_layers yes)
		(keep_end_layers yes)
		(zone_layer_connections "In2.Cu" "In4.Cu" "In6.Cu" "In9.Cu")
		(net 553)
	)
	(via
		(at 191.5 150.5)
		(size 0.45)
		(drill 0.1)
		(layers "F.Cu" "B.Cu")
		(remove_unused_layers yes)
		(keep_end_layers yes)
		(zone_layer_connections "In2.Cu" "In4.Cu" "In6.Cu" "In9.Cu")
		(net 553)
	)
	(via
		(at 193.500001 155.5)
		(size 0.45)
		(drill 0.1)
		(layers "F.Cu" "B.Cu")
		(remove_unused_layers yes)
		(keep_end_layers yes)
		(zone_layer_connections "In2.Cu" "In4.Cu" "In6.Cu" "In9.Cu")
		(net 553)
	)
	(via
		(at 214.039997 162.325)
		(size 0.45)
		(drill 0.1)
		(layers "F.Cu" "B.Cu")
		(remove_unused_layers yes)
		(keep_end_layers yes)
		(zone_layer_connections "In2.Cu" "In4.Cu" "In6.Cu" "In9.Cu")
		(net 553)
	)
	(via
		(at 215.919999 165.35)
		(size 0.45)
		(drill 0.1)
		(layers "F.Cu" "B.Cu")
		(remove_unused_layers yes)
		(keep_end_layers yes)
		(zone_layer_connections "In2.Cu" "In4.Cu" "In6.Cu" "In9.Cu")
		(net 553)
	)
	(via
		(at 231.8 167.5)
		(size 0.45)
		(drill 0.1)
		(layers "F.Cu" "B.Cu")
		(remove_unused_layers yes)
		(keep_end_layers yes)
		(zone_layer_connections "In2.Cu")
		(net 553)
	)
	(via
		(at 206.125 163.525)
		(size 0.45)
		(drill 0.1)
		(layers "F.Cu" "B.Cu")
		(remove_unused_layers yes)
		(keep_end_layers yes)
		(zone_layer_connections "In2.Cu" "In4.Cu" "In6.Cu" "In9.Cu")
		(net 553)
	)
	(via
		(at 210.599997 165.4)
		(size 0.45)
		(drill 0.1)
		(layers "F.Cu" "B.Cu")
		(remove_unused_layers yes)
		(keep_end_layers yes)
		(zone_layer_connections "In2.Cu" "In4.Cu" "In6.Cu" "In9.Cu")
		(net 553)
	)
	(via
		(at 206.599997 162.350007)
		(size 0.45)
		(drill 0.1)
		(layers "F.Cu" "B.Cu")
		(remove_unused_layers yes)
		(keep_end_layers yes)
		(zone_layer_connections "In2.Cu" "In4.Cu" "In6.Cu" "In9.Cu")
		(net 553)
	)
	(via
		(at 184.5 148.5)
		(size 0.45)
		(drill 0.1)
		(layers "F.Cu" "B.Cu")
		(remove_unused_layers yes)
		(keep_end_layers yes)
		(zone_layer_connections "In4.Cu" "In6.Cu" "In9.Cu")
		(net 553)
	)
	(via
		(at 186.5 150.5)
		(size 0.45)
		(drill 0.1)
		(layers "F.Cu" "B.Cu")
		(remove_unused_layers yes)
		(keep_end_layers yes)
		(zone_layer_connections "In2.Cu" "In4.Cu" "In6.Cu" "In9.Cu")
		(net 553)
	)
	(via
		(at 207.619997 166.625005)
		(size 0.45)
		(drill 0.1)
		(layers "F.Cu" "B.Cu")
		(remove_unused_layers yes)
		(keep_end_layers yes)
		(zone_layer_connections "In2.Cu" "In4.Cu" "In6.Cu" "In9.Cu")
		(net 553)
	)
	(via
		(at 204.5 153.5)
		(size 0.45)
		(drill 0.1)
		(layers "F.Cu" "B.Cu")
		(remove_unused_layers yes)
		(keep_end_layers yes)
		(zone_layer_connections "In6.Cu" "In9.Cu")
		(net 553)
	)
	(via
		(at 212.650001 165.55)
		(size 0.45)
		(drill 0.1)
		(layers "F.Cu" "B.Cu")
		(remove_unused_layers yes)
		(keep_end_layers yes)
		(zone_layer_connections "In2.Cu" "In4.Cu" "In6.Cu" "In9.Cu")
		(net 553)
	)
	(via
		(at 190.5 157.5)
		(size 0.45)
		(drill 0.1)
		(layers "F.Cu" "B.Cu")
		(remove_unused_layers yes)
		(keep_end_layers yes)
		(zone_layer_connections "In2.Cu" "In4.Cu" "In6.Cu" "In9.Cu")
		(net 553)
	)
	(via
		(at 219.04 163.4)
		(size 0.45)
		(drill 0.1)
		(layers "F.Cu" "B.Cu")
		(remove_unused_layers yes)
		(keep_end_layers yes)
		(zone_layer_connections "In2.Cu" "In4.Cu" "In6.Cu" "In9.Cu")
		(net 553)
	)
	(via
		(at 214.82 165.475)
		(size 0.45)
		(drill 0.1)
		(layers "F.Cu" "B.Cu")
		(remove_unused_layers yes)
		(keep_end_layers yes)
		(zone_layer_connections "In2.Cu" "In4.Cu" "In6.Cu" "In9.Cu")
		(net 553)
	)
	(via
		(at 219.279998 162.325)
		(size 0.45)
		(drill 0.1)
		(layers "F.Cu" "B.Cu")
		(remove_unused_layers yes)
		(keep_end_layers yes)
		(zone_layer_connections "In2.Cu" "In4.Cu" "In6.Cu" "In9.Cu")
		(net 553)
	)
	(via
		(at 185.5 149.5)
		(size 0.45)
		(drill 0.1)
		(layers "F.Cu" "B.Cu")
		(remove_unused_layers yes)
		(keep_end_layers yes)
		(zone_layer_connections "In4.Cu" "In6.Cu" "In9.Cu")
		(net 553)
	)
	(via
		(at 207.619997 164.475006)
		(size 0.45)
		(drill 0.1)
		(layers "F.Cu" "B.Cu")
		(remove_unused_layers yes)
		(keep_end_layers yes)
		(zone_layer_connections "In2.Cu" "In4.Cu" "In6.Cu" "In9.Cu")
		(net 553)
	)
	(via
		(at 222.219999 160.975)
		(size 0.45)
		(drill 0.1)
		(layers "F.Cu" "B.Cu")
		(remove_unused_layers yes)
		(keep_end_layers yes)
		(zone_layer_connections "In2.Cu" "In4.Cu" "In6.Cu" "In9.Cu")
		(net 553)
	)
	(via
		(at 230.42 165.299998)
		(size 0.45)
		(drill 0.1)
		(layers "F.Cu" "B.Cu")
		(remove_unused_layers yes)
		(keep_end_layers yes)
		(zone_layer_connections "In2.Cu" "In4.Cu" "In6.Cu" "In9.Cu")
		(net 553)
	)
	(via
		(at 203.5 156.4995)
		(size 0.45)
		(drill 0.1)
		(layers "F.Cu" "B.Cu")
		(remove_unused_layers yes)
		(keep_end_layers yes)
		(zone_layer_connections "In6.Cu" "In9.Cu")
		(net 553)
	)
	(via
		(at 207.379999 161.15)
		(size 0.45)
		(drill 0.1)
		(layers "F.Cu" "B.Cu")
		(remove_unused_layers yes)
		(keep_end_layers yes)
		(zone_layer_connections "In2.Cu" "In4.Cu" "In6.Cu" "In9.Cu")
		(net 553)
	)
	(via
		(at 207.379999 167.700005)
		(size 0.45)
		(drill 0.1)
		(layers "F.Cu" "B.Cu")
		(remove_unused_layers yes)
		(keep_end_layers yes)
		(zone_layer_connections "In2.Cu" "In4.Cu" "In6.Cu" "In9.Cu")
		(net 553)
	)
	(via
		(at 228.38 165.349998)
		(size 0.45)
		(drill 0.1)
		(layers "F.Cu" "B.Cu")
		(remove_unused_layers yes)
		(keep_end_layers yes)
		(zone_layer_connections "In2.Cu" "In4.Cu" "In6.Cu" "In9.Cu")
		(net 553)
	)
	(via
		(at 210.839996 166.475)
		(size 0.45)
		(drill 0.1)
		(layers "F.Cu" "B.Cu")
		(remove_unused_layers yes)
		(keep_end_layers yes)
		(zone_layer_connections "In2.Cu" "In4.Cu" "In6.Cu" "In9.Cu")
		(net 553)
	)
	(via
		(at 222.249997 165.35)
		(size 0.45)
		(drill 0.1)
		(layers "F.Cu" "B.Cu")
		(remove_unused_layers yes)
		(keep_end_layers yes)
		(zone_layer_connections "In2.Cu" "In4.Cu" "In6.Cu" "In9.Cu")
		(net 553)
	)
	(via
		(at 176.5 166.45)
		(size 0.45)
		(drill 0.1)
		(layers "F.Cu" "B.Cu")
		(remove_unused_layers yes)
		(keep_end_layers yes)
		(zone_layer_connections "In4.Cu" "In6.Cu" "In9.Cu")
		(net 553)
	)
	(via
		(at 205.825 173.775)
		(size 0.45)
		(drill 0.1)
		(layers "F.Cu" "B.Cu")
		(remove_unused_layers yes)
		(keep_end_layers yes)
		(zone_layer_connections "In2.Cu" "In4.Cu" "In6.Cu" "In9.Cu")
		(net 553)
	)
	(via
		(at 192.5 151.5)
		(size 0.45)
		(drill 0.1)
		(layers "F.Cu" "B.Cu")
		(remove_unused_layers yes)
		(keep_end_layers yes)
		(zone_layer_connections "In4.Cu" "In6.Cu" "In9.Cu")
		(net 553)
	)
	(via
		(at 214.910001 166.405)
		(size 0.45)
		(drill 0.1)
		(layers "F.Cu" "B.Cu")
		(remove_unused_layers yes)
		(keep_end_layers yes)
		(zone_layer_connections "In2.Cu" "In4.Cu" "In6.Cu" "In9.Cu")
		(net 553)
	)
	(via
		(at 187.5 154.5)
		(size 0.45)
		(drill 0.1)
		(layers "F.Cu" "B.Cu")
		(remove_unused_layers yes)
		(keep_end_layers yes)
		(zone_layer_connections "In2.Cu" "In4.Cu" "In6.Cu" "In9.Cu")
		(net 553)
	)
	(segment
		(start 186.997999 148.997999)
		(end 186.5 148.5)
		(width 0.256)
		(layer "B.Cu")
		(net 553)
	)
	(segment
		(start 190 158)
		(end 189.5 157.5)
		(width 0.256)
		(layer "B.Cu")
		(net 553)
	)
	(segment
		(start 191.5 148.5)
		(end 191.502 148.5)
		(width 0.256)
		(layer "B.Cu")
		(net 553)
	)
	(segment
		(start 188.5 150.15)
		(end 189.15 150.15)
		(width 0.4)
		(layer "B.Cu")
		(net 553)
	)
	(segment
		(start 185 151)
		(end 185.5 151.5)
		(width 0.256)
		(layer "B.Cu")
		(net 553)
	)
	(segment
		(start 191.502 148.5)
		(end 192 148.002)
		(width 0.256)
		(layer "B.Cu")
		(net 553)
	)
	(segment
		(start 193.5 150.5)
		(end 193.498 150.5)
		(width 0.256)
		(layer "B.Cu")
		(net 553)
	)
	(segment
		(start 191.5 157.502)
		(end 192 158.002)
		(width 0.256)
		(layer "B.Cu")
		(net 553)
	)
	(segment
		(start 184.5 153.5)
		(end 184.5 152.675)
		(width 0.256)
		(layer "B.Cu")
		(net 553)
	)
	(segment
		(start 222.135 176.26)
		(end 222.285 176.11)
		(width 0.15)
		(layer "B.Cu")
		(net 553)
	)
	(segment
		(start 186 158)
		(end 186.5 157.5)
		(width 0.256)
		(layer "B.Cu")
		(net 553)
	)
	(segment
		(start 192 158)
		(end 192.5 157.5)
		(width 0.256)
		(layer "B.Cu")
		(net 553)
	)
	(segment
		(start 191.5 155.498)
		(end 192 154.998)
		(width 0.256)
		(layer "B.Cu")
		(net 553)
	)
	(segment
		(start 193.502 148.5)
		(end 194 148.002)
		(width 0.256)
		(layer "B.Cu")
		(net 553)
	)
	(segment
		(start 193.5 153.502)
		(end 194 154.002)
		(width 0.256)
		(layer "B.Cu")
		(net 553)
	)
	(segment
		(start 192 157)
		(end 192.5 157.5)
		(width 0.256)
		(layer "B.Cu")
		(net 553)
	)
	(segment
		(start 187.500001 157.5)
		(end 187.500001 157.498001)
		(width 0.256)
		(layer "B.Cu")
		(net 553)
	)
	(segment
		(start 185.374999 151.500001)
		(end 184.35 152.525)
		(width 0.256)
		(layer "B.Cu")
		(net 553)
	)
	(segment
		(start 189.499999 155.315027)
		(end 188.634972 154.45)
		(width 0.4)
		(layer "B.Cu")
		(net 553)
	)
	(segment
		(start 187 148.999999)
		(end 187.500001 149.5)
		(width 0.256)
		(layer "B.Cu")
		(net 553)
	)
	(segment
		(start 193 148.998)
		(end 193.002 148.998)
		(width 0.256)
		(layer "B.Cu")
		(net 553)
	)
	(segment
		(start 191.5 157.500001)
		(end 191.5 157.498)
		(width 0.256)
		(layer "B.Cu")
		(net 553)
	)
	(segment
		(start 187.002 156.998)
		(end 187.5 156.5)
		(width 0.256)
		(layer "B.Cu")
		(net 553)
	)
	(segment
		(start 190.5 149.498)
		(end 191 148.998)
		(width 0.256)
		(layer "B.Cu")
		(net 553)
	)
	(segment
		(start 191.5 150.5)
		(end 191.498 150.5)
		(width 0.256)
		(layer "B.Cu")
		(net 553)
	)
	(segment
		(start 185.5 151.500001)
		(end 185.374999 151.500001)
		(width 0.256)
		(layer "B.Cu")
		(net 553)
	)
	(segment
		(start 184.5 152.675)
		(end 184.35 152.525)
		(width 0.256)
		(layer "B.Cu")
		(net 553)
	)
	(segment
		(start 189.5 148.5)
		(end 190 148)
		(width 0.256)
		(layer "B.Cu")
		(net 553)
	)
	(segment
		(start 192.5 157.502)
		(end 193 158.002)
		(width 0.256)
		(layer "B.Cu")
		(net 553)
	)
	(segment
		(start 195 154)
		(end 194.002 154)
		(width 0.201)
		(layer "B.Cu")
		(net 553)
	)
	(segment
		(start 186 158.001999)
		(end 186 158)
		(width 0.256)
		(layer "B.Cu")
		(net 553)
	)
	(segment
		(start 189.5 150.5)
		(end 189.502 150.5)
		(width 0.256)
		(layer "B.Cu")
		(net 553)
	)
	(segment
		(start 193.5 153.5)
		(end 193.5 153.502)
		(width 0.256)
		(layer "B.Cu")
		(net 553)
	)
	(segment
		(start 191.5 157.498)
		(end 192 156.998)
		(width 0.256)
		(layer "B.Cu")
		(net 553)
	)
	(segment
		(start 184.5 155.5)
		(end 184.5 155.502001)
		(width 0.256)
		(layer "B.Cu")
		(net 553)
	)
	(segment
		(start 186 148.002)
		(end 186.002 148.002)
		(width 0.256)
		(layer "B.Cu")
		(net 553)
	)
	(segment
		(start 192.5 151.5)
		(end 192 151)
		(width 0.256)
		(layer "B.Cu")
		(net 553)
	)
	(segment
		(start 192.501999 156.5)
		(end 193 156.001999)
		(width 0.256)
		(layer "B.Cu")
		(net 553)
	)
	(segment
		(start 188.150001 150.15)
		(end 188.5 150.15)
		(width 0.4)
		(layer "B.Cu")
		(net 553)
	)
	(segment
		(start 185.5 156.5)
		(end 186 156)
		(width 0.256)
		(layer "B.Cu")
		(net 553)
	)
	(segment
		(start 186.002 150.002)
		(end 186.5 150.5)
		(width 0.256)
		(layer "B.Cu")
		(net 553)
	)
	(segment
		(start 191.498 150.5)
		(end 191 150.002)
		(width 0.256)
		(layer "B.Cu")
		(net 553)
	)
	(segment
		(start 191.002 148.998)
		(end 191.5 148.5)
		(width 0.256)
		(layer "B.Cu")
		(net 553)
	)
	(segment
		(start 191 156.998)
		(end 190.998 156.998)
		(width 0.256)
		(layer "B.Cu")
		(net 553)
	)
	(segment
		(start 189.499999 155.5)
		(end 189.499999 155.502)
		(width 0.256)
		(layer "B.Cu")
		(net 553)
	)
	(segment
		(start 186.002 148.002)
		(end 186.5 148.5)
		(width 0.256)
		(layer "B.Cu")
		(net 553)
	)
	(segment
		(start 186.002 150.003999)
		(end 186.002 150.002)
		(width 0.256)
		(layer "B.Cu")
		(net 553)
	)
	(segment
		(start 185.502001 154.5)
		(end 186 154.002001)
		(width 0.256)
		(layer "B.Cu")
		(net 553)
	)
	(segment
		(start 185.5 154.5)
		(end 185.502001 154.5)
		(width 0.256)
		(layer "B.Cu")
		(net 553)
	)
	(segment
		(start 190.5 157.5)
		(end 190.5 157.502)
		(width 0.256)
		(layer "B.Cu")
		(net 553)
	)
	(segment
		(start 187 158.000001)
		(end 187.500001 157.5)
		(width 0.256)
		(layer "B.Cu")
		(net 553)
	)
	(segment
		(start 192 154.998)
		(end 192.002 154.998)
		(width 0.256)
		(layer "B.Cu")
		(net 553)
	)
	(segment
		(start 190.502 154.5)
		(end 191 154.002)
		(width 0.256)
		(layer "B.Cu")
		(net 553)
	)
	(segment
		(start 184.5 155.502001)
		(end 184.002001 156)
		(width 0.256)
		(layer "B.Cu")
		(net 553)
	)
	(segment
		(start 192.5 156.5)
		(end 192.501999 156.5)
		(width 0.256)
		(layer "B.Cu")
		(net 553)
	)
	(segment
		(start 190.5 149.502)
		(end 191 150.002)
		(width 0.256)
		(layer "B.Cu")
		(net 553)
	)
	(segment
		(start 193 148.998)
		(end 193 149)
		(width 0.256)
		(layer "B.Cu")
		(net 553)
	)
	(segment
		(start 189.15 150.15)
		(end 189.5 150.5)
		(width 0.4)
		(layer "B.Cu")
		(net 553)
	)
	(segment
		(start 185 148.998)
		(end 184.998 148.998)
		(width 0.256)
		(layer "B.Cu")
		(net 553)
	)
	(segment
		(start 186.5 155.497999)
		(end 187 154.997999)
		(width 0.256)
		(layer "B.Cu")
		(net 553)
	)
	(segment
		(start 184.5 155.497999)
		(end 185 154.997999)
		(width 0.256)
		(layer "B.Cu")
		(net 553)
	)
	(segment
		(start 186 154)
		(end 186.5 153.5)
		(width 0.256)
		(layer "B.Cu")
		(net 553)
	)
	(segment
		(start 187.500001 157.498001)
		(end 187 156.998)
		(width 0.256)
		(layer "B.Cu")
		(net 553)
	)
	(segment
		(start 189.499999 155.5)
		(end 189.499999 155.315027)
		(width 0.4)
		(layer "B.Cu")
		(net 553)
	)
	(segment
		(start 193.5 148.5)
		(end 193.502 148.5)
		(width 0.256)
		(layer "B.Cu")
		(net 553)
	)
	(segment
		(start 184.998 150.998)
		(end 184.5 150.5)
		(width 0.256)
		(layer "B.Cu")
		(net 553)
	)
	(segment
		(start 188.634972 154.45)
		(end 188.5 154.45)
		(width 0.4)
		(layer "B.Cu")
		(net 553)
	)
	(segment
		(start 187.5 154.5)
		(end 188.45 154.5)
		(width 0.256)
		(layer "B.Cu")
		(net 553)
	)
	(segment
		(start 190.5 157.5)
		(end 190.5 157.497999)
		(width 0.256)
		(layer "B.Cu")
		(net 553)
	)
	(segment
		(start 190 158.002)
		(end 190 158)
		(width 0.256)
		(layer "B.Cu")
		(net 553)
	)
	(segment
		(start 191.5 157.500001)
		(end 191.5 157.502)
		(width 0.256)
		(layer "B.Cu")
		(net 553)
	)
	(segment
		(start 186 154.002001)
		(end 186 154)
		(width 0.256)
		(layer "B.Cu")
		(net 553)
	)
	(segment
		(start 193 156.000001)
		(end 193.500001 155.5)
		(width 0.256)
		(layer "B.Cu")
		(net 553)
	)
	(segment
		(start 193 154.998)
		(end 193 154.999999)
		(width 0.256)
		(layer "B.Cu")
		(net 553)
	)
	(segment
		(start 190.5 154.5)
		(end 190.502 154.5)
		(width 0.256)
		(layer "B.Cu")
		(net 553)
	)
	(segment
		(start 184.498 148.5)
		(end 184 148.002)
		(width 0.256)
		(layer "B.Cu")
		(net 553)
	)
	(segment
		(start 187 158.002)
		(end 187 158.000001)
		(width 0.256)
		(layer "B.Cu")
		(net 553)
	)
	(segment
		(start 192.002 154.998)
		(end 192.5 154.5)
		(width 0.256)
		(layer "B.Cu")
		(net 553)
	)
	(segment
		(start 187 156.998)
		(end 187.002 156.998)
		(width 0.256)
		(layer "B.Cu")
		(net 553)
	)
	(segment
		(start 184.5 148.5)
		(end 184.498 148.5)
		(width 0.256)
		(layer "B.Cu")
		(net 553)
	)
	(segment
		(start 191 157.000001)
		(end 191.5 157.500001)
		(width 0.256)
		(layer "B.Cu")
		(net 553)
	)
	(segment
		(start 190.998 156.998)
		(end 190.5 156.5)
		(width 0.256)
		(layer "B.Cu")
		(net 553)
	)
	(segment
		(start 190.498 154.5)
		(end 190 154.998)
		(width 0.256)
		(layer "B.Cu")
		(net 553)
	)
	(segment
		(start 188.45 154.5)
		(end 188.5 154.45)
		(width 0.256)
		(layer "B.Cu")
		(net 553)
	)
	(segment
		(start 185.5 157.5)
		(end 185.5 157.501999)
		(width 0.256)
		(layer "B.Cu")
		(net 553)
	)
	(segment
		(start 185 148.998)
		(end 185 149)
		(width 0.256)
		(layer "B.Cu")
		(net 553)
	)
	(segment
		(start 190.5 157.502)
		(end 191 158.002)
		(width 0.256)
		(layer "B.Cu")
		(net 553)
	)
	(segment
		(start 190.5 157.502)
		(end 190 158.002)
		(width 0.256)
		(layer "B.Cu")
		(net 553)
	)
	(segment
		(start 194.002 154)
		(end 194 154.002)
		(width 0.201)
		(layer "B.Cu")
		(net 553)
	)
	(segment
		(start 184.002 150.002)
		(end 184.5 150.5)
		(width 0.256)
		(layer "B.Cu")
		(net 553)
	)
	(segment
		(start 193.002 148.998)
		(end 193.5 148.5)
		(width 0.256)
		(layer "B.Cu")
		(net 553)
	)
	(segment
		(start 184.998 148.998)
		(end 184.5 148.5)
		(width 0.256)
		(layer "B.Cu")
		(net 553)
	)
	(segment
		(start 185 158)
		(end 185.5 157.5)
		(width 0.256)
		(layer "B.Cu")
		(net 553)
	)
	(segment
		(start 190.5 154.5)
		(end 190.498 154.5)
		(width 0.256)
		(layer "B.Cu")
		(net 553)
	)
	(segment
		(start 190 154.999999)
		(end 189.499999 155.5)
		(width 0.256)
		(layer "B.Cu")
		(net 553)
	)
	(segment
		(start 185.5 157.501999)
		(end 186 158.001999)
		(width 0.256)
		(layer "B.Cu")
		(net 553)
	)
	(segment
		(start 192.5 157.5)
		(end 192.5 157.502)
		(width 0.256)
		(layer "B.Cu")
		(net 553)
	)
	(segment
		(start 193 149)
		(end 192.5 149.5)
		(width 0.256)
		(layer "B.Cu")
		(net 553)
	)
	(segment
		(start 186.002 150.002)
		(end 185.5 149.5)
		(width 0.256)
		(layer "B.Cu")
		(net 553)
	)
	(segment
		(start 186.5 155.5)
		(end 186.5 155.497999)
		(width 0.256)
		(layer "B.Cu")
		(net 553)
	)
	(segment
		(start 193 158.002)
		(end 193 158)
		(width 0.256)
		(layer "B.Cu")
		(net 553)
	)
	(segment
		(start 184.996 157)
		(end 185 157)
		(width 0.256)
		(layer "B.Cu")
		(net 553)
	)
	(segment
		(start 186 156)
		(end 186.5 155.5)
		(width 0.256)
		(layer "B.Cu")
		(net 553)
	)
	(segment
		(start 192.002 156.998)
		(end 192.5 156.5)
		(width 0.256)
		(layer "B.Cu")
		(net 553)
	)
	(segment
		(start 192.5 149.502)
		(end 193 150.002)
		(width 0.256)
		(layer "B.Cu")
		(net 553)
	)
	(segment
		(start 193 154.998)
		(end 192.998 154.998)
		(width 0.256)
		(layer "B.Cu")
		(net 553)
	)
	(segment
		(start 191 156.998)
		(end 191 157.000001)
		(width 0.256)
		(layer "B.Cu")
		(net 553)
	)
	(segment
		(start 192 158.002)
		(end 192 158)
		(width 0.256)
		(layer "B.Cu")
		(net 553)
	)
	(segment
		(start 186.5 157.5)
		(end 186.5 157.502)
		(width 0.256)
		(layer "B.Cu")
		(net 553)
	)
	(segment
		(start 190.497999 156.5)
		(end 190 156.002001)
		(width 0.256)
		(layer "B.Cu")
		(net 553)
	)
	(segment
		(start 185.497999 154.5)
		(end 185 154.997999)
		(width 0.256)
		(layer "B.Cu")
		(net 553)
	)
	(segment
		(start 191.5 150.5)
		(end 192 151)
		(width 0.256)
		(layer "B.Cu")
		(net 553)
	)
	(segment
		(start 184.5 153.5)
		(end 184.5 153.502001)
		(width 0.256)
		(layer "B.Cu")
		(net 553)
	)
	(segment
		(start 190.5 149.5)
		(end 190.5 149.502)
		(width 0.256)
		(layer "B.Cu")
		(net 553)
	)
	(segment
		(start 185 157)
		(end 185.5 156.5)
		(width 0.256)
		(layer "B.Cu")
		(net 553)
	)
	(segment
		(start 193 156.001999)
		(end 193 156.000001)
		(width 0.256)
		(layer "B.Cu")
		(net 553)
	)
	(segment
		(start 190.5 149.5)
		(end 190.5 149.498)
		(width 0.256)
		(layer "B.Cu")
		(net 553)
	)
	(segment
		(start 187.002001 154.997999)
		(end 187.5 154.5)
		(width 0.256)
		(layer "B.Cu")
		(net 553)
	)
	(segment
		(start 192 156.998)
		(end 192 157)
		(width 0.256)
		(layer "B.Cu")
		(net 553)
	)
	(segment
		(start 191 148.998)
		(end 191.002 148.998)
		(width 0.256)
		(layer "B.Cu")
		(net 553)
	)
	(segment
		(start 193.498 150.5)
		(end 193 150.002)
		(width 0.256)
		(layer "B.Cu")
		(net 553)
	)
	(segment
		(start 190.5 157.497999)
		(end 191 156.997999)
		(width 0.256)
		(layer "B.Cu")
		(net 553)
	)
	(segment
		(start 191.5 155.5)
		(end 191.5 155.498)
		(width 0.256)
		(layer "B.Cu")
		(net 553)
	)
	(segment
		(start 193 154.999999)
		(end 193.500001 155.5)
		(width 0.256)
		(layer "B.Cu")
		(net 553)
	)
	(segment
		(start 190 154.998)
		(end 190 154.999999)
		(width 0.256)
		(layer "B.Cu")
		(net 553)
	)
	(segment
		(start 185.496 157.5)
		(end 184.996 157)
		(width 0.256)
		(layer "B.Cu")
		(net 553)
	)
	(segment
		(start 187 148.997999)
		(end 187 148.999999)
		(width 0.256)
		(layer "B.Cu")
		(net 553)
	)
	(segment
		(start 187 154.997999)
		(end 187.002001 154.997999)
		(width 0.256)
		(layer "B.Cu")
		(net 553)
	)
	(segment
		(start 190.5 156.5)
		(end 190.497999 156.5)
		(width 0.256)
		(layer "B.Cu")
		(net 553)
	)
	(segment
		(start 187 148.997999)
		(end 186.997999 148.997999)
		(width 0.256)
		(layer "B.Cu")
		(net 553)
	)
	(segment
		(start 185.5 157.5)
		(end 185.496 157.5)
		(width 0.256)
		(layer "B.Cu")
		(net 553)
	)
	(segment
		(start 184.5 155.5)
		(end 184.5 155.497999)
		(width 0.256)
		(layer "B.Cu")
		(net 553)
	)
	(segment
		(start 185.5 154.5)
		(end 185.497999 154.5)
		(width 0.256)
		(layer "B.Cu")
		(net 553)
	)
	(segment
		(start 184.5 153.502001)
		(end 184 154.002001)
		(width 0.256)
		(layer "B.Cu")
		(net 553)
	)
	(segment
		(start 191 158.002)
		(end 191 158.000001)
		(width 0.256)
		(layer "B.Cu")
		(net 553)
	)
	(segment
		(start 192.5 149.5)
		(end 192.5 149.502)
		(width 0.256)
		(layer "B.Cu")
		(net 553)
	)
	(segment
		(start 184 150.002)
		(end 184.002 150.002)
		(width 0.256)
		(layer "B.Cu")
		(net 553)
	)
	(segment
		(start 185 149)
		(end 185.5 149.5)
		(width 0.256)
		(layer "B.Cu")
		(net 553)
	)
	(segment
		(start 187.500001 149.5)
		(end 188.150001 150.15)
		(width 0.4)
		(layer "B.Cu")
		(net 553)
	)
	(segment
		(start 185 158.002)
		(end 185 158)
		(width 0.256)
		(layer "B.Cu")
		(net 553)
	)
	(segment
		(start 189.502 150.5)
		(end 190 150.998)
		(width 0.256)
		(layer "B.Cu")
		(net 553)
	)
	(segment
		(start 222.135 176.534)
		(end 222.135 176.26)
		(width 0.15)
		(layer "B.Cu")
		(net 553)
	)
	(segment
		(start 189.499999 155.502)
		(end 190 156.002001)
		(width 0.256)
		(layer "B.Cu")
		(net 553)
	)
	(segment
		(start 191 158.000001)
		(end 191.5 157.500001)
		(width 0.256)
		(layer "B.Cu")
		(net 553)
	)
	(segment
		(start 186.5 157.502)
		(end 187 158.002)
		(width 0.256)
		(layer "B.Cu")
		(net 553)
	)
	(segment
		(start 193 158)
		(end 193.5 157.5)
		(width 0.256)
		(layer "B.Cu")
		(net 553)
	)
	(segment
		(start 185 150.998)
		(end 184.998 150.998)
		(width 0.256)
		(layer "B.Cu")
		(net 553)
	)
	(segment
		(start 192.998 154.998)
		(end 192.5 154.5)
		(width 0.256)
		(layer "B.Cu")
		(net 553)
	)
	(segment
		(start 192 156.998)
		(end 192.002 156.998)
		(width 0.256)
		(layer "B.Cu")
		(net 553)
	)
	(segment
		(start 185.499999 151.5)
		(end 185.799999 151.5)
		(width 0.1)
		(layer "In2.Cu")
		(net 553)
	)
	(segment
		(start 185.899999 152.017159)
		(end 185.467158 152.45)
		(width 0.1)
		(layer "In2.Cu")
		(net 553)
	)
	(segment
		(start 185.467158 152.45)
		(end 184.736827 152.45)
		(width 0.1)
		(layer "In2.Cu")
		(net 553)
	)
	(segment
		(start 186.7 158.1)
		(end 186.9 158.3)
		(width 0.1)
		(layer "In2.Cu")
		(net 553)
	)
	(segment
		(start 183.9 153.286826)
		(end 183.9 157.713173)
		(width 0.1)
		(layer "In2.Cu")
		(net 553)
	)
	(segment
		(start 186.9 158.3)
		(end 186.9 176.832843)
		(width 0.1)
		(layer "In2.Cu")
		(net 553)
	)
	(segment
		(start 183.9 157.713173)
		(end 184.286826 158.1)
		(width 0.1)
		(layer "In2.Cu")
		(net 553)
	)
	(segment
		(start 186.9 176.832843)
		(end 192.417158 182.35)
		(width 0.1)
		(layer "In2.Cu")
		(net 553)
	)
	(segment
		(start 192.417158 182.35)
		(end 205.782843 182.35)
		(width 0.1)
		(layer "In2.Cu")
		(net 553)
	)
	(segment
		(start 184.286826 158.1)
		(end 186.7 158.1)
		(width 0.1)
		(layer "In2.Cu")
		(net 553)
	)
	(segment
		(start 185.799999 151.5)
		(end 185.899999 151.6)
		(width 0.1)
		(layer "In2.Cu")
		(net 553)
	)
	(segment
		(start 185.899999 151.6)
		(end 185.899999 152.017159)
		(width 0.1)
		(layer "In2.Cu")
		(net 553)
	)
	(segment
		(start 210.457843 177.675)
		(end 221.7 177.675)
		(width 0.1)
		(layer "In2.Cu")
		(net 553)
	)
	(segment
		(start 221.7 177.675)
		(end 222 177.375)
		(width 0.1)
		(layer "In2.Cu")
		(net 553)
	)
	(segment
		(start 222 177.375)
		(end 222 176.395)
		(width 0.1)
		(layer "In2.Cu")
		(net 553)
	)
	(segment
		(start 184.736827 152.45)
		(end 183.9 153.286826)
		(width 0.1)
		(layer "In2.Cu")
		(net 553)
	)
	(segment
		(start 205.782843 182.35)
		(end 210.457843 177.675)
		(width 0.1)
		(layer "In2.Cu")
		(net 553)
	)
	(segment
		(start 222 176.395)
		(end 222.285 176.11)
		(width 0.1)
		(layer "In2.Cu")
		(net 553)
	)
	(segment
		(start 126.076 184.778)
		(end 126.076 187.162)
		(width 0.201)
		(layer "F.Cu")
		(net 554)
	)
	(segment
		(start 182.9995 153.000501)
		(end 182.5 153.5)
		(width 0.256)
		(layer "F.Cu")
		(net 554)
	)
	(segment
		(start 126.076 187.162)
		(end 127.106 188.192)
		(width 0.201)
		(layer "F.Cu")
		(net 554)
	)
	(via
		(at 182.5 153.5)
		(size 0.45)
		(drill 0.1)
		(layers "F.Cu" "B.Cu")
		(remove_unused_layers yes)
		(keep_end_layers yes)
		(zone_layer_connections)
		(net 554)
	)
	(via
		(at 127.106 188.192)
		(size 0.45)
		(drill 0.1)
		(layers "F.Cu" "B.Cu")
		(remove_unused_layers yes)
		(keep_end_layers yes)
		(zone_layer_connections)
		(net 554)
	)
	(segment
		(start 126.4 187.94)
		(end 126.854 187.94)
		(width 0.201)
		(layer "B.Cu")
		(net 554)
	)
	(segment
		(start 126.854 187.94)
		(end 127.106 188.192)
		(width 0.201)
		(layer "B.Cu")
		(net 554)
	)
	(segment
		(start 180.7 163)
		(end 174.5 163)
		(width 0.1)
		(layer "In9.Cu")
		(net 554)
	)
	(segment
		(start 174.5 163)
		(end 168.5 169)
		(width 0.1)
		(layer "In9.Cu")
		(net 554)
	)
	(segment
		(start 182.5 153.5)
		(end 182.875001 153.124999)
		(width 0.1)
		(layer "In9.Cu")
		(net 554)
	)
	(segment
		(start 181 157.469669)
		(end 181 162.7)
		(width 0.1)
		(layer "In9.Cu")
		(net 554)
	)
	(segment
		(start 181.344669 157.125)
		(end 181 157.469669)
		(width 0.1)
		(layer "In9.Cu")
		(net 554)
	)
	(segment
		(start 184.1 153.569668)
		(end 184.1 156.430331)
		(width 0.1)
		(layer "In9.Cu")
		(net 554)
	)
	(segment
		(start 184.1 156.430331)
		(end 183.40533 157.125001)
		(width 0.1)
		(layer "In9.Cu")
		(net 554)
	)
	(segment
		(start 183.655331 153.124999)
		(end 184.1 153.569668)
		(width 0.1)
		(layer "In9.Cu")
		(net 554)
	)
	(segment
		(start 182.875001 153.124999)
		(end 183.655331 153.124999)
		(width 0.1)
		(layer "In9.Cu")
		(net 554)
	)
	(segment
		(start 141.30383 177)
		(end 130.21033 188.0935)
		(width 0.1)
		(layer "In9.Cu")
		(net 554)
	)
	(segment
		(start 157.5 177)
		(end 141.30383 177)
		(width 0.1)
		(layer "In9.Cu")
		(net 554)
	)
	(segment
		(start 183.40533 157.125001)
		(end 181.344669 157.125)
		(width 0.1)
		(layer "In9.Cu")
		(net 554)
	)
	(segment
		(start 168.5 169)
		(end 165.5 169)
		(width 0.1)
		(layer "In9.Cu")
		(net 554)
	)
	(segment
		(start 130.21033 188.0935)
		(end 127.106 188.0935)
		(width 0.1)
		(layer "In9.Cu")
		(net 554)
	)
	(segment
		(start 181 162.7)
		(end 180.7 163)
		(width 0.1)
		(layer "In9.Cu")
		(net 554)
	)
	(segment
		(start 165.5 169)
		(end 157.5 177)
		(width 0.1)
		(layer "In9.Cu")
		(net 554)
	)
	(segment
		(start 183.9995 154.0005)
		(end 183.5 154.5)
		(width 0.256)
		(layer "F.Cu")
		(net 555)
	)
	(via
		(at 183.5 154.5)
		(size 0.45)
		(drill 0.1)
		(layers "F.Cu" "B.Cu")
		(remove_unused_layers yes)
		(keep_end_layers yes)
		(zone_layer_connections)
		(net 555)
	)
	(via
		(at 120.2 168.575)
		(size 0.45)
		(drill 0.1)
		(layers "F.Cu" "B.Cu")
		(remove_unused_layers yes)
		(keep_end_layers yes)
		(zone_layer_connections)
		(net 555)
	)
	(segment
		(start 119.45 168.575)
		(end 118.7 167.825)
		(width 0.15)
		(layer "B.Cu")
		(net 555)
	)
	(segment
		(start 120.2 168.575)
		(end 119.45 168.575)
		(width 0.15)
		(layer "B.Cu")
		(net 555)
	)
	(segment
		(start 118.7 167.825)
		(end 118.7 167.22)
		(width 0.15)
		(layer "B.Cu")
		(net 555)
	)
	(segment
		(start 171.15 152.125)
		(end 167.375 155.9)
		(width 0.1)
		(layer "In9.Cu")
		(net 555)
	)
	(segment
		(start 180 153.8)
		(end 180 153.125)
		(width 0.1)
		(layer "In9.Cu")
		(net 555)
	)
	(segment
		(start 153.131447 154.698553)
		(end 150.973 156.857)
		(width 0.1)
		(layer "In9.Cu")
		(net 555)
	)
	(segment
		(start 183.5 154.5)
		(end 183.1 154.1)
		(width 0.1)
		(layer "In9.Cu")
		(net 555)
	)
	(segment
		(start 144.644669 156.857)
		(end 144.562669 156.775)
		(width 0.1)
		(layer "In9.Cu")
		(net 555)
	)
	(segment
		(start 120.55 168.225)
		(end 120.2 168.575)
		(width 0.1)
		(layer "In9.Cu")
		(net 555)
	)
	(segment
		(start 136 160.9)
		(end 127.7 169.2)
		(width 0.1)
		(layer "In9.Cu")
		(net 555)
	)
	(segment
		(start 162.598553 154.698553)
		(end 153.131447 154.698553)
		(width 0.1)
		(layer "In9.Cu")
		(net 555)
	)
	(segment
		(start 141.725 156.775)
		(end 137.6 160.9)
		(width 0.1)
		(layer "In9.Cu")
		(net 555)
	)
	(segment
		(start 127.7 169.2)
		(end 122.675 169.2)
		(width 0.1)
		(layer "In9.Cu")
		(net 555)
	)
	(segment
		(start 167.375 155.9)
		(end 163.8 155.9)
		(width 0.1)
		(layer "In9.Cu")
		(net 555)
	)
	(segment
		(start 180.3 154.1)
		(end 180 153.8)
		(width 0.1)
		(layer "In9.Cu")
		(net 555)
	)
	(segment
		(start 183.1 154.1)
		(end 180.3 154.1)
		(width 0.1)
		(layer "In9.Cu")
		(net 555)
	)
	(segment
		(start 122.675 169.2)
		(end 121.7 168.225)
		(width 0.1)
		(layer "In9.Cu")
		(net 555)
	)
	(segment
		(start 137.6 160.9)
		(end 136 160.9)
		(width 0.1)
		(layer "In9.Cu")
		(net 555)
	)
	(segment
		(start 150.973 156.857)
		(end 144.644669 156.857)
		(width 0.1)
		(layer "In9.Cu")
		(net 555)
	)
	(segment
		(start 144.562669 156.775)
		(end 141.725 156.775)
		(width 0.1)
		(layer "In9.Cu")
		(net 555)
	)
	(segment
		(start 179 152.125)
		(end 171.15 152.125)
		(width 0.1)
		(layer "In9.Cu")
		(net 555)
	)
	(segment
		(start 121.7 168.225)
		(end 120.55 168.225)
		(width 0.1)
		(layer "In9.Cu")
		(net 555)
	)
	(segment
		(start 180 153.125)
		(end 179 152.125)
		(width 0.1)
		(layer "In9.Cu")
		(net 555)
	)
	(segment
		(start 163.8 155.9)
		(end 162.598553 154.698553)
		(width 0.1)
		(layer "In9.Cu")
		(net 555)
	)
	(segment
		(start 186.9995 141.9995)
		(end 186.5 141.5)
		(width 0.256)
		(layer "F.Cu")
		(net 556)
	)
	(via
		(at 186.5 141.5)
		(size 0.45)
		(drill 0.1)
		(layers "F.Cu" "B.Cu")
		(remove_unused_layers yes)
		(keep_end_layers yes)
		(zone_layer_connections)
		(net 556)
	)
	(segment
		(start 201.4995 159.4995)
		(end 201 159)
		(width 0.256)
		(layer "F.Cu")
		(net 557)
	)
	(via
		(at 201.4995 159.4995)
		(size 0.45)
		(drill 0.1)
		(layers "F.Cu" "B.Cu")
		(remove_unused_layers yes)
		(keep_end_layers yes)
		(zone_layer_connections)
		(net 557)
	)
	(segment
		(start 202.386982 166.937233)
		(end 202.463554 167.013805)
		(width 0.22)
		(layer "B.Cu")
		(net 557)
	)
	(segment
		(start 202.17071 165.649851)
		(end 202.129236 165.691325)
		(width 0.1)
		(layer "B.Cu")
		(net 557)
	)
	(segment
		(start 201.47021 159.82879)
		(end 201.428789 159.870211)
		(width 0.1)
		(layer "B.Cu")
		(net 557)
	)
	(segment
		(start 201.099499 159.958079)
		(end 200.958078 160.0995)
		(width 0.1)
		(layer "B.Cu")
		(net 557)
	)
	(segment
		(start 193.89892 192.472079)
		(end 193.622499 192.7485)
		(width 0.22)
		(layer "B.Cu")
		(net 557)
	)
	(segment
		(start 200.8995 160.240921)
		(end 200.8995 163.916658)
		(width 0.1)
		(layer "B.Cu")
		(net 557)
	)
	(segment
		(start 202.129236 165.691325)
		(end 202.129236 166.314979)
		(width 0.22)
		(layer "B.Cu")
		(net 557)
	)
	(segment
		(start 201.358079 159.8995)
		(end 201.240921 159.8995)
		(width 0.1)
		(layer "B.Cu")
		(net 557)
	)
	(segment
		(start 201.4995 159.4995)
		(end 201.4995 159.758079)
		(width 0.1)
		(layer "B.Cu")
		(net 557)
	)
	(segment
		(start 201.145534 182.760764)
		(end 194.508138 189.39816)
		(width 0.22)
		(layer "B.Cu")
		(net 557)
	)
	(segment
		(start 202.61 167.367358)
		(end 202.61 179.22523)
		(width 0.22)
		(layer "B.Cu")
		(net 557)
	)
	(segment
		(start 202.2 165.382843)
		(end 202.2 165.57914)
		(width 0.1)
		(layer "B.Cu")
		(net 557)
	)
	(segment
		(start 200.987368 164.12879)
		(end 202.170711 165.312133)
		(width 0.1)
		(layer "B.Cu")
		(net 557)
	)
	(segment
		(start 193.957499 190.72752)
		(end 193.957499 192.330657)
		(width 0.22)
		(layer "B.Cu")
		(net 557)
	)
	(arc
		(start 202.386982 166.937233)
		(mid 202.196222 166.65174)
		(end 202.129236 166.314979)
		(width 0.22)
		(layer "B.Cu")
		(net 557)
	)
	(arc
		(start 202.61 167.367358)
		(mid 202.57194 167.176017)
		(end 202.463554 167.013805)
		(width 0.22)
		(layer "B.Cu")
		(net 557)
	)
	(arc
		(start 200.8995 163.916658)
		(mid 200.922336 164.031463)
		(end 200.987368 164.12879)
		(width 0.1)
		(layer "B.Cu")
		(net 557)
	)
	(arc
		(start 194.508138 189.39816)
		(mid 194.100606 190.008076)
		(end 193.957499 190.72752)
		(width 0.22)
		(layer "B.Cu")
		(net 557)
	)
	(arc
		(start 200.958078 160.0995)
		(mid 200.914724 160.164385)
		(end 200.8995 160.240921)
		(width 0.1)
		(layer "B.Cu")
		(net 557)
	)
	(arc
		(start 201.4995 159.758079)
		(mid 201.491888 159.796348)
		(end 201.47021 159.82879)
		(width 0.1)
		(layer "B.Cu")
		(net 557)
	)
	(arc
		(start 201.145534 182.760764)
		(mid 202.229398 181.138647)
		(end 202.61 179.22523)
		(width 0.22)
		(layer "B.Cu")
		(net 557)
	)
	(arc
		(start 201.428789 159.870211)
		(mid 201.396347 159.891888)
		(end 201.358079 159.8995)
		(width 0.1)
		(layer "B.Cu")
		(net 557)
	)
	(arc
		(start 202.2 165.382843)
		(mid 202.192388 165.344575)
		(end 202.170711 165.312133)
		(width 0.1)
		(layer "B.Cu")
		(net 557)
	)
	(arc
		(start 201.240921 159.8995)
		(mid 201.164384 159.914724)
		(end 201.099499 159.958079)
		(width 0.1)
		(layer "B.Cu")
		(net 557)
	)
	(arc
		(start 193.89892 192.472079)
		(mid 193.942275 192.407194)
		(end 193.957499 192.330657)
		(width 0.22)
		(layer "B.Cu")
		(net 557)
	)
	(arc
		(start 202.2 165.57914)
		(mid 202.192388 165.617409)
		(end 202.17071 165.649851)
		(width 0.1)
		(layer "B.Cu")
		(net 557)
	)
	(segment
		(start 201 160)
		(end 201.4995 160.4995)
		(width 0.256)
		(layer "F.Cu")
		(net 558)
	)
	(via
		(at 201.4995 160.4995)
		(size 0.45)
		(drill 0.1)
		(layers "F.Cu" "B.Cu")
		(remove_unused_layers yes)
		(keep_end_layers yes)
		(zone_layer_connections)
		(net 558)
	)
	(segment
		(start 201.128789 160.211633)
		(end 201.211632 160.12879)
		(width 0.1)
		(layer "B.Cu")
		(net 558)
	)
	(segment
		(start 194.6485 192.7485)
		(end 194.672499 192.7485)
		(width 0.22)
		(layer "B.Cu")
		(net 558)
	)
	(segment
		(start 201.362151 160.98735)
		(end 201.362151 160.95)
		(width 0.1)
		(layer "B.Cu")
		(net 558)
	)
	(segment
		(start 201.0995 163.916657)
		(end 201.0995 161.25)
		(width 0.1)
		(layer "B.Cu")
		(net 558)
	)
	(segment
		(start 201.0995 160.65)
		(end 201.0995 160.282343)
		(width 0.1)
		(layer "B.Cu")
		(net 558)
	)
	(segment
		(start 202.312132 165.17071)
		(end 201.12879 163.987368)
		(width 0.1)
		(layer "B.Cu")
		(net 558)
	)
	(segment
		(start 201.4995 160.240921)
		(end 201.4995 160.4995)
		(width 0.1)
		(layer "B.Cu")
		(net 558)
	)
	(segment
		(start 201.282343 160.0995)
		(end 201.358079 160.0995)
		(width 0.1)
		(layer "B.Cu")
		(net 558)
	)
	(segment
		(start 201.230825 161.118675)
		(end 201.230826 161.118675)
		(width 0.1)
		(layer "B.Cu")
		(net 558)
	)
	(segment
		(start 201.414234 183.029468)
		(end 194.776839 189.666863)
		(width 0.22)
		(layer "B.Cu")
		(net 558)
	)
	(segment
		(start 194.337499 190.727523)
		(end 194.337499 192.354656)
		(width 0.22)
		(layer "B.Cu")
		(net 558)
	)
	(segment
		(start 202.4 165.540668)
		(end 202.4 165.382842)
		(width 0.1)
		(layer "B.Cu")
		(net 558)
	)
	(segment
		(start 202.509236 165.691325)
		(end 202.42929 165.611379)
		(width 0.1)
		(layer "B.Cu")
		(net 558)
	)
	(segment
		(start 202.509236 165.691325)
		(end 202.509236 166.314976)
		(width 0.22)
		(layer "B.Cu")
		(net 558)
	)
	(segment
		(start 202.655683 166.66853)
		(end 202.732254 166.745101)
		(width 0.22)
		(layer "B.Cu")
		(net 558)
	)
	(segment
		(start 194.396078 192.496078)
		(end 194.6485 192.7485)
		(width 0.22)
		(layer "B.Cu")
		(net 558)
	)
	(segment
		(start 202.99 167.367355)
		(end 202.99 179.225233)
		(width 0.22)
		(layer "B.Cu")
		(net 558)
	)
	(segment
		(start 201.230826 160.818675)
		(end 201.230825 160.818675)
		(width 0.1)
		(layer "B.Cu")
		(net 558)
	)
	(segment
		(start 201.428789 160.128789)
		(end 201.47021 160.17021)
		(width 0.1)
		(layer "B.Cu")
		(net 558)
	)
	(segment
		(start 201.0995 160.68735)
		(end 201.0995 160.65)
		(width 0.1)
		(layer "B.Cu")
		(net 558)
	)
	(arc
		(start 201.211632 160.12879)
		(mid 201.244074 160.107112)
		(end 201.282343 160.0995)
		(width 0.1)
		(layer "B.Cu")
		(net 558)
	)
	(arc
		(start 202.509236 166.314976)
		(mid 202.547296 166.506318)
		(end 202.655683 166.66853)
		(width 0.22)
		(layer "B.Cu")
		(net 558)
	)
	(arc
		(start 194.776839 189.666863)
		(mid 194.45168 190.153498)
		(end 194.337499 190.727523)
		(width 0.22)
		(layer "B.Cu")
		(net 558)
	)
	(arc
		(start 201.47021 160.17021)
		(mid 201.491888 160.202652)
		(end 201.4995 160.240921)
		(width 0.1)
		(layer "B.Cu")
		(net 558)
	)
	(arc
		(start 202.99 167.367355)
		(mid 202.923014 167.030594)
		(end 202.732254 166.745101)
		(width 0.22)
		(layer "B.Cu")
		(net 558)
	)
	(arc
		(start 201.362151 160.95)
		(mid 201.323687 160.857139)
		(end 201.230826 160.818675)
		(width 0.1)
		(layer "B.Cu")
		(net 558)
	)
	(arc
		(start 202.42929 165.611379)
		(mid 202.407612 165.578937)
		(end 202.4 165.540668)
		(width 0.1)
		(layer "B.Cu")
		(net 558)
	)
	(arc
		(start 201.0995 160.282343)
		(mid 201.107112 160.244075)
		(end 201.128789 160.211633)
		(width 0.1)
		(layer "B.Cu")
		(net 558)
	)
	(arc
		(start 201.358079 160.0995)
		(mid 201.396347 160.107112)
		(end 201.428789 160.128789)
		(width 0.1)
		(layer "B.Cu")
		(net 558)
	)
	(arc
		(start 202.4 165.382842)
		(mid 202.377164 165.268037)
		(end 202.312132 165.17071)
		(width 0.1)
		(layer "B.Cu")
		(net 558)
	)
	(arc
		(start 202.99 179.225233)
		(mid 202.580472 181.28407)
		(end 201.414234 183.029468)
		(width 0.22)
		(layer "B.Cu")
		(net 558)
	)
	(arc
		(start 201.230825 160.818675)
		(mid 201.137964 160.780211)
		(end 201.0995 160.68735)
		(width 0.1)
		(layer "B.Cu")
		(net 558)
	)
	(arc
		(start 194.396078 192.496078)
		(mid 194.352723 192.431193)
		(end 194.337499 192.354656)
		(width 0.22)
		(layer "B.Cu")
		(net 558)
	)
	(arc
		(start 201.0995 161.25)
		(mid 201.137964 161.157139)
		(end 201.230825 161.118675)
		(width 0.1)
		(layer "B.Cu")
		(net 558)
	)
	(arc
		(start 201.12879 163.987368)
		(mid 201.107112 163.954926)
		(end 201.0995 163.916657)
		(width 0.1)
		(layer "B.Cu")
		(net 558)
	)
	(arc
		(start 201.230826 161.118675)
		(mid 201.323687 161.080211)
		(end 201.362151 160.98735)
		(width 0.1)
		(layer "B.Cu")
		(net 558)
	)
	(segment
		(start 200 157)
		(end 200.4995 157.4995)
		(width 0.256)
		(layer "F.Cu")
		(net 559)
	)
	(via
		(at 200.500001 157.5)
		(size 0.45)
		(drill 0.1)
		(layers "F.Cu" "B.Cu")
		(remove_unused_layers yes)
		(keep_end_layers yes)
		(zone_layer_connections)
		(net 559)
	)
	(segment
		(start 199.958079 158.0995)
		(end 200.0995 157.958079)
		(width 0.1)
		(layer "B.Cu")
		(net 559)
	)
	(segment
		(start 200.59638 166.2)
		(end 200.59638 166.500574)
		(width 0.22)
		(layer "B.Cu")
		(net 559)
	)
	(segment
		(start 199.899501 159.875237)
		(end 199.899501 158.240921)
		(width 0.1)
		(layer "B.Cu")
		(net 559)
	)
	(segment
		(start 200.42879 157.870211)
		(end 200.470211 157.82879)
		(width 0.1)
		(layer "B.Cu")
		(net 559)
	)
	(segment
		(start 199.900001 164.14)
		(end 199.900001 159.875737)
		(width 0.1)
		(layer "B.Cu")
		(net 559)
	)
	(segment
		(start 189.957499 191.15252)
		(end 189.957499 192.330657)
		(width 0.22)
		(layer "B.Cu")
		(net 559)
	)
	(segment
		(start 200.7 166.054959)
		(end 200.7 165.082843)
		(width 0.1)
		(layer "B.Cu")
		(net 559)
	)
	(segment
		(start 201.01 167.485809)
		(end 201.01 177.25023)
		(width 0.22)
		(layer "B.Cu")
		(net 559)
	)
	(segment
		(start 200.499501 157.758079)
		(end 200.499501 157.4995)
		(width 0.1)
		(layer "B.Cu")
		(net 559)
	)
	(segment
		(start 200.59638 166.2)
		(end 200.67071 166.12567)
		(width 0.1)
		(layer "B.Cu")
		(net 559)
	)
	(segment
		(start 189.89892 192.472079)
		(end 189.622499 192.7485)
		(width 0.22)
		(layer "B.Cu")
		(net 559)
	)
	(segment
		(start 199.545534 180.785764)
		(end 190.508138 189.82316)
		(width 0.22)
		(layer "B.Cu")
		(net 559)
	)
	(segment
		(start 200.240922 157.8995)
		(end 200.35808 157.8995)
		(width 0.1)
		(layer "B.Cu")
		(net 559)
	)
	(segment
		(start 199.900001 159.875737)
		(end 199.899501 159.875237)
		(width 0.1)
		(layer "B.Cu")
		(net 559)
	)
	(segment
		(start 200.854126 167.122828)
		(end 200.863554 167.132256)
		(width 0.22)
		(layer "B.Cu")
		(net 559)
	)
	(segment
		(start 200.670711 165.012133)
		(end 199.971718 164.31314)
		(width 0.1)
		(layer "B.Cu")
		(net 559)
	)
	(arc
		(start 199.545534 180.785764)
		(mid 200.629398 179.163647)
		(end 201.01 177.25023)
		(width 0.22)
		(layer "B.Cu")
		(net 559)
	)
	(arc
		(start 189.957499 191.15252)
		(mid 190.100605 190.433075)
		(end 190.508138 189.82316)
		(width 0.22)
		(layer "B.Cu")
		(net 559)
	)
	(arc
		(start 200.7 165.082843)
		(mid 200.692388 165.044575)
		(end 200.670711 165.012133)
		(width 0.1)
		(layer "B.Cu")
		(net 559)
	)
	(arc
		(start 200.35808 157.8995)
		(mid 200.396348 157.891888)
		(end 200.42879 157.870211)
		(width 0.1)
		(layer "B.Cu")
		(net 559)
	)
	(arc
		(start 200.470211 157.82879)
		(mid 200.491889 157.796348)
		(end 200.499501 157.758079)
		(width 0.1)
		(layer "B.Cu")
		(net 559)
	)
	(arc
		(start 200.67071 166.12567)
		(mid 200.692388 166.093228)
		(end 200.7 166.054959)
		(width 0.1)
		(layer "B.Cu")
		(net 559)
	)
	(arc
		(start 199.899501 158.240921)
		(mid 199.914725 158.164385)
		(end 199.958079 158.0995)
		(width 0.1)
		(layer "B.Cu")
		(net 559)
	)
	(arc
		(start 200.0995 157.958079)
		(mid 200.164385 157.914724)
		(end 200.240922 157.8995)
		(width 0.1)
		(layer "B.Cu")
		(net 559)
	)
	(arc
		(start 200.854126 167.122828)
		(mid 200.663366 166.837335)
		(end 200.59638 166.500574)
		(width 0.22)
		(layer "B.Cu")
		(net 559)
	)
	(arc
		(start 189.89892 192.472079)
		(mid 189.942275 192.407194)
		(end 189.957499 192.330657)
		(width 0.22)
		(layer "B.Cu")
		(net 559)
	)
	(arc
		(start 199.971718 164.31314)
		(mid 199.91864 164.233703)
		(end 199.900001 164.14)
		(width 0.1)
		(layer "B.Cu")
		(net 559)
	)
	(arc
		(start 201.01 167.485809)
		(mid 200.97194 167.294468)
		(end 200.863554 167.132256)
		(width 0.22)
		(layer "B.Cu")
		(net 559)
	)
	(segment
		(start 191.0005 160.0005)
		(end 191.5 160.5)
		(width 0.256)
		(layer "F.Cu")
		(net 560)
	)
	(via
		(at 191.5 160.5)
		(size 0.45)
		(drill 0.1)
		(layers "F.Cu" "B.Cu")
		(remove_unused_layers yes)
		(keep_end_layers yes)
		(zone_layer_connections)
		(net 560)
	)
	(segment
		(start 191.0005 159.0005)
		(end 191.5 159.5)
		(width 0.256)
		(layer "F.Cu")
		(net 561)
	)
	(via
		(at 191.5 159.5)
		(size 0.45)
		(drill 0.1)
		(layers "F.Cu" "B.Cu")
		(remove_unused_layers yes)
		(keep_end_layers yes)
		(zone_layer_connections)
		(net 561)
	)
	(segment
		(start 200 158)
		(end 200.499501 158.4995)
		(width 0.256)
		(layer "F.Cu")
		(net 562)
	)
	(via
		(at 200.499501 158.4995)
		(size 0.45)
		(drill 0.1)
		(layers "F.Cu" "B.Cu")
		(remove_unused_layers yes)
		(keep_end_layers yes)
		(zone_layer_connections)
		(net 562)
	)
	(segment
		(start 200.099501 158.282343)
		(end 200.099501 158.693675)
		(width 0.1)
		(layer "B.Cu")
		(net 562)
	)
	(segment
		(start 200.470211 158.17021)
		(end 200.42879 158.128789)
		(width 0.1)
		(layer "B.Cu")
		(net 562)
	)
	(segment
		(start 200.97638 166.2)
		(end 200.92929 166.15291)
		(width 0.1)
		(layer "B.Cu")
		(net 562)
	)
	(segment
		(start 200.499501 158.4995)
		(end 200.499501 158.240921)
		(width 0.1)
		(layer "B.Cu")
		(net 562)
	)
	(segment
		(start 200.100001 164.117158)
		(end 200.099501 164.116658)
		(width 0.1)
		(layer "B.Cu")
		(net 562)
	)
	(segment
		(start 200.230826 159.125)
		(end 200.243675 159.125)
		(width 0.1)
		(layer "B.Cu")
		(net 562)
	)
	(segment
		(start 190.6485 192.7485)
		(end 190.672499 192.7485)
		(width 0.22)
		(layer "B.Cu")
		(net 562)
	)
	(segment
		(start 200.9 166.082199)
		(end 200.9 165.082842)
		(width 0.1)
		(layer "B.Cu")
		(net 562)
	)
	(segment
		(start 200.812132 164.87071)
		(end 200.129291 164.187869)
		(width 0.1)
		(layer "B.Cu")
		(net 562)
	)
	(segment
		(start 190.337499 191.152523)
		(end 190.337499 192.354656)
		(width 0.22)
		(layer "B.Cu")
		(net 562)
	)
	(segment
		(start 199.814234 181.054468)
		(end 190.776839 190.091863)
		(width 0.22)
		(layer "B.Cu")
		(net 562)
	)
	(segment
		(start 200.230826 158.825)
		(end 200.243675 158.825)
		(width 0.1)
		(layer "B.Cu")
		(net 562)
	)
	(segment
		(start 200.97638 166.2)
		(end 200.97638 166.500571)
		(width 0.22)
		(layer "B.Cu")
		(net 562)
	)
	(segment
		(start 200.211633 158.12879)
		(end 200.12879 158.211633)
		(width 0.1)
		(layer "B.Cu")
		(net 562)
	)
	(segment
		(start 200.35808 158.0995)
		(end 200.282344 158.0995)
		(width 0.1)
		(layer "B.Cu")
		(net 562)
	)
	(segment
		(start 190.396078 192.496078)
		(end 190.6485 192.7485)
		(width 0.22)
		(layer "B.Cu")
		(net 562)
	)
	(segment
		(start 200.099501 159.256325)
		(end 200.099501 164.116658)
		(width 0.1)
		(layer "B.Cu")
		(net 562)
	)
	(segment
		(start 201.122827 166.854125)
		(end 201.132254 166.863552)
		(width 0.22)
		(layer "B.Cu")
		(net 562)
	)
	(segment
		(start 200.375 158.956325)
		(end 200.375 158.993675)
		(width 0.1)
		(layer "B.Cu")
		(net 562)
	)
	(segment
		(start 201.39 167.485806)
		(end 201.39 177.250233)
		(width 0.22)
		(layer "B.Cu")
		(net 562)
	)
	(arc
		(start 200.230826 159.125)
		(mid 200.137965 159.163464)
		(end 200.099501 159.256325)
		(width 0.1)
		(layer "B.Cu")
		(net 562)
	)
	(arc
		(start 200.282344 158.0995)
		(mid 200.244075 158.107112)
		(end 200.211633 158.12879)
		(width 0.1)
		(layer "B.Cu")
		(net 562)
	)
	(arc
		(start 200.812132 164.87071)
		(mid 200.877164 164.968037)
		(end 200.9 165.082842)
		(width 0.1)
		(layer "B.Cu")
		(net 562)
	)
	(arc
		(start 200.42879 158.128789)
		(mid 200.396348 158.107112)
		(end 200.35808 158.0995)
		(width 0.1)
		(layer "B.Cu")
		(net 562)
	)
	(arc
		(start 200.375 158.993675)
		(mid 200.336536 159.086536)
		(end 200.243675 159.125)
		(width 0.1)
		(layer "B.Cu")
		(net 562)
	)
	(arc
		(start 190.396078 192.496078)
		(mid 190.352723 192.431193)
		(end 190.337499 192.354656)
		(width 0.22)
		(layer "B.Cu")
		(net 562)
	)
	(arc
		(start 200.243675 158.825)
		(mid 200.336536 158.863464)
		(end 200.375 158.956325)
		(width 0.1)
		(layer "B.Cu")
		(net 562)
	)
	(arc
		(start 201.39 167.485806)
		(mid 201.323014 167.149045)
		(end 201.132254 166.863552)
		(width 0.22)
		(layer "B.Cu")
		(net 562)
	)
	(arc
		(start 200.97638 166.500571)
		(mid 201.01444 166.691913)
		(end 201.122827 166.854125)
		(width 0.22)
		(layer "B.Cu")
		(net 562)
	)
	(arc
		(start 200.099501 158.693675)
		(mid 200.137965 158.786536)
		(end 200.230826 158.825)
		(width 0.1)
		(layer "B.Cu")
		(net 562)
	)
	(arc
		(start 190.337499 191.152523)
		(mid 190.45168 190.578498)
		(end 190.776839 190.091863)
		(width 0.22)
		(layer "B.Cu")
		(net 562)
	)
	(arc
		(start 200.92929 166.15291)
		(mid 200.907612 166.120468)
		(end 200.9 166.082199)
		(width 0.1)
		(layer "B.Cu")
		(net 562)
	)
	(arc
		(start 201.39 177.250233)
		(mid 200.980472 179.30907)
		(end 199.814234 181.054468)
		(width 0.22)
		(layer "B.Cu")
		(net 562)
	)
	(arc
		(start 200.129291 164.187869)
		(mid 200.107613 164.155427)
		(end 200.100001 164.117158)
		(width 0.1)
		(layer "B.Cu")
		(net 562)
	)
	(arc
		(start 200.12879 158.211633)
		(mid 200.107113 158.244075)
		(end 200.099501 158.282343)
		(width 0.1)
		(layer "B.Cu")
		(net 562)
	)
	(arc
		(start 200.499501 158.240921)
		(mid 200.491889 158.202652)
		(end 200.470211 158.17021)
		(width 0.1)
		(layer "B.Cu")
		(net 562)
	)
	(segment
		(start 199 159)
		(end 199.4995 159.4995)
		(width 0.256)
		(layer "F.Cu")
		(net 563)
	)
	(via
		(at 199.4995 159.4995)
		(size 0.45)
		(drill 0.1)
		(layers "F.Cu" "B.Cu")
		(remove_unused_layers yes)
		(keep_end_layers yes)
		(zone_layer_connections)
		(net 563)
	)
	(segment
		(start 199.376903 159.8995)
		(end 199.240921 159.8995)
		(width 0.1)
		(layer "B.Cu")
		(net 563)
	)
	(segment
		(start 199.310147 166.447506)
		(end 199.310147 175.825083)
		(width 0.22)
		(layer "B.Cu")
		(net 563)
	)
	(segment
		(start 199.4995 159.4995)
		(end 199.4995 159.758079)
		(width 0.1)
		(layer "B.Cu")
		(net 563)
	)
	(segment
		(start 185.89892 192.472079)
		(end 185.622499 192.7485)
		(width 0.22)
		(layer "B.Cu")
		(net 563)
	)
	(segment
		(start 199.187868 164.72929)
		(end 199.370711 164.912133)
		(width 0.1)
		(layer "B.Cu")
		(net 563)
	)
	(segment
		(start 199.37071 166.386943)
		(end 199.310147 166.447506)
		(width 0.1)
		(layer "B.Cu")
		(net 563)
	)
	(segment
		(start 197.845681 179.360617)
		(end 186.508138 190.69816)
		(width 0.22)
		(layer "B.Cu")
		(net 563)
	)
	(segment
		(start 199.1 162.324265)
		(end 199.1 164.517158)
		(width 0.1)
		(layer "B.Cu")
		(net 563)
	)
	(segment
		(start 199.099499 159.958079)
		(end 198.958078 160.0995)
		(width 0.1)
		(layer "B.Cu")
		(net 563)
	)
	(segment
		(start 199.47021 159.82879)
		(end 199.415479 159.883521)
		(width 0.1)
		(layer "B.Cu")
		(net 563)
	)
	(segment
		(start 185.957499 192.02752)
		(end 185.957499 192.330657)
		(width 0.22)
		(layer "B.Cu")
		(net 563)
	)
	(segment
		(start 199.016658 162.15808)
		(end 199.041422 162.182844)
		(width 0.1)
		(layer "B.Cu")
		(net 563)
	)
	(segment
		(start 198.8995 160.240921)
		(end 198.8995 161.875237)
		(width 0.1)
		(layer "B.Cu")
		(net 563)
	)
	(segment
		(start 199.4 164.982843)
		(end 199.4 166.316232)
		(width 0.1)
		(layer "B.Cu")
		(net 563)
	)
	(arc
		(start 199.1 162.324265)
		(mid 199.084776 162.247729)
		(end 199.041422 162.182844)
		(width 0.1)
		(layer "B.Cu")
		(net 563)
	)
	(arc
		(start 199.310147 175.825083)
		(mid 198.929545 177.7385)
		(end 197.845681 179.360617)
		(width 0.22)
		(layer "B.Cu")
		(net 563)
	)
	(arc
		(start 199.240921 159.8995)
		(mid 199.164384 159.914724)
		(end 199.099499 159.958079)
		(width 0.1)
		(layer "B.Cu")
		(net 563)
	)
	(arc
		(start 199.370711 164.912133)
		(mid 199.392388 164.944575)
		(end 199.4 164.982843)
		(width 0.1)
		(layer "B.Cu")
		(net 563)
	)
	(arc
		(start 199.376903 159.8995)
		(mid 199.39778 159.895347)
		(end 199.415479 159.883521)
		(width 0.1)
		(layer "B.Cu")
		(net 563)
	)
	(arc
		(start 199.187868 164.72929)
		(mid 199.122836 164.631963)
		(end 199.1 164.517158)
		(width 0.1)
		(layer "B.Cu")
		(net 563)
	)
	(arc
		(start 199.4995 159.758079)
		(mid 199.491888 159.796348)
		(end 199.47021 159.82879)
		(width 0.1)
		(layer "B.Cu")
		(net 563)
	)
	(arc
		(start 198.958078 160.0995)
		(mid 198.914724 160.164385)
		(end 198.8995 160.240921)
		(width 0.1)
		(layer "B.Cu")
		(net 563)
	)
	(arc
		(start 199.37071 166.386943)
		(mid 199.392388 166.354501)
		(end 199.4 166.316232)
		(width 0.1)
		(layer "B.Cu")
		(net 563)
	)
	(arc
		(start 199.016658 162.15808)
		(mid 198.929949 162.028311)
		(end 198.8995 161.875237)
		(width 0.1)
		(layer "B.Cu")
		(net 563)
	)
	(arc
		(start 185.89892 192.472079)
		(mid 185.942275 192.407194)
		(end 185.957499 192.330657)
		(width 0.22)
		(layer "B.Cu")
		(net 563)
	)
	(arc
		(start 185.957499 192.02752)
		(mid 186.100605 191.308075)
		(end 186.508138 190.69816)
		(width 0.22)
		(layer "B.Cu")
		(net 563)
	)
	(segment
		(start 193.0005 160.0005)
		(end 193.500001 160.5)
		(width 0.256)
		(layer "F.Cu")
		(net 564)
	)
	(via
		(at 193.500001 160.5)
		(size 0.45)
		(drill 0.1)
		(layers "F.Cu" "B.Cu")
		(remove_unused_layers yes)
		(keep_end_layers yes)
		(zone_layer_connections)
		(net 564)
	)
	(segment
		(start 193.0005 159.0005)
		(end 193.5 159.500001)
		(width 0.256)
		(layer "F.Cu")
		(net 565)
	)
	(via
		(at 193.5 159.500001)
		(size 0.45)
		(drill 0.1)
		(layers "F.Cu" "B.Cu")
		(remove_unused_layers yes)
		(keep_end_layers yes)
		(zone_layer_connections)
		(net 565)
	)
	(segment
		(start 198 161)
		(end 198.4995 161.4995)
		(width 0.256)
		(layer "F.Cu")
		(net 566)
	)
	(via
		(at 198.4995 161.4995)
		(size 0.45)
		(drill 0.1)
		(layers "F.Cu" "B.Cu")
		(remove_unused_layers yes)
		(keep_end_layers yes)
		(zone_layer_connections)
		(net 566)
	)
	(segment
		(start 198.099499 161.958079)
		(end 197.958078 162.0995)
		(width 0.1)
		(layer "B.Cu")
		(net 566)
	)
	(segment
		(start 198.358079 161.8995)
		(end 198.240921 161.8995)
		(width 0.1)
		(layer "B.Cu")
		(net 566)
	)
	(segment
		(start 198.4995 161.4995)
		(end 198.4995 161.758079)
		(width 0.1)
		(layer "B.Cu")
		(net 566)
	)
	(segment
		(start 197.8995 162.240921)
		(end 197.8995 163.916658)
		(width 0.1)
		(layer "B.Cu")
		(net 566)
	)
	(segment
		(start 198.47021 161.82879)
		(end 198.428789 161.870211)
		(width 0.1)
		(layer "B.Cu")
		(net 566)
	)
	(segment
		(start 198.01 174.22523)
		(end 198.01 164.7)
		(width 0.22)
		(layer "B.Cu")
		(net 566)
	)
	(segment
		(start 197.987368 164.12879)
		(end 198.070711 164.212133)
		(width 0.1)
		(layer "B.Cu")
		(net 566)
	)
	(segment
		(start 198.1 164.282843)
		(end 198.1 164.568579)
		(width 0.1)
		(layer "B.Cu")
		(net 566)
	)
	(segment
		(start 183.26007 190.61)
		(end 183.364927 190.61)
		(width 0.22)
		(layer "B.Cu")
		(net 566)
	)
	(segment
		(start 183.930612 190.375686)
		(end 196.545534 177.760764)
		(width 0.22)
		(layer "B.Cu")
		(net 566)
	)
	(segment
		(start 182.303113 191.078185)
		(end 182.425684 190.955614)
		(width 0.22)
		(layer "B.Cu")
		(net 566)
	)
	(segment
		(start 181.957499 192.330657)
		(end 181.957499 191.912571)
		(width 0.22)
		(layer "B.Cu")
		(net 566)
	)
	(segment
		(start 198.07071 164.63929)
		(end 198.01 164.7)
		(width 0.1)
		(layer "B.Cu")
		(net 566)
	)
	(segment
		(start 181.622499 192.7485)
		(end 181.89892 192.472079)
		(width 0.22)
		(layer "B.Cu")
		(net 566)
	)
	(arc
		(start 198.240921 161.8995)
		(mid 198.164384 161.914724)
		(end 198.099499 161.958079)
		(width 0.1)
		(layer "B.Cu")
		(net 566)
	)
	(arc
		(start 196.545534 177.760764)
		(mid 197.629398 176.138647)
		(end 198.01 174.22523)
		(width 0.22)
		(layer "B.Cu")
		(net 566)
	)
	(arc
		(start 198.070711 164.212133)
		(mid 198.092388 164.244575)
		(end 198.1 164.282843)
		(width 0.1)
		(layer "B.Cu")
		(net 566)
	)
	(arc
		(start 198.428789 161.870211)
		(mid 198.396347 161.891888)
		(end 198.358079 161.8995)
		(width 0.1)
		(layer "B.Cu")
		(net 566)
	)
	(arc
		(start 198.4995 161.758079)
		(mid 198.491888 161.796348)
		(end 198.47021 161.82879)
		(width 0.1)
		(layer "B.Cu")
		(net 566)
	)
	(arc
		(start 197.958078 162.0995)
		(mid 197.914724 162.164385)
		(end 197.8995 162.240921)
		(width 0.1)
		(layer "B.Cu")
		(net 566)
	)
	(arc
		(start 181.957499 191.912571)
		(mid 182.047321 191.461005)
		(end 182.303113 191.078185)
		(width 0.22)
		(layer "B.Cu")
		(net 566)
	)
	(arc
		(start 183.364927 190.61)
		(mid 183.671073 190.549104)
		(end 183.930612 190.375686)
		(width 0.22)
		(layer "B.Cu")
		(net 566)
	)
	(arc
		(start 182.425684 190.955614)
		(mid 182.808504 190.699822)
		(end 183.26007 190.61)
		(width 0.22)
		(layer "B.Cu")
		(net 566)
	)
	(arc
		(start 198.07071 164.63929)
		(mid 198.092388 164.606848)
		(end 198.1 164.568579)
		(width 0.1)
		(layer "B.Cu")
		(net 566)
	)
	(arc
		(start 181.89892 192.472079)
		(mid 181.942275 192.407194)
		(end 181.957499 192.330657)
		(width 0.22)
		(layer "B.Cu")
		(net 566)
	)
	(arc
		(start 197.8995 163.916658)
		(mid 197.922336 164.031463)
		(end 197.987368 164.12879)
		(width 0.1)
		(layer "B.Cu")
		(net 566)
	)
	(segment
		(start 194.0005 149.9995)
		(end 194.5 149.5)
		(width 0.256)
		(layer "F.Cu")
		(net 567)
	)
	(via
		(at 194.5 149.5)
		(size 0.45)
		(drill 0.1)
		(layers "F.Cu" "B.Cu")
		(remove_unused_layers yes)
		(keep_end_layers yes)
		(zone_layer_connections)
		(net 567)
	)
	(segment
		(start 198.4995 162.4995)
		(end 198 162)
		(width 0.256)
		(layer "F.Cu")
		(net 568)
	)
	(via
		(at 198.4995 162.4995)
		(size 0.45)
		(drill 0.1)
		(layers "F.Cu" "B.Cu")
		(remove_unused_layers yes)
		(keep_end_layers yes)
		(zone_layer_connections)
		(net 568)
	)
	(segment
		(start 198.12879 163.987368)
		(end 198.212132 164.07071)
		(width 0.1)
		(layer "B.Cu")
		(net 568)
	)
	(segment
		(start 198.39 174.225233)
		(end 198.39 164.7)
		(width 0.22)
		(layer "B.Cu")
		(net 568)
	)
	(segment
		(start 198.0995 163.434702)
		(end 198.0995 163.916657)
		(width 0.1)
		(layer "B.Cu")
		(net 568)
	)
	(segment
		(start 183.260073 190.99)
		(end 183.36493 190.99)
		(width 0.22)
		(layer "B.Cu")
		(net 568)
	)
	(segment
		(start 198.0995 162.282343)
		(end 198.0995 162.75)
		(width 0.1)
		(layer "B.Cu")
		(net 568)
	)
	(segment
		(start 198.4995 162.4995)
		(end 198.4995 162.299503)
		(width 0.1)
		(layer "B.Cu")
		(net 568)
	)
	(segment
		(start 198.211632 162.12879)
		(end 198.128789 162.211633)
		(width 0.1)
		(layer "B.Cu")
		(net 568)
	)
	(segment
		(start 198.32929 164.63929)
		(end 198.39 164.7)
		(width 0.1)
		(layer "B.Cu")
		(net 568)
	)
	(segment
		(start 198.358079 162.0995)
		(end 198.282343 162.0995)
		(width 0.1)
		(layer "B.Cu")
		(net 568)
	)
	(segment
		(start 182.672499 192.7485)
		(end 182.6485 192.7485)
		(width 0.22)
		(layer "B.Cu")
		(net 568)
	)
	(segment
		(start 182.337499 192.354656)
		(end 182.337499 191.912574)
		(width 0.22)
		(layer "B.Cu")
		(net 568)
	)
	(segment
		(start 184.199316 190.644386)
		(end 196.814234 178.029468)
		(width 0.22)
		(layer "B.Cu")
		(net 568)
	)
	(segment
		(start 182.571813 191.346889)
		(end 182.694387 191.224315)
		(width 0.22)
		(layer "B.Cu")
		(net 568)
	)
	(segment
		(start 182.6485 192.7485)
		(end 182.396078 192.496078)
		(width 0.22)
		(layer "B.Cu")
		(net 568)
	)
	(segment
		(start 198.3 164.282842)
		(end 198.3 164.568579)
		(width 0.1)
		(layer "B.Cu")
		(net 568)
	)
	(segment
		(start 198.0995 163.25)
		(end 198.0995 163.434702)
		(width 0.1)
		(layer "B.Cu")
		(net 568)
	)
	(arc
		(start 196.814234 178.029468)
		(mid 197.980472 176.28407)
		(end 198.39 174.225233)
		(width 0.22)
		(layer "B.Cu")
		(net 568)
	)
	(arc
		(start 198.428789 162.128789)
		(mid 198.396347 162.107112)
		(end 198.358079 162.0995)
		(width 0.1)
		(layer "B.Cu")
		(net 568)
	)
	(arc
		(start 198.3 164.568579)
		(mid 198.307612 164.606848)
		(end 198.32929 164.63929)
		(width 0.1)
		(layer "B.Cu")
		(net 568)
	)
	(arc
		(start 198.0995 162.75)
		(mid 198.136112 162.838388)
		(end 198.2245 162.875)
		(width 0.1)
		(layer "B.Cu")
		(net 568)
	)
	(arc
		(start 183.36493 190.99)
		(mid 183.816496 190.900178)
		(end 184.199316 190.644386)
		(width 0.22)
		(layer "B.Cu")
		(net 568)
	)
	(arc
		(start 198.2245 162.875)
		(mid 198.312888 162.911612)
		(end 198.3495 163)
		(width 0.1)
		(layer "B.Cu")
		(net 568)
	)
	(arc
		(start 198.128789 162.211633)
		(mid 198.107112 162.244075)
		(end 198.0995 162.282343)
		(width 0.1)
		(layer "B.Cu")
		(net 568)
	)
	(arc
		(start 198.4995 162.299503)
		(mid 198.481122 162.207113)
		(end 198.428789 162.128789)
		(width 0.1)
		(layer "B.Cu")
		(net 568)
	)
	(arc
		(start 182.694387 191.224315)
		(mid 182.953926 191.050897)
		(end 183.260073 190.99)
		(width 0.22)
		(layer "B.Cu")
		(net 568)
	)
	(arc
		(start 182.396078 192.496078)
		(mid 182.352723 192.431193)
		(end 182.337499 192.354656)
		(width 0.22)
		(layer "B.Cu")
		(net 568)
	)
	(arc
		(start 198.0995 163.916657)
		(mid 198.107112 163.954926)
		(end 198.12879 163.987368)
		(width 0.1)
		(layer "B.Cu")
		(net 568)
	)
	(arc
		(start 198.282343 162.0995)
		(mid 198.244074 162.107112)
		(end 198.211632 162.12879)
		(width 0.1)
		(layer "B.Cu")
		(net 568)
	)
	(arc
		(start 198.3495 163)
		(mid 198.312888 163.088388)
		(end 198.2245 163.125)
		(width 0.1)
		(layer "B.Cu")
		(net 568)
	)
	(arc
		(start 198.2245 163.125)
		(mid 198.136112 163.161612)
		(end 198.0995 163.25)
		(width 0.1)
		(layer "B.Cu")
		(net 568)
	)
	(arc
		(start 198.212132 164.07071)
		(mid 198.277164 164.168037)
		(end 198.3 164.282842)
		(width 0.1)
		(layer "B.Cu")
		(net 568)
	)
	(arc
		(start 182.337499 191.912574)
		(mid 182.398395 191.606428)
		(end 182.571813 191.346889)
		(width 0.22)
		(layer "B.Cu")
		(net 568)
	)
	(segment
		(start 195.0005 160.0005)
		(end 195.5 160.5)
		(width 0.256)
		(layer "F.Cu")
		(net 569)
	)
	(via
		(at 195.5 160.5)
		(size 0.45)
		(drill 0.1)
		(layers "F.Cu" "B.Cu")
		(remove_unused_layers yes)
		(keep_end_layers yes)
		(zone_layer_connections)
		(net 569)
	)
	(segment
		(start 195.0005 159.0005)
		(end 195.5 159.5)
		(width 0.256)
		(layer "F.Cu")
		(net 570)
	)
	(via
		(at 195.5 159.5)
		(size 0.45)
		(drill 0.1)
		(layers "F.Cu" "B.Cu")
		(remove_unused_layers yes)
		(keep_end_layers yes)
		(zone_layer_connections)
		(net 570)
	)
	(segment
		(start 195.0005 153.0005)
		(end 195.5 153.5)
		(width 0.256)
		(layer "F.Cu")
		(net 571)
	)
	(via
		(at 195.5 153.5)
		(size 0.45)
		(drill 0.1)
		(layers "F.Cu" "B.Cu")
		(remove_unused_layers yes)
		(keep_end_layers yes)
		(zone_layer_connections)
		(net 571)
	)
	(segment
		(start 195.0005 149.9995)
		(end 195.5 149.5)
		(width 0.256)
		(layer "F.Cu")
		(net 572)
	)
	(via
		(at 195.5 149.5)
		(size 0.45)
		(drill 0.1)
		(layers "F.Cu" "B.Cu")
		(remove_unused_layers yes)
		(keep_end_layers yes)
		(zone_layer_connections)
		(net 572)
	)
	(segment
		(start 192.0005 159.0005)
		(end 192.5 159.5)
		(width 0.256)
		(layer "F.Cu")
		(net 573)
	)
	(segment
		(start 255.106 179.78)
		(end 255.1 179.774)
		(width 0.1)
		(layer "F.Cu")
		(net 573)
	)
	(segment
		(start 255.937 179.78)
		(end 255.106 179.78)
		(width 0.1)
		(layer "F.Cu")
		(net 573)
	)
	(segment
		(start 190.0005 159.0005)
		(end 190.5 159.5)
		(width 0.256)
		(layer "F.Cu")
		(net 573)
	)
	(via
		(at 192.5 159.5)
		(size 0.45)
		(drill 0.1)
		(layers "F.Cu" "B.Cu")
		(remove_unused_layers yes)
		(keep_end_layers yes)
		(zone_layer_connections "In8.Cu")
		(net 573)
	)
	(via
		(at 251.05 179.625)
		(size 0.45)
		(drill 0.1)
		(layers "F.Cu" "B.Cu")
		(remove_unused_layers yes)
		(keep_end_layers yes)
		(zone_layer_connections "In8.Cu")
		(net 573)
	)
	(via
		(at 246.1 179.625)
		(size 0.45)
		(drill 0.1)
		(layers "F.Cu" "B.Cu")
		(remove_unused_layers yes)
		(keep_end_layers yes)
		(zone_layer_connections "In8.Cu")
		(net 573)
	)
	(via
		(at 190.5 159.5)
		(size 0.45)
		(drill 0.1)
		(layers "F.Cu" "B.Cu")
		(remove_unused_layers yes)
		(keep_end_layers yes)
		(zone_layer_connections "In8.Cu")
		(net 573)
	)
	(via
		(at 245.025 179.275)
		(size 0.45)
		(drill 0.1)
		(layers "F.Cu" "B.Cu")
		(remove_unused_layers yes)
		(keep_end_layers yes)
		(zone_layer_connections "In8.Cu")
		(net 573)
	)
	(via
		(at 247.275 179.275)
		(size 0.45)
		(drill 0.1)
		(layers "F.Cu" "B.Cu")
		(remove_unused_layers yes)
		(keep_end_layers yes)
		(zone_layer_connections "In8.Cu")
		(net 573)
	)
	(via
		(at 188.5 157.5)
		(size 0.45)
		(drill 0.1)
		(layers "F.Cu" "B.Cu")
		(remove_unused_layers yes)
		(keep_end_layers yes)
		(zone_layer_connections "In8.Cu")
		(net 573)
	)
	(via
		(at 248.525 179.675)
		(size 0.45)
		(drill 0.1)
		(layers "F.Cu" "B.Cu")
		(remove_unused_layers yes)
		(keep_end_layers yes)
		(zone_layer_connections "In8.Cu")
		(net 573)
	)
	(via
		(at 249.825 179.275)
		(size 0.45)
		(drill 0.1)
		(layers "F.Cu" "B.Cu")
		(remove_unused_layers yes)
		(keep_end_layers yes)
		(zone_layer_connections "In8.Cu")
		(net 573)
	)
	(via
		(at 252.475 179.275)
		(size 0.45)
		(drill 0.1)
		(layers "F.Cu" "B.Cu")
		(remove_unused_layers yes)
		(keep_end_layers yes)
		(zone_layer_connections "In8.Cu")
		(net 573)
	)
	(segment
		(start 190.002 160)
		(end 190.002 159.998)
		(width 0.256)
		(layer "B.Cu")
		(net 573)
	)
	(segment
		(start 188.5 157.5)
		(end 188.5 156.95)
		(width 0.4)
		(layer "B.Cu")
		(net 573)
	)
	(segment
		(start 190.002 159.998)
		(end 190.5 159.5)
		(width 0.256)
		(layer "B.Cu")
		(net 573)
	)
	(segment
		(start 192.5 159.5)
		(end 192 160)
		(width 0.256)
		(layer "B.Cu")
		(net 573)
	)
	(segment
		(start 196.97071 164.32929)
		(end 196.929289 164.370711)
		(width 0.1)
		(layer "F.Cu")
		(net 583)
	)
	(segment
		(start 196.31 173.70759)
		(end 196.31 166.1)
		(width 0.22)
		(layer "F.Cu")
		(net 583)
	)
	(segment
		(start 196.4 164.741421)
		(end 196.4 165.968579)
		(width 0.1)
		(layer "F.Cu")
		(net 583)
	)
	(segment
		(start 181.535766 191.795532)
		(end 193.966854 179.364444)
		(width 0.22)
		(layer "F.Cu")
		(net 583)
	)
	(segment
		(start 196.858579 164.4)
		(end 196.741421 164.4)
		(width 0.1)
		(layer "F.Cu")
		(net 583)
	)
	(segment
		(start 196.37071 166.03929)
		(end 196.31 166.1)
		(width 0.1)
		(layer "F.Cu")
		(net 583)
	)
	(segment
		(start 179.65 197.3)
		(end 179.96 196.99)
		(width 0.22)
		(layer "F.Cu")
		(net 583)
	)
	(segment
		(start 179.96 196.99)
		(end 179.96 195.599767)
		(width 0.22)
		(layer "F.Cu")
		(net 583)
	)
	(segment
		(start 179.65 199.25)
		(end 179.65 197.3)
		(width 0.22)
		(layer "F.Cu")
		(net 583)
	)
	(segment
		(start 196.599999 164.458579)
		(end 196.458578 164.6)
		(width 0.1)
		(layer "F.Cu")
		(net 583)
	)
	(segment
		(start 197 164)
		(end 197 164.258579)
		(width 0.1)
		(layer "F.Cu")
		(net 583)
	)
	(arc
		(start 196.458578 164.6)
		(mid 196.415224 164.664885)
		(end 196.4 164.741421)
		(width 0.1)
		(layer "F.Cu")
		(net 583)
	)
	(arc
		(start 181.535766 191.795532)
		(mid 180.369528 193.54093)
		(end 179.96 195.599767)
		(width 0.22)
		(layer "F.Cu")
		(net 583)
	)
	(arc
		(start 196.929289 164.370711)
		(mid 196.896847 164.392388)
		(end 196.858579 164.4)
		(width 0.1)
		(layer "F.Cu")
		(net 583)
	)
	(arc
		(start 196.37071 166.03929)
		(mid 196.392388 166.006848)
		(end 196.4 165.968579)
		(width 0.1)
		(layer "F.Cu")
		(net 583)
	)
	(arc
		(start 196.741421 164.4)
		(mid 196.664884 164.415224)
		(end 196.599999 164.458579)
		(width 0.1)
		(layer "F.Cu")
		(net 583)
	)
	(arc
		(start 197 164.258579)
		(mid 196.992388 164.296848)
		(end 196.97071 164.32929)
		(width 0.1)
		(layer "F.Cu")
		(net 583)
	)
	(arc
		(start 193.966854 179.364444)
		(mid 195.701036 176.769057)
		(end 196.31 173.70759)
		(width 0.22)
		(layer "F.Cu")
		(net 583)
	)
	(segment
		(start 196.6 165.875)
		(end 196.6 165.930848)
		(width 0.1)
		(layer "F.Cu")
		(net 584)
	)
	(segment
		(start 196.742674 165.75)
		(end 196.725 165.75)
		(width 0.1)
		(layer "F.Cu")
		(net 584)
	)
	(segment
		(start 180.65 199.25)
		(end 180.65 197.341421)
		(width 0.22)
		(layer "F.Cu")
		(net 584)
	)
	(segment
		(start 196.97071 164.67071)
		(end 196.929289 164.629289)
		(width 0.1)
		(layer "F.Cu")
		(net 584)
	)
	(segment
		(start 180.34 196.948579)
		(end 180.34 195.59977)
		(width 0.22)
		(layer "F.Cu")
		(net 584)
	)
	(segment
		(start 196.62929 166.03929)
		(end 196.69 166.1)
		(width 0.1)
		(layer "F.Cu")
		(net 584)
	)
	(segment
		(start 181.804466 192.064236)
		(end 194.235555 179.633147)
		(width 0.22)
		(layer "F.Cu")
		(net 584)
	)
	(segment
		(start 197 165)
		(end 197 164.741421)
		(width 0.1)
		(layer "F.Cu")
		(net 584)
	)
	(segment
		(start 196.6 165.930848)
		(end 196.6 165.968579)
		(width 0.1)
		(layer "F.Cu")
		(net 584)
	)
	(segment
		(start 196.69 173.707592)
		(end 196.69 166.1)
		(width 0.22)
		(layer "F.Cu")
		(net 584)
	)
	(segment
		(start 196.6 164.782843)
		(end 196.6 165.375)
		(width 0.1)
		(layer "F.Cu")
		(net 584)
	)
	(segment
		(start 196.725 165.5)
		(end 196.742674 165.5)
		(width 0.1)
		(layer "F.Cu")
		(net 584)
	)
	(segment
		(start 196.712132 164.62929)
		(end 196.629289 164.712133)
		(width 0.1)
		(layer "F.Cu")
		(net 584)
	)
	(segment
		(start 196.858579 164.6)
		(end 196.782843 164.6)
		(width 0.1)
		(layer "F.Cu")
		(net 584)
	)
	(segment
		(start 180.62071 197.27071)
		(end 180.369289 197.019289)
		(width 0.22)
		(layer "F.Cu")
		(net 584)
	)
	(arc
		(start 196.782843 164.6)
		(mid 196.744574 164.607612)
		(end 196.712132 164.62929)
		(width 0.1)
		(layer "F.Cu")
		(net 584)
	)
	(arc
		(start 196.929289 164.629289)
		(mid 196.896847 164.607612)
		(end 196.858579 164.6)
		(width 0.1)
		(layer "F.Cu")
		(net 584)
	)
	(arc
		(start 196.629289 164.712133)
		(mid 196.607612 164.744575)
		(end 196.6 164.782843)
		(width 0.1)
		(layer "F.Cu")
		(net 584)
	)
	(arc
		(start 197 164.741421)
		(mid 196.992388 164.703152)
		(end 196.97071 164.67071)
		(width 0.1)
		(layer "F.Cu")
		(net 584)
	)
	(arc
		(start 180.369289 197.019289)
		(mid 180.347612 196.986847)
		(end 180.34 196.948579)
		(width 0.22)
		(layer "F.Cu")
		(net 584)
	)
	(arc
		(start 196.867674 165.625)
		(mid 196.831062 165.713388)
		(end 196.742674 165.75)
		(width 0.1)
		(layer "F.Cu")
		(net 584)
	)
	(arc
		(start 196.6 165.968579)
		(mid 196.607612 166.006848)
		(end 196.62929 166.03929)
		(width 0.1)
		(layer "F.Cu")
		(net 584)
	)
	(arc
		(start 180.65 197.341421)
		(mid 180.642388 197.303152)
		(end 180.62071 197.27071)
		(width 0.22)
		(layer "F.Cu")
		(net 584)
	)
	(arc
		(start 194.235555 179.633147)
		(mid 196.052108 176.914479)
		(end 196.69 173.707592)
		(width 0.22)
		(layer "F.Cu")
		(net 584)
	)
	(arc
		(start 196.6 165.375)
		(mid 196.636612 165.463388)
		(end 196.725 165.5)
		(width 0.1)
		(layer "F.Cu")
		(net 584)
	)
	(arc
		(start 196.742674 165.5)
		(mid 196.831062 165.536612)
		(end 196.867674 165.625)
		(width 0.1)
		(layer "F.Cu")
		(net 584)
	)
	(arc
		(start 196.725 165.75)
		(mid 196.636612 165.786612)
		(end 196.6 165.875)
		(width 0.1)
		(layer "F.Cu")
		(net 584)
	)
	(arc
		(start 180.34 195.59977)
		(mid 180.720602 193.686353)
		(end 181.804466 192.064236)
		(width 0.22)
		(layer "F.Cu")
		(net 584)
	)
	(segment
		(start 183.65 197.3)
		(end 183.96 196.99)
		(width 0.22)
		(layer "F.Cu")
		(net 585)
	)
	(segment
		(start 198.37071 166.03929)
		(end 198.31 166.1)
		(width 0.1)
		(layer "F.Cu")
		(net 585)
	)
	(segment
		(start 183.96 196.99)
		(end 183.96 194.399767)
		(width 0.22)
		(layer "F.Cu")
		(net 585)
	)
	(segment
		(start 198.599999 164.458579)
		(end 198.458578 164.6)
		(width 0.1)
		(layer "F.Cu")
		(net 585)
	)
	(segment
		(start 199 164)
		(end 199 164.258579)
		(width 0.1)
		(layer "F.Cu")
		(net 585)
	)
	(segment
		(start 198.31 174.50759)
		(end 198.31 166.1)
		(width 0.22)
		(layer "F.Cu")
		(net 585)
	)
	(segment
		(start 183.65 199.25)
		(end 183.65 197.3)
		(width 0.22)
		(layer "F.Cu")
		(net 585)
	)
	(segment
		(start 198.4 164.741421)
		(end 198.4 165.968579)
		(width 0.1)
		(layer "F.Cu")
		(net 585)
	)
	(segment
		(start 198.858579 164.4)
		(end 198.741421 164.4)
		(width 0.1)
		(layer "F.Cu")
		(net 585)
	)
	(segment
		(start 198.97071 164.32929)
		(end 198.929289 164.370711)
		(width 0.1)
		(layer "F.Cu")
		(net 585)
	)
	(segment
		(start 185.535766 190.595532)
		(end 195.966854 180.164444)
		(width 0.22)
		(layer "F.Cu")
		(net 585)
	)
	(arc
		(start 198.929289 164.370711)
		(mid 198.896847 164.392388)
		(end 198.858579 164.4)
		(width 0.1)
		(layer "F.Cu")
		(net 585)
	)
	(arc
		(start 198.37071 166.03929)
		(mid 198.392388 166.006848)
		(end 198.4 165.968579)
		(width 0.1)
		(layer "F.Cu")
		(net 585)
	)
	(arc
		(start 183.96 194.399767)
		(mid 184.369528 192.34093)
		(end 185.535766 190.595532)
		(width 0.22)
		(layer "F.Cu")
		(net 585)
	)
	(arc
		(start 195.966854 180.164444)
		(mid 197.701036 177.569057)
		(end 198.31 174.50759)
		(width 0.22)
		(layer "F.Cu")
		(net 585)
	)
	(arc
		(start 198.741421 164.4)
		(mid 198.664884 164.415224)
		(end 198.599999 164.458579)
		(width 0.1)
		(layer "F.Cu")
		(net 585)
	)
	(arc
		(start 198.458578 164.6)
		(mid 198.415224 164.664885)
		(end 198.4 164.741421)
		(width 0.1)
		(layer "F.Cu")
		(net 585)
	)
	(arc
		(start 199 164.258579)
		(mid 198.992388 164.296848)
		(end 198.97071 164.32929)
		(width 0.1)
		(layer "F.Cu")
		(net 585)
	)
	(segment
		(start 184.65 199.25)
		(end 184.65 197.3)
		(width 0.22)
		(layer "F.Cu")
		(net 586)
	)
	(segment
		(start 198.6 165.85)
		(end 198.6 165.879853)
		(width 0.1)
		(layer "F.Cu")
		(net 586)
	)
	(segment
		(start 198.69 174.507592)
		(end 198.69 166.1)
		(width 0.22)
		(layer "F.Cu")
		(net 586)
	)
	(segment
		(start 185.804466 190.864236)
		(end 196.235555 180.433147)
		(width 0.22)
		(layer "F.Cu")
		(net 586)
	)
	(segment
		(start 198.6 165.879853)
		(end 198.6 165.968579)
		(width 0.1)
		(layer "F.Cu")
		(net 586)
	)
	(segment
		(start 199 165)
		(end 199 164.741421)
		(width 0.1)
		(layer "F.Cu")
		(net 586)
	)
	(segment
		(start 198.858579 164.6)
		(end 198.782843 164.6)
		(width 0.1)
		(layer "F.Cu")
		(net 586)
	)
	(segment
		(start 184.34 196.99)
		(end 184.34 194.39977)
		(width 0.22)
		(layer "F.Cu")
		(net 586)
	)
	(segment
		(start 198.62929 166.03929)
		(end 198.69 166.1)
		(width 0.1)
		(layer "F.Cu")
		(net 586)
	)
	(segment
		(start 198.734682 165.725)
		(end 198.725 165.725)
		(width 0.1)
		(layer "F.Cu")
		(net 586)
	)
	(segment
		(start 198.725 165.475)
		(end 198.734682 165.475)
		(width 0.1)
		(layer "F.Cu")
		(net 586)
	)
	(segment
		(start 198.712132 164.62929)
		(end 198.629289 164.712133)
		(width 0.1)
		(layer "F.Cu")
		(net 586)
	)
	(segment
		(start 198.6 164.782843)
		(end 198.6 165.35)
		(width 0.1)
		(layer "F.Cu")
		(net 586)
	)
	(segment
		(start 184.65 197.3)
		(end 184.34 196.99)
		(width 0.22)
		(layer "F.Cu")
		(net 586)
	)
	(segment
		(start 198.97071 164.67071)
		(end 198.929289 164.629289)
		(width 0.1)
		(layer "F.Cu")
		(net 586)
	)
	(arc
		(start 185.804466 190.864236)
		(mid 184.720602 192.486353)
		(end 184.34 194.39977)
		(width 0.22)
		(layer "F.Cu")
		(net 586)
	)
	(arc
		(start 198.734682 165.475)
		(mid 198.82307 165.511612)
		(end 198.859682 165.6)
		(width 0.1)
		(layer "F.Cu")
		(net 586)
	)
	(arc
		(start 198.859682 165.6)
		(mid 198.82307 165.688388)
		(end 198.734682 165.725)
		(width 0.1)
		(layer "F.Cu")
		(net 586)
	)
	(arc
		(start 198.725 165.725)
		(mid 198.636612 165.761612)
		(end 198.6 165.85)
		(width 0.1)
		(layer "F.Cu")
		(net 586)
	)
	(arc
		(start 198.929289 164.629289)
		(mid 198.896847 164.607612)
		(end 198.858579 164.6)
		(width 0.1)
		(layer "F.Cu")
		(net 586)
	)
	(arc
		(start 196.235555 180.433147)
		(mid 198.052111 177.714479)
		(end 198.69 174.507592)
		(width 0.22)
		(layer "F.Cu")
		(net 586)
	)
	(arc
		(start 198.6 165.35)
		(mid 198.636612 165.438388)
		(end 198.725 165.475)
		(width 0.1)
		(layer "F.Cu")
		(net 586)
	)
	(arc
		(start 199 164.741421)
		(mid 198.992388 164.703152)
		(end 198.97071 164.67071)
		(width 0.1)
		(layer "F.Cu")
		(net 586)
	)
	(arc
		(start 198.782843 164.6)
		(mid 198.744574 164.607612)
		(end 198.712132 164.62929)
		(width 0.1)
		(layer "F.Cu")
		(net 586)
	)
	(arc
		(start 198.629289 164.712133)
		(mid 198.607612 164.744575)
		(end 198.6 164.782843)
		(width 0.1)
		(layer "F.Cu")
		(net 586)
	)
	(arc
		(start 198.6 165.968579)
		(mid 198.607612 166.006848)
		(end 198.62929 166.03929)
		(width 0.1)
		(layer "F.Cu")
		(net 586)
	)
	(segment
		(start 199.858579 162.4)
		(end 199.741421 162.4)
		(width 0.1)
		(layer "F.Cu")
		(net 587)
	)
	(segment
		(start 199.4 162.741421)
		(end 199.4 165.968579)
		(width 0.1)
		(layer "F.Cu")
		(net 587)
	)
	(segment
		(start 199.97071 162.32929)
		(end 199.929289 162.370711)
		(width 0.1)
		(layer "F.Cu")
		(net 587)
	)
	(segment
		(start 187.96 196.99)
		(end 187.65 197.3)
		(width 0.22)
		(layer "F.Cu")
		(net 587)
	)
	(segment
		(start 187.96 193.499767)
		(end 187.96 196.99)
		(width 0.22)
		(layer "F.Cu")
		(net 587)
	)
	(segment
		(start 199.31 166.1)
		(end 199.31 167.907087)
		(width 0.22)
		(layer "F.Cu")
		(net 587)
	)
	(segment
		(start 199.599999 162.458579)
		(end 199.458578 162.6)
		(width 0.1)
		(layer "F.Cu")
		(net 587)
	)
	(segment
		(start 197.866854 181.364444)
		(end 189.535765 189.695533)
		(width 0.22)
		(layer "F.Cu")
		(net 587)
	)
	(segment
		(start 200.21 169.792916)
		(end 200.21 175.70759)
		(width 0.22)
		(layer "F.Cu")
		(net 587)
	)
	(segment
		(start 200 162)
		(end 200 162.258579)
		(width 0.1)
		(layer "F.Cu")
		(net 587)
	)
	(segment
		(start 187.65 197.3)
		(end 187.65 199.25)
		(width 0.22)
		(layer "F.Cu")
		(net 587)
	)
	(segment
		(start 199.714193 168.882895)
		(end 199.917107 169.085809)
		(width 0.22)
		(layer "F.Cu")
		(net 587)
	)
	(segment
		(start 199.37071 166.03929)
		(end 199.31 166.1)
		(width 0.1)
		(layer "F.Cu")
		(net 587)
	)
	(arc
		(start 200.21 175.70759)
		(mid 199.601036 178.769057)
		(end 197.866854 181.364444)
		(width 0.22)
		(layer "F.Cu")
		(net 587)
	)
	(arc
		(start 199.929289 162.370711)
		(mid 199.896847 162.392388)
		(end 199.858579 162.4)
		(width 0.1)
		(layer "F.Cu")
		(net 587)
	)
	(arc
		(start 199.714193 168.882895)
		(mid 199.415046 168.435191)
		(end 199.31 167.907087)
		(width 0.22)
		(layer "F.Cu")
		(net 587)
	)
	(arc
		(start 199.917107 169.085809)
		(mid 200.13388 169.410232)
		(end 200.21 169.792916)
		(width 0.22)
		(layer "F.Cu")
		(net 587)
	)
	(arc
		(start 189.535765 189.695533)
		(mid 188.369528 191.44093)
		(end 187.96 193.499767)
		(width 0.22)
		(layer "F.Cu")
		(net 587)
	)
	(arc
		(start 199.4 165.968579)
		(mid 199.392388 166.006848)
		(end 199.37071 166.03929)
		(width 0.1)
		(layer "F.Cu")
		(net 587)
	)
	(arc
		(start 199.458578 162.6)
		(mid 199.415224 162.664885)
		(end 199.4 162.741421)
		(width 0.1)
		(layer "F.Cu")
		(net 587)
	)
	(arc
		(start 200 162.258579)
		(mid 199.992388 162.296848)
		(end 199.97071 162.32929)
		(width 0.1)
		(layer "F.Cu")
		(net 587)
	)
	(arc
		(start 199.741421 162.4)
		(mid 199.664884 162.415224)
		(end 199.599999 162.458579)
		(width 0.1)
		(layer "F.Cu")
		(net 587)
	)
	(segment
		(start 199.858579 162.6)
		(end 199.782843 162.6)
		(width 0.1)
		(layer "F.Cu")
		(net 588)
	)
	(segment
		(start 199.741673 163.65)
		(end 199.725 163.65)
		(width 0.1)
		(layer "F.Cu")
		(net 588)
	)
	(segment
		(start 199.6 163.775)
		(end 199.6 163.894069)
		(width 0.1)
		(layer "F.Cu")
		(net 588)
	)
	(segment
		(start 199.62929 166.03929)
		(end 199.69 166.1)
		(width 0.1)
		(layer "F.Cu")
		(net 588)
	)
	(segment
		(start 188.65 197.3)
		(end 188.65 199.25)
		(width 0.22)
		(layer "F.Cu")
		(net 588)
	)
	(segment
		(start 199.712132 162.62929)
		(end 199.629289 162.712133)
		(width 0.1)
		(layer "F.Cu")
		(net 588)
	)
	(segment
		(start 188.34 193.49977)
		(end 188.34 196.99)
		(width 0.22)
		(layer "F.Cu")
		(net 588)
	)
	(segment
		(start 198.135555 181.633147)
		(end 189.804466 189.964236)
		(width 0.22)
		(layer "F.Cu")
		(net 588)
	)
	(segment
		(start 200 163)
		(end 200 162.741421)
		(width 0.1)
		(layer "F.Cu")
		(net 588)
	)
	(segment
		(start 199.725 163.4)
		(end 199.741673 163.4)
		(width 0.1)
		(layer "F.Cu")
		(net 588)
	)
	(segment
		(start 199.982893 168.614191)
		(end 200.185808 168.817106)
		(width 0.22)
		(layer "F.Cu")
		(net 588)
	)
	(segment
		(start 199.6 162.782843)
		(end 199.6 163.275)
		(width 0.1)
		(layer "F.Cu")
		(net 588)
	)
	(segment
		(start 199.69 166.1)
		(end 199.69 167.907084)
		(width 0.22)
		(layer "F.Cu")
		(net 588)
	)
	(segment
		(start 188.34 196.99)
		(end 188.65 197.3)
		(width 0.22)
		(layer "F.Cu")
		(net 588)
	)
	(segment
		(start 200.59 169.792913)
		(end 200.59 175.707592)
		(width 0.22)
		(layer "F.Cu")
		(net 588)
	)
	(segment
		(start 199.6 163.894069)
		(end 199.6 165.968579)
		(width 0.1)
		(layer "F.Cu")
		(net 588)
	)
	(segment
		(start 199.97071 162.67071)
		(end 199.929289 162.629289)
		(width 0.1)
		(layer "F.Cu")
		(net 588)
	)
	(arc
		(start 200.59 175.707592)
		(mid 199.952111 178.914479)
		(end 198.135555 181.633147)
		(width 0.22)
		(layer "F.Cu")
		(net 588)
	)
	(arc
		(start 199.725 163.65)
		(mid 199.636612 163.686612)
		(end 199.6 163.775)
		(width 0.1)
		(layer "F.Cu")
		(net 588)
	)
	(arc
		(start 199.6 165.968579)
		(mid 199.607612 166.006848)
		(end 199.62929 166.03929)
		(width 0.1)
		(layer "F.Cu")
		(net 588)
	)
	(arc
		(start 199.6 163.275)
		(mid 199.636612 163.363388)
		(end 199.725 163.4)
		(width 0.1)
		(layer "F.Cu")
		(net 588)
	)
	(arc
		(start 200 162.741421)
		(mid 199.992388 162.703152)
		(end 199.97071 162.67071)
		(width 0.1)
		(layer "F.Cu")
		(net 588)
	)
	(arc
		(start 199.866673 163.525)
		(mid 199.830061 163.613388)
		(end 199.741673 163.65)
		(width 0.1)
		(layer "F.Cu")
		(net 588)
	)
	(arc
		(start 188.34 193.49977)
		(mid 188.720602 191.586353)
		(end 189.804466 189.964236)
		(width 0.22)
		(layer "F.Cu")
		(net 588)
	)
	(arc
		(start 199.929289 162.629289)
		(mid 199.896847 162.607612)
		(end 199.858579 162.6)
		(width 0.1)
		(layer "F.Cu")
		(net 588)
	)
	(arc
		(start 199.69 167.907084)
		(mid 199.76612 168.289767)
		(end 199.982893 168.614191)
		(width 0.22)
		(layer "F.Cu")
		(net 588)
	)
	(arc
		(start 199.629289 162.712133)
		(mid 199.607612 162.744575)
		(end 199.6 162.782843)
		(width 0.1)
		(layer "F.Cu")
		(net 588)
	)
	(arc
		(start 199.741673 163.4)
		(mid 199.830061 163.436612)
		(end 199.866673 163.525)
		(width 0.1)
		(layer "F.Cu")
		(net 588)
	)
	(arc
		(start 200.59 169.792913)
		(mid 200.484954 169.26481)
		(end 200.185808 168.817106)
		(width 0.22)
		(layer "F.Cu")
		(net 588)
	)
	(arc
		(start 199.782843 162.6)
		(mid 199.744574 162.607612)
		(end 199.712132 162.62929)
		(width 0.1)
		(layer "F.Cu")
		(net 588)
	)
	(segment
		(start 200.4 164.741421)
		(end 200.4 165.968579)
		(width 0.1)
		(layer "F.Cu")
		(net 589)
	)
	(segment
		(start 200.714193 167.582895)
		(end 201.617107 168.485809)
		(width 0.22)
		(layer "F.Cu")
		(net 589)
	)
	(segment
		(start 200.31 166.1)
		(end 200.31 166.607087)
		(width 0.22)
		(layer "F.Cu")
		(net 589)
	)
	(segment
		(start 200.858579 164.4)
		(end 200.741421 164.4)
		(width 0.1)
		(layer "F.Cu")
		(net 589)
	)
	(segment
		(start 201 164)
		(end 201 164.258579)
		(width 0.1)
		(layer "F.Cu")
		(net 589)
	)
	(segment
		(start 200.37071 166.03929)
		(end 200.31 166.1)
		(width 0.1)
		(layer "F.Cu")
		(net 589)
	)
	(segment
		(start 200.599999 164.458579)
		(end 200.458578 164.6)
		(width 0.1)
		(layer "F.Cu")
		(net 589)
	)
	(segment
		(start 191.96 193.199767)
		(end 191.96 196.99)
		(width 0.22)
		(layer "F.Cu")
		(net 589)
	)
	(segment
		(start 191.96 196.99)
		(end 191.65 197.3)
		(width 0.22)
		(layer "F.Cu")
		(net 589)
	)
	(segment
		(start 200.97071 164.32929)
		(end 200.929289 164.370711)
		(width 0.1)
		(layer "F.Cu")
		(net 589)
	)
	(segment
		(start 199.566854 183.364444)
		(end 193.535765 189.395533)
		(width 0.22)
		(layer "F.Cu")
		(net 589)
	)
	(segment
		(start 191.65 197.3)
		(end 191.65 199.25)
		(width 0.22)
		(layer "F.Cu")
		(net 589)
	)
	(segment
		(start 201.91 169.192916)
		(end 201.91 177.70759)
		(width 0.22)
		(layer "F.Cu")
		(net 589)
	)
	(arc
		(start 191.96 193.199767)
		(mid 192.369528 191.14093)
		(end 193.535765 189.395533)
		(width 0.22)
		(layer "F.Cu")
		(net 589)
	)
	(arc
		(start 201.617107 168.485809)
		(mid 201.83388 168.810232)
		(end 201.91 169.192916)
		(width 0.22)
		(layer "F.Cu")
		(net 589)
	)
	(arc
		(start 200.458578 164.6)
		(mid 200.415224 164.664885)
		(end 200.4 164.741421)
		(width 0.1)
		(layer "F.Cu")
		(net 589)
	)
	(arc
		(start 200.929289 164.370711)
		(mid 200.896847 164.392388)
		(end 200.858579 164.4)
		(width 0.1)
		(layer "F.Cu")
		(net 589)
	)
	(arc
		(start 200.741421 164.4)
		(mid 200.664884 164.415224)
		(end 200.599999 164.458579)
		(width 0.1)
		(layer "F.Cu")
		(net 589)
	)
	(arc
		(start 200.714193 167.582895)
		(mid 200.415046 167.135191)
		(end 200.31 166.607087)
		(width 0.22)
		(layer "F.Cu")
		(net 589)
	)
	(arc
		(start 200.37071 166.03929)
		(mid 200.392388 166.006848)
		(end 200.4 165.968579)
		(width 0.1)
		(layer "F.Cu")
		(net 589)
	)
	(arc
		(start 201.91 177.70759)
		(mid 201.301036 180.769057)
		(end 199.566854 183.364444)
		(width 0.22)
		(layer "F.Cu")
		(net 589)
	)
	(arc
		(start 201 164.258579)
		(mid 200.992388 164.296848)
		(end 200.97071 164.32929)
		(width 0.1)
		(layer "F.Cu")
		(net 589)
	)
	(segment
		(start 199.835555 183.633147)
		(end 193.804466 189.664236)
		(width 0.22)
		(layer "F.Cu")
		(net 590)
	)
	(segment
		(start 192.65 197.3)
		(end 192.65 199.25)
		(width 0.22)
		(layer "F.Cu")
		(net 590)
	)
	(segment
		(start 200.6 165.305372)
		(end 200.6 165.275)
		(width 0.1)
		(layer "F.Cu")
		(net 590)
	)
	(segment
		(start 200.6 165.275)
		(end 200.6 164.782843)
		(width 0.1)
		(layer "F.Cu")
		(net 590)
	)
	(segment
		(start 200.69 166.1)
		(end 200.62929 166.03929)
		(width 0.1)
		(layer "F.Cu")
		(net 590)
	)
	(segment
		(start 200.782843 164.6)
		(end 200.858579 164.6)
		(width 0.1)
		(layer "F.Cu")
		(net 590)
	)
	(segment
		(start 192.34 196.99)
		(end 192.65 197.3)
		(width 0.22)
		(layer "F.Cu")
		(net 590)
	)
	(segment
		(start 200.69 166.1)
		(end 200.69 166.607084)
		(width 0.22)
		(layer "F.Cu")
		(net 590)
	)
	(segment
		(start 200.6 165.968579)
		(end 200.6 165.875)
		(width 0.1)
		(layer "F.Cu")
		(net 590)
	)
	(segment
		(start 200.929289 164.629289)
		(end 200.97071 164.67071)
		(width 0.1)
		(layer "F.Cu")
		(net 590)
	)
	(segment
		(start 202.29 169.192913)
		(end 202.29 177.707592)
		(width 0.22)
		(layer "F.Cu")
		(net 590)
	)
	(segment
		(start 192.34 193.19977)
		(end 192.34 196.99)
		(width 0.22)
		(layer "F.Cu")
		(net 590)
	)
	(segment
		(start 201 164.741421)
		(end 201 165)
		(width 0.1)
		(layer "F.Cu")
		(net 590)
	)
	(segment
		(start 200.982893 167.314191)
		(end 201.885808 168.217106)
		(width 0.22)
		(layer "F.Cu")
		(net 590)
	)
	(segment
		(start 200.629289 164.712133)
		(end 200.712132 164.62929)
		(width 0.1)
		(layer "F.Cu")
		(net 590)
	)
	(segment
		(start 200.869628 165.605372)
		(end 200.869628 165.575)
		(width 0.1)
		(layer "F.Cu")
		(net 590)
	)
	(arc
		(start 200.97071 164.67071)
		(mid 200.992388 164.703152)
		(end 201 164.741421)
		(width 0.1)
		(layer "F.Cu")
		(net 590)
	)
	(arc
		(start 200.734814 165.440186)
		(mid 200.639486 165.4007)
		(end 200.6 165.305372)
		(width 0.1)
		(layer "F.Cu")
		(net 590)
	)
	(arc
		(start 200.734814 165.740186)
		(mid 200.830142 165.7007)
		(end 200.869628 165.605372)
		(width 0.1)
		(layer "F.Cu")
		(net 590)
	)
	(arc
		(start 202.29 177.707592)
		(mid 201.652111 180.914479)
		(end 199.835555 183.633147)
		(width 0.22)
		(layer "F.Cu")
		(net 590)
	)
	(arc
		(start 200.6 164.782843)
		(mid 200.607612 164.744575)
		(end 200.629289 164.712133)
		(width 0.1)
		(layer "F.Cu")
		(net 590)
	)
	(arc
		(start 202.29 169.192913)
		(mid 202.184954 168.66481)
		(end 201.885808 168.217106)
		(width 0.22)
		(layer "F.Cu")
		(net 590)
	)
	(arc
		(start 200.858579 164.6)
		(mid 200.896847 164.607612)
		(end 200.929289 164.629289)
		(width 0.1)
		(layer "F.Cu")
		(net 590)
	)
	(arc
		(start 200.6 165.875)
		(mid 200.639486 165.779672)
		(end 200.734814 165.740186)
		(width 0.1)
		(layer "F.Cu")
		(net 590)
	)
	(arc
		(start 200.62929 166.03929)
		(mid 200.607612 166.006848)
		(end 200.6 165.968579)
		(width 0.1)
		(layer "F.Cu")
		(net 590)
	)
	(arc
		(start 200.982893 167.314191)
		(mid 200.76612 166.989768)
		(end 200.69 166.607084)
		(width 0.22)
		(layer "F.Cu")
		(net 590)
	)
	(arc
		(start 192.34 193.19977)
		(mid 192.720602 191.286353)
		(end 193.804466 189.664236)
		(width 0.22)
		(layer "F.Cu")
		(net 590)
	)
	(arc
		(start 200.869628 165.575)
		(mid 200.830142 165.479672)
		(end 200.734814 165.440186)
		(width 0.1)
		(layer "F.Cu")
		(net 590)
	)
	(arc
		(start 200.712132 164.62929)
		(mid 200.744574 164.607612)
		(end 200.782843 164.6)
		(width 0.1)
		(layer "F.Cu")
		(net 590)
	)
	(segment
		(start 194.65 198.7)
		(end 194.65 194.55)
		(width 0.182)
		(layer "F.Cu")
		(net 591)
	)
	(segment
		(start 152.299 182.747)
		(end 152.697 182.747)
		(width 0.1)
		(layer "F.Cu")
		(net 591)
	)
	(segment
		(start 195.5 194.25)
		(end 195.747105 194.497105)
		(width 0.182)
		(layer "F.Cu")
		(net 591)
	)
	(segment
		(start 194.65 194.55)
		(end 194.95 194.25)
		(width 0.182)
		(layer "F.Cu")
		(net 591)
	)
	(segment
		(start 194.95 194.25)
		(end 195.5 194.25)
		(width 0.182)
		(layer "F.Cu")
		(net 591)
	)
	(segment
		(start 195.747105 194.497105)
		(end 195.747105 194.828588)
		(width 0.182)
		(layer "F.Cu")
		(net 591)
	)
	(segment
		(start 152.697 182.747)
		(end 153.335981 183.385981)
		(width 0.177)
		(layer "F.Cu")
		(net 591)
	)
	(via
		(at 195.747105 194.828588)
		(size 0.45)
		(drill 0.1)
		(layers "F.Cu" "B.Cu")
		(remove_unused_layers yes)
		(keep_end_layers yes)
		(zone_layer_connections)
		(net 591)
	)
	(via
		(at 153.335981 183.385981)
		(size 0.45)
		(drill 0.1)
		(layers "F.Cu" "B.Cu")
		(remove_unused_layers yes)
		(keep_end_layers yes)
		(zone_layer_connections)
		(net 591)
	)
	(segment
		(start 153.921962 182.8)
		(end 183.718517 182.8)
		(width 0.1)
		(layer "In2.Cu")
		(net 591)
	)
	(segment
		(start 183.718517 182.8)
		(end 195.747105 194.828588)
		(width 0.1)
		(layer "In2.Cu")
		(net 591)
	)
	(segment
		(start 153.335981 183.385981)
		(end 153.921962 182.8)
		(width 0.1)
		(layer "In2.Cu")
		(net 591)
	)
	(segment
		(start 148.8 110.598)
		(end 148.8 111.75)
		(width 0.38)
		(layer "F.Cu")
		(net 592)
	)
	(segment
		(start 185.9995 140.9995)
		(end 185.5 140.5)
		(width 0.256)
		(layer "F.Cu")
		(net 592)
	)
	(via
		(at 148.8 111.75)
		(size 0.45)
		(drill 0.1)
		(layers "F.Cu" "B.Cu")
		(remove_unused_layers yes)
		(keep_end_layers yes)
		(zone_layer_connections)
		(net 592)
	)
	(via
		(at 185.5 140.5)
		(size 0.45)
		(drill 0.1)
		(layers "F.Cu" "B.Cu")
		(remove_unused_layers yes)
		(keep_end_layers yes)
		(zone_layer_connections)
		(net 592)
	)
	(segment
		(start 150.035241 123.965)
		(end 151.107476 123.965)
		(width 0.13)
		(layer "In6.Cu")
		(net 592)
	)
	(segment
		(start 151.107476 123.355)
		(end 150.035241 123.355)
		(width 0.13)
		(layer "In6.Cu")
		(net 592)
	)
	(segment
		(start 148.8 111.75)
		(end 148.75 111.75)
		(width 0.13)
		(layer "In6.Cu")
		(net 592)
	)
	(segment
		(start 148.495 112.975294)
		(end 149.55 114.030294)
		(width 0.13)
		(layer "In6.Cu")
		(net 592)
	)
	(segment
		(start 150.03525 125.665)
		(end 151.107476 125.665)
		(width 0.13)
		(layer "In6.Cu")
		(net 592)
	)
	(segment
		(start 148.75 111.75)
		(end 148.495 112.005)
		(width 0.13)
		(layer "In6.Cu")
		(net 592)
	)
	(segment
		(start 148.495 112.005)
		(end 148.495 112.975294)
		(width 0.13)
		(layer "In6.Cu")
		(net 592)
	)
	(segment
		(start 151.107476 121.655)
		(end 150.035241 121.655)
		(width 0.13)
		(layer "In6.Cu")
		(net 592)
	)
	(segment
		(start 185.5 140.84)
		(end 185.44 140.9)
		(width 0.1)
		(layer "In6.Cu")
		(net 592)
	)
	(segment
		(start 185.44 140.9)
		(end 175 140.9)
		(width 0.1)
		(layer "In6.Cu")
		(net 592)
	)
	(segment
		(start 149.905 120.325)
		(end 151.057476 120.325)
		(width 0.13)
		(layer "In6.Cu")
		(net 592)
	)
	(segment
		(start 161.773959 140.879253)
		(end 162.31 140.879253)
		(width 0.13)
		(layer "In6.Cu")
		(net 592)
	)
	(segment
		(start 162.658348 140.530904)
		(end 162.96 140.530904)
		(width 0.13)
		(layer "In6.Cu")
		(net 592)
	)
	(segment
		(start 151.652476 126.21)
		(end 151.652476 126.510263)
		(width 0.13)
		(layer "In6.Cu")
		(net 592)
	)
	(segment
		(start 162.484174 140.705079)
		(end 162.484174 140.705078)
		(width 0.13)
		(layer "In6.Cu")
		(net 592)
	)
	(segment
		(start 185.5 140.5)
		(end 185.5 140.84)
		(width 0.1)
		(layer "In6.Cu")
		(net 592)
	)
	(segment
		(start 151.652476 126.510263)
		(end 151.652476 130.75777)
		(width 0.13)
		(layer "In6.Cu")
		(net 592)
	)
	(segment
		(start 151.652476 130.75777)
		(end 161.773959 140.879253)
		(width 0.13)
		(layer "In6.Cu")
		(net 592)
	)
	(segment
		(start 149.55 114.030294)
		(end 149.55 119.97)
		(width 0.13)
		(layer "In6.Cu")
		(net 592)
	)
	(segment
		(start 151.107476 125.055)
		(end 150.03525 125.055)
		(width 0.13)
		(layer "In6.Cu")
		(net 592)
	)
	(segment
		(start 150.035241 122.265)
		(end 151.107476 122.265)
		(width 0.13)
		(layer "In6.Cu")
		(net 592)
	)
	(segment
		(start 163.308348 140.879253)
		(end 174.994253 140.879253)
		(width 0.13)
		(layer "In6.Cu")
		(net 592)
	)
	(segment
		(start 163.134174 140.705078)
		(end 163.134174 140.705079)
		(width 0.13)
		(layer "In6.Cu")
		(net 592)
	)
	(segment
		(start 151.652476 120.92)
		(end 151.652476 121.11)
		(width 0.13)
		(layer "In6.Cu")
		(net 592)
	)
	(arc
		(start 162.96 140.530904)
		(mid 163.08316 140.581918)
		(end 163.134174 140.705078)
		(width 0.13)
		(layer "In6.Cu")
		(net 592)
	)
	(arc
		(start 162.31 140.879253)
		(mid 162.43316 140.828239)
		(end 162.484174 140.705079)
		(width 0.13)
		(layer "In6.Cu")
		(net 592)
	)
	(arc
		(start 149.73025 125.36)
		(mid 149.819582 125.575668)
		(end 150.03525 125.665)
		(width 0.13)
		(layer "In6.Cu")
		(net 592)
	)
	(arc
		(start 163.134174 140.705079)
		(mid 163.185188 140.828239)
		(end 163.308348 140.879253)
		(width 0.13)
		(layer "In6.Cu")
		(net 592)
	)
	(arc
		(start 149.730241 121.96)
		(mid 149.819573 122.175668)
		(end 150.035241 122.265)
		(width 0.13)
		(layer "In6.Cu")
		(net 592)
	)
	(arc
		(start 151.652476 124.51)
		(mid 151.492849 124.895373)
		(end 151.107476 125.055)
		(width 0.13)
		(layer "In6.Cu")
		(net 592)
	)
	(arc
		(start 151.107476 122.265)
		(mid 151.492849 122.424627)
		(end 151.652476 122.81)
		(width 0.13)
		(layer "In6.Cu")
		(net 592)
	)
	(arc
		(start 151.057476 120.325)
		(mid 151.478205 120.499271)
		(end 151.652476 120.92)
		(width 0.13)
		(layer "In6.Cu")
		(net 592)
	)
	(arc
		(start 151.107476 125.665)
		(mid 151.492849 125.824627)
		(end 151.652476 126.21)
		(width 0.13)
		(layer "In6.Cu")
		(net 592)
	)
	(arc
		(start 149.730241 123.66)
		(mid 149.819573 123.875668)
		(end 150.035241 123.965)
		(width 0.13)
		(layer "In6.Cu")
		(net 592)
	)
	(arc
		(start 162.484174 140.705078)
		(mid 162.535188 140.581918)
		(end 162.658348 140.530904)
		(width 0.13)
		(layer "In6.Cu")
		(net 592)
	)
	(arc
		(start 150.03525 125.055)
		(mid 149.819582 125.144332)
		(end 149.73025 125.36)
		(width 0.13)
		(layer "In6.Cu")
		(net 592)
	)
	(arc
		(start 150.035241 123.355)
		(mid 149.819573 123.444332)
		(end 149.730241 123.66)
		(width 0.13)
		(layer "In6.Cu")
		(net 592)
	)
	(arc
		(start 151.107476 123.965)
		(mid 151.492849 124.124627)
		(end 151.652476 124.51)
		(width 0.13)
		(layer "In6.Cu")
		(net 592)
	)
	(arc
		(start 151.652476 122.81)
		(mid 151.492849 123.195373)
		(end 151.107476 123.355)
		(width 0.13)
		(layer "In6.Cu")
		(net 592)
	)
	(arc
		(start 151.652476 121.11)
		(mid 151.492849 121.495373)
		(end 151.107476 121.655)
		(width 0.13)
		(layer "In6.Cu")
		(net 592)
	)
	(arc
		(start 149.55 119.97)
		(mid 149.653977 120.221023)
		(end 149.905 120.325)
		(width 0.13)
		(layer "In6.Cu")
		(net 592)
	)
	(arc
		(start 150.035241 121.655)
		(mid 149.819573 121.744332)
		(end 149.730241 121.96)
		(width 0.13)
		(layer "In6.Cu")
		(net 592)
	)
	(segment
		(start 147.95 110.598)
		(end 147.95 111.75)
		(width 0.38)
		(layer "F.Cu")
		(net 593)
	)
	(segment
		(start 185.9995 141.999501)
		(end 185.5 141.5)
		(width 0.256)
		(layer "F.Cu")
		(net 593)
	)
	(via
		(at 147.95 111.75)
		(size 0.45)
		(drill 0.1)
		(layers "F.Cu" "B.Cu")
		(remove_unused_layers yes)
		(keep_end_layers yes)
		(zone_layer_connections)
		(net 593)
	)
	(via
		(at 185.5 141.5)
		(size 0.45)
		(drill 0.1)
		(layers "F.Cu" "B.Cu")
		(remove_unused_layers yes)
		(keep_end_layers yes)
		(zone_layer_connections)
		(net 593)
	)
	(segment
		(start 185.4 141.1)
		(end 175 141.1)
		(width 0.1)
		(layer "In6.Cu")
		(net 593)
	)
	(segment
		(start 150.035241 124.205)
		(end 151.107476 124.205)
		(width 0.13)
		(layer "In6.Cu")
		(net 593)
	)
	(segment
		(start 148.255 113.074706)
		(end 149.31 114.129706)
		(width 0.13)
		(layer "In6.Cu")
		(net 593)
	)
	(segment
		(start 151.107476 121.415)
		(end 150.035241 121.415)
		(width 0.13)
		(layer "In6.Cu")
		(net 593)
	)
	(segment
		(start 149.905 120.565)
		(end 151.057476 120.565)
		(width 0.13)
		(layer "In6.Cu")
		(net 593)
	)
	(segment
		(start 185.5 141.5)
		(end 185.5 141.2)
		(width 0.1)
		(layer "In6.Cu")
		(net 593)
	)
	(segment
		(start 151.107476 123.115)
		(end 150.035241 123.115)
		(width 0.13)
		(layer "In6.Cu")
		(net 593)
	)
	(segment
		(start 161.674547 141.119253)
		(end 174.994253 141.119253)
		(width 0.13)
		(layer "In6.Cu")
		(net 593)
	)
	(segment
		(start 151.412476 126.21)
		(end 151.412476 126.510263)
		(width 0.13)
		(layer "In6.Cu")
		(net 593)
	)
	(segment
		(start 151.412476 120.92)
		(end 151.412476 121.11)
		(width 0.13)
		(layer "In6.Cu")
		(net 593)
	)
	(segment
		(start 149.31 114.129706)
		(end 149.31 119.97)
		(width 0.13)
		(layer "In6.Cu")
		(net 593)
	)
	(segment
		(start 147.95 111.75)
		(end 148.255 112.055)
		(width 0.13)
		(layer "In6.Cu")
		(net 593)
	)
	(segment
		(start 150.035241 122.505)
		(end 151.107476 122.505)
		(width 0.13)
		(layer "In6.Cu")
		(net 593)
	)
	(segment
		(start 185.5 141.2)
		(end 185.4 141.1)
		(width 0.1)
		(layer "In6.Cu")
		(net 593)
	)
	(segment
		(start 148.255 112.055)
		(end 148.255 113.074706)
		(width 0.13)
		(layer "In6.Cu")
		(net 593)
	)
	(segment
		(start 151.412476 130.857182)
		(end 161.674547 141.119253)
		(width 0.13)
		(layer "In6.Cu")
		(net 593)
	)
	(segment
		(start 151.412476 126.510263)
		(end 151.412476 130.857182)
		(width 0.13)
		(layer "In6.Cu")
		(net 593)
	)
	(segment
		(start 151.107476 124.815)
		(end 150.03525 124.815)
		(width 0.13)
		(layer "In6.Cu")
		(net 593)
	)
	(segment
		(start 150.03525 125.905)
		(end 151.107476 125.905)
		(width 0.13)
		(layer "In6.Cu")
		(net 593)
	)
	(arc
		(start 149.490241 121.96)
		(mid 149.649868 122.345373)
		(end 150.035241 122.505)
		(width 0.13)
		(layer "In6.Cu")
		(net 593)
	)
	(arc
		(start 151.107476 124.205)
		(mid 151.323144 124.294332)
		(end 151.412476 124.51)
		(width 0.13)
		(layer "In6.Cu")
		(net 593)
	)
	(arc
		(start 151.057476 120.565)
		(mid 151.308499 120.668977)
		(end 151.412476 120.92)
		(width 0.13)
		(layer "In6.Cu")
		(net 593)
	)
	(arc
		(start 151.107476 125.905)
		(mid 151.323144 125.994332)
		(end 151.412476 126.21)
		(width 0.13)
		(layer "In6.Cu")
		(net 593)
	)
	(arc
		(start 151.412476 121.11)
		(mid 151.323144 121.325668)
		(end 151.107476 121.415)
		(width 0.13)
		(layer "In6.Cu")
		(net 593)
	)
	(arc
		(start 149.31 119.97)
		(mid 149.484271 120.390729)
		(end 149.905 120.565)
		(width 0.13)
		(layer "In6.Cu")
		(net 593)
	)
	(arc
		(start 151.107476 122.505)
		(mid 151.323144 122.594332)
		(end 151.412476 122.81)
		(width 0.13)
		(layer "In6.Cu")
		(net 593)
	)
	(arc
		(start 149.490241 123.66)
		(mid 149.649868 124.045373)
		(end 150.035241 124.205)
		(width 0.13)
		(layer "In6.Cu")
		(net 593)
	)
	(arc
		(start 149.49025 125.36)
		(mid 149.649877 125.745373)
		(end 150.03525 125.905)
		(width 0.13)
		(layer "In6.Cu")
		(net 593)
	)
	(arc
		(start 150.035241 123.115)
		(mid 149.649868 123.274627)
		(end 149.490241 123.66)
		(width 0.13)
		(layer "In6.Cu")
		(net 593)
	)
	(arc
		(start 150.035241 121.415)
		(mid 149.649868 121.574627)
		(end 149.490241 121.96)
		(width 0.13)
		(layer "In6.Cu")
		(net 593)
	)
	(arc
		(start 151.412476 122.81)
		(mid 151.323144 123.025668)
		(end 151.107476 123.115)
		(width 0.13)
		(layer "In6.Cu")
		(net 593)
	)
	(arc
		(start 151.412476 124.51)
		(mid 151.323144 124.725668)
		(end 151.107476 124.815)
		(width 0.13)
		(layer "In6.Cu")
		(net 593)
	)
	(arc
		(start 150.03525 124.815)
		(mid 149.649877 124.974627)
		(end 149.49025 125.36)
		(width 0.13)
		(layer "In6.Cu")
		(net 593)
	)
	(segment
		(start 139.45 110.598)
		(end 139.45 111.75)
		(width 0.38)
		(layer "F.Cu")
		(net 594)
	)
	(segment
		(start 180.9995 140.9995)
		(end 180.5 140.5)
		(width 0.256)
		(layer "F.Cu")
		(net 594)
	)
	(via
		(at 180.5 140.5)
		(size 0.45)
		(drill 0.1)
		(layers "F.Cu" "B.Cu")
		(remove_unused_layers yes)
		(keep_end_layers yes)
		(zone_layer_connections)
		(net 594)
	)
	(via
		(at 139.45 111.75)
		(size 0.45)
		(drill 0.1)
		(layers "F.Cu" "B.Cu")
		(remove_unused_layers yes)
		(keep_end_layers yes)
		(zone_layer_connections)
		(net 594)
	)
	(segment
		(start 180.114848 138.569235)
		(end 180.114848 133.255142)
		(width 0.13)
		(layer "In4.Cu")
		(net 594)
	)
	(segment
		(start 149.25 124.28)
		(end 148.813092 124.28)
		(width 0.13)
		(layer "In4.Cu")
		(net 594)
	)
	(segment
		(start 155.97 123.8)
		(end 155.97 123.486252)
		(width 0.13)
		(layer "In4.Cu")
		(net 594)
	)
	(segment
		(start 148.813092 124.28)
		(end 148.199706 124.28)
		(width 0.13)
		(layer "In4.Cu")
		(net 594)
	)
	(segment
		(start 154.53 123.486252)
		(end 154.53 123.8)
		(width 0.13)
		(layer "In4.Cu")
		(net 594)
	)
	(segment
		(start 180.425 140.9)
		(end 180.198387 140.9)
		(width 0.1)
		(layer "In4.Cu")
		(net 594)
	)
	(segment
		(start 180.1 138.584083)
		(end 180.114848 138.569235)
		(width 0.1)
		(layer "In4.Cu")
		(net 594)
	)
	(segment
		(start 151.17 123.8)
		(end 151.17 123.486249)
		(width 0.13)
		(layer "In4.Cu")
		(net 594)
	)
	(segment
		(start 152.13 123.48625)
		(end 152.13 123.8)
		(width 0.13)
		(layer "In4.Cu")
		(net 594)
	)
	(segment
		(start 180.1 140.801613)
		(end 180.1 140.3)
		(width 0.1)
		(layer "In4.Cu")
		(net 594)
	)
	(segment
		(start 180.198387 140.9)
		(end 180.1 140.801613)
		(width 0.1)
		(layer "In4.Cu")
		(net 594)
	)
	(segment
		(start 139.145 112.055)
		(end 139.45 111.75)
		(width 0.13)
		(layer "In4.Cu")
		(net 594)
	)
	(segment
		(start 153.57 123.8)
		(end 153.57 123.48625)
		(width 0.13)
		(layer "In4.Cu")
		(net 594)
	)
	(segment
		(start 180.114848 133.255142)
		(end 169.069706 122.21)
		(width 0.13)
		(layer "In4.Cu")
		(net 594)
	)
	(segment
		(start 158.37 123.8)
		(end 158.37 123.486254)
		(width 0.13)
		(layer "In4.Cu")
		(net 594)
	)
	(segment
		(start 169.069706 122.21)
		(end 161.220294 122.21)
		(width 0.13)
		(layer "In4.Cu")
		(net 594)
	)
	(segment
		(start 156.93 123.486254)
		(end 156.93 123.8)
		(width 0.13)
		(layer "In4.Cu")
		(net 594)
	)
	(segment
		(start 149.73 123.486249)
		(end 149.73 123.8)
		(width 0.13)
		(layer "In4.Cu")
		(net 594)
	)
	(segment
		(start 180.235472 139.925)
		(end 180.225 139.925)
		(width 0.1)
		(layer "In4.Cu")
		(net 594)
	)
	(segment
		(start 180.5 140.5)
		(end 180.5 140.825)
		(width 0.1)
		(layer "In4.Cu")
		(net 594)
	)
	(segment
		(start 161.220294 122.21)
		(end 159.150294 124.28)
		(width 0.13)
		(layer "In4.Cu")
		(net 594)
	)
	(segment
		(start 180.5 140.825)
		(end 180.425 140.9)
		(width 0.1)
		(layer "In4.Cu")
		(net 594)
	)
	(segment
		(start 148.199706 124.28)
		(end 139.145 115.225294)
		(width 0.13)
		(layer "In4.Cu")
		(net 594)
	)
	(segment
		(start 159.150294 124.28)
		(end 158.85 124.28)
		(width 0.13)
		(layer "In4.Cu")
		(net 594)
	)
	(segment
		(start 180.1 139.8)
		(end 180.1 138.584083)
		(width 0.1)
		(layer "In4.Cu")
		(net 594)
	)
	(segment
		(start 180.225 140.175)
		(end 180.235472 140.175)
		(width 0.1)
		(layer "In4.Cu")
		(net 594)
	)
	(segment
		(start 139.145 115.225294)
		(end 139.145 112.055)
		(width 0.13)
		(layer "In4.Cu")
		(net 594)
	)
	(arc
		(start 150.45 122.766249)
		(mid 149.940883 122.977132)
		(end 149.73 123.486249)
		(width 0.13)
		(layer "In4.Cu")
		(net 594)
	)
	(arc
		(start 156.45 124.28)
		(mid 156.110589 124.139411)
		(end 155.97 123.8)
		(width 0.13)
		(layer "In4.Cu")
		(net 594)
	)
	(arc
		(start 180.235472 140.175)
		(mid 180.32386 140.138388)
		(end 180.360472 140.05)
		(width 0.1)
		(layer "In4.Cu")
		(net 594)
	)
	(arc
		(start 153.57 123.48625)
		(mid 153.359117 122.977133)
		(end 152.85 122.76625)
		(width 0.13)
		(layer "In4.Cu")
		(net 594)
	)
	(arc
		(start 149.73 123.8)
		(mid 149.589411 124.139411)
		(end 149.25 124.28)
		(width 0.13)
		(layer "In4.Cu")
		(net 594)
	)
	(arc
		(start 156.93 123.8)
		(mid 156.789411 124.139411)
		(end 156.45 124.28)
		(width 0.13)
		(layer "In4.Cu")
		(net 594)
	)
	(arc
		(start 155.97 123.486252)
		(mid 155.759117 122.977135)
		(end 155.25 122.766252)
		(width 0.13)
		(layer "In4.Cu")
		(net 594)
	)
	(arc
		(start 154.53 123.8)
		(mid 154.389411 124.139411)
		(end 154.05 124.28)
		(width 0.13)
		(layer "In4.Cu")
		(net 594)
	)
	(arc
		(start 180.360472 140.05)
		(mid 180.32386 139.961612)
		(end 180.235472 139.925)
		(width 0.1)
		(layer "In4.Cu")
		(net 594)
	)
	(arc
		(start 157.65 122.766254)
		(mid 157.140883 122.977137)
		(end 156.93 123.486254)
		(width 0.13)
		(layer "In4.Cu")
		(net 594)
	)
	(arc
		(start 158.37 123.486254)
		(mid 158.159117 122.977137)
		(end 157.65 122.766254)
		(width 0.13)
		(layer "In4.Cu")
		(net 594)
	)
	(arc
		(start 152.13 123.8)
		(mid 151.989411 124.139411)
		(end 151.65 124.28)
		(width 0.13)
		(layer "In4.Cu")
		(net 594)
	)
	(arc
		(start 180.1 140.3)
		(mid 180.136612 140.211612)
		(end 180.225 140.175)
		(width 0.1)
		(layer "In4.Cu")
		(net 594)
	)
	(arc
		(start 180.225 139.925)
		(mid 180.136612 139.888388)
		(end 180.1 139.8)
		(width 0.1)
		(layer "In4.Cu")
		(net 594)
	)
	(arc
		(start 151.65 124.28)
		(mid 151.310589 124.139411)
		(end 151.17 123.8)
		(width 0.13)
		(layer "In4.Cu")
		(net 594)
	)
	(arc
		(start 155.25 122.766252)
		(mid 154.740883 122.977135)
		(end 154.53 123.486252)
		(width 0.13)
		(layer "In4.Cu")
		(net 594)
	)
	(arc
		(start 151.17 123.486249)
		(mid 150.959117 122.977132)
		(end 150.45 122.766249)
		(width 0.13)
		(layer "In4.Cu")
		(net 594)
	)
	(arc
		(start 158.85 124.28)
		(mid 158.510589 124.139411)
		(end 158.37 123.8)
		(width 0.13)
		(layer "In4.Cu")
		(net 594)
	)
	(arc
		(start 154.05 124.28)
		(mid 153.710589 124.139411)
		(end 153.57 123.8)
		(width 0.13)
		(layer "In4.Cu")
		(net 594)
	)
	(arc
		(start 152.85 122.76625)
		(mid 152.340883 122.977133)
		(end 152.13 123.48625)
		(width 0.13)
		(layer "In4.Cu")
		(net 594)
	)
	(segment
		(start 180.9995 141.999501)
		(end 180.5 141.5)
		(width 0.256)
		(layer "F.Cu")
		(net 595)
	)
	(segment
		(start 138.6 110.598)
		(end 138.6 111.75)
		(width 0.38)
		(layer "F.Cu")
		(net 595)
	)
	(via
		(at 180.5 141.5)
		(size 0.45)
		(drill 0.1)
		(layers "F.Cu" "B.Cu")
		(remove_unused_layers yes)
		(keep_end_layers yes)
		(zone_layer_connections)
		(net 595)
	)
	(via
		(at 138.6 111.75)
		(size 0.45)
		(drill 0.1)
		(layers "F.Cu" "B.Cu")
		(remove_unused_layers yes)
		(keep_end_layers yes)
		(zone_layer_connections)
		(net 595)
	)
	(segment
		(start 179.874848 138.569235)
		(end 179.874848 133.354554)
		(width 0.13)
		(layer "In4.Cu")
		(net 595)
	)
	(segment
		(start 149.25 124.52)
		(end 148.813092 124.52)
		(width 0.13)
		(layer "In4.Cu")
		(net 595)
	)
	(segment
		(start 138.905 112.005)
		(end 138.65 111.75)
		(width 0.13)
		(layer "In4.Cu")
		(net 595)
	)
	(segment
		(start 180.425 141.1)
		(end 180.115543 141.1)
		(width 0.1)
		(layer "In4.Cu")
		(net 595)
	)
	(segment
		(start 157.17 123.486254)
		(end 157.17 123.8)
		(width 0.13)
		(layer "In4.Cu")
		(net 595)
	)
	(segment
		(start 138.905 115.324706)
		(end 138.905 112.005)
		(width 0.13)
		(layer "In4.Cu")
		(net 595)
	)
	(segment
		(start 179.874848 133.354554)
		(end 168.970294 122.45)
		(width 0.13)
		(layer "In4.Cu")
		(net 595)
	)
	(segment
		(start 148.813092 124.52)
		(end 148.100294 124.52)
		(width 0.13)
		(layer "In4.Cu")
		(net 595)
	)
	(segment
		(start 153.33 123.8)
		(end 153.33 123.48625)
		(width 0.13)
		(layer "In4.Cu")
		(net 595)
	)
	(segment
		(start 149.97 123.486249)
		(end 149.97 123.8)
		(width 0.13)
		(layer "In4.Cu")
		(net 595)
	)
	(segment
		(start 158.13 123.8)
		(end 158.13 123.486254)
		(width 0.13)
		(layer "In4.Cu")
		(net 595)
	)
	(segment
		(start 179.9 140.884457)
		(end 179.9 138.594387)
		(width 0.1)
		(layer "In4.Cu")
		(net 595)
	)
	(segment
		(start 148.100294 124.52)
		(end 138.905 115.324706)
		(width 0.13)
		(layer "In4.Cu")
		(net 595)
	)
	(segment
		(start 150.93 123.8)
		(end 150.93 123.486249)
		(width 0.13)
		(layer "In4.Cu")
		(net 595)
	)
	(segment
		(start 159.249706 124.52)
		(end 158.85 124.52)
		(width 0.13)
		(layer "In4.Cu")
		(net 595)
	)
	(segment
		(start 152.37 123.48625)
		(end 152.37 123.8)
		(width 0.13)
		(layer "In4.Cu")
		(net 595)
	)
	(segment
		(start 180.115543 141.1)
		(end 179.9 140.884457)
		(width 0.1)
		(layer "In4.Cu")
		(net 595)
	)
	(segment
		(start 179.9 138.594387)
		(end 179.874848 138.569235)
		(width 0.1)
		(layer "In4.Cu")
		(net 595)
	)
	(segment
		(start 155.73 123.8)
		(end 155.73 123.486252)
		(width 0.13)
		(layer "In4.Cu")
		(net 595)
	)
	(segment
		(start 168.970294 122.45)
		(end 161.319706 122.45)
		(width 0.13)
		(layer "In4.Cu")
		(net 595)
	)
	(segment
		(start 180.5 141.5)
		(end 180.5 141.175)
		(width 0.1)
		(layer "In4.Cu")
		(net 595)
	)
	(segment
		(start 180.5 141.175)
		(end 180.425 141.1)
		(width 0.1)
		(layer "In4.Cu")
		(net 595)
	)
	(segment
		(start 161.319706 122.45)
		(end 159.249706 124.52)
		(width 0.13)
		(layer "In4.Cu")
		(net 595)
	)
	(segment
		(start 154.77 123.486252)
		(end 154.77 123.8)
		(width 0.13)
		(layer "In4.Cu")
		(net 595)
	)
	(segment
		(start 138.65 111.75)
		(end 138.6 111.75)
		(width 0.13)
		(layer "In4.Cu")
		(net 595)
	)
	(arc
		(start 151.65 124.52)
		(mid 151.140883 124.309117)
		(end 150.93 123.8)
		(width 0.13)
		(layer "In4.Cu")
		(net 595)
	)
	(arc
		(start 154.77 123.8)
		(mid 154.559117 124.309117)
		(end 154.05 124.52)
		(width 0.13)
		(layer "In4.Cu")
		(net 595)
	)
	(arc
		(start 154.05 124.52)
		(mid 153.540883 124.309117)
		(end 153.33 123.8)
		(width 0.13)
		(layer "In4.Cu")
		(net 595)
	)
	(arc
		(start 155.73 123.486252)
		(mid 155.589411 123.146841)
		(end 155.25 123.006252)
		(width 0.13)
		(layer "In4.Cu")
		(net 595)
	)
	(arc
		(start 157.65 123.006254)
		(mid 157.310589 123.146843)
		(end 157.17 123.486254)
		(width 0.13)
		(layer "In4.Cu")
		(net 595)
	)
	(arc
		(start 152.37 123.8)
		(mid 152.159117 124.309117)
		(end 151.65 124.52)
		(width 0.13)
		(layer "In4.Cu")
		(net 595)
	)
	(arc
		(start 153.33 123.48625)
		(mid 153.189411 123.146839)
		(end 152.85 123.00625)
		(width 0.13)
		(layer "In4.Cu")
		(net 595)
	)
	(arc
		(start 155.25 123.006252)
		(mid 154.910589 123.146841)
		(end 154.77 123.486252)
		(width 0.13)
		(layer "In4.Cu")
		(net 595)
	)
	(arc
		(start 158.13 123.486254)
		(mid 157.989411 123.146843)
		(end 157.65 123.006254)
		(width 0.13)
		(layer "In4.Cu")
		(net 595)
	)
	(arc
		(start 152.85 123.00625)
		(mid 152.510589 123.146839)
		(end 152.37 123.48625)
		(width 0.13)
		(layer "In4.Cu")
		(net 595)
	)
	(arc
		(start 150.45 123.006249)
		(mid 150.110589 123.146838)
		(end 149.97 123.486249)
		(width 0.13)
		(layer "In4.Cu")
		(net 595)
	)
	(arc
		(start 150.93 123.486249)
		(mid 150.789411 123.146838)
		(end 150.45 123.006249)
		(width 0.13)
		(layer "In4.Cu")
		(net 595)
	)
	(arc
		(start 158.85 124.52)
		(mid 158.340883 124.309117)
		(end 158.13 123.8)
		(width 0.13)
		(layer "In4.Cu")
		(net 595)
	)
	(arc
		(start 157.17 123.8)
		(mid 156.959117 124.309117)
		(end 156.45 124.52)
		(width 0.13)
		(layer "In4.Cu")
		(net 595)
	)
	(arc
		(start 149.97 123.8)
		(mid 149.759117 124.309117)
		(end 149.25 124.52)
		(width 0.13)
		(layer "In4.Cu")
		(net 595)
	)
	(arc
		(start 156.45 124.52)
		(mid 155.940883 124.309117)
		(end 155.73 123.8)
		(width 0.13)
		(layer "In4.Cu")
		(net 595)
	)
	(segment
		(start 130.1 110.598)
		(end 130.1 111.75)
		(width 0.38)
		(layer "F.Cu")
		(net 596)
	)
	(segment
		(start 177.9995 141.9995)
		(end 177.5 141.5)
		(width 0.256)
		(layer "F.Cu")
		(net 596)
	)
	(via
		(at 177.5 141.5)
		(size 0.45)
		(drill 0.1)
		(layers "F.Cu" "B.Cu")
		(remove_unused_layers yes)
		(keep_end_layers yes)
		(zone_layer_connections)
		(net 596)
	)
	(via
		(at 130.1 111.75)
		(size 0.45)
		(drill 0.1)
		(layers "F.Cu" "B.Cu")
		(remove_unused_layers yes)
		(keep_end_layers yes)
		(zone_layer_connections)
		(net 596)
	)
	(segment
		(start 150.312737 132.673887)
		(end 151.02646 133.38761)
		(width 0.13)
		(layer "In2.Cu")
		(net 596)
	)
	(segment
		(start 178.895325 139.15147)
		(end 178.9 139.156145)
		(width 0.1)
		(layer "In2.Cu")
		(net 596)
	)
	(segment
		(start 130.333449 113.44655)
		(end 130.333449 113.55)
		(width 0.13)
		(layer "In2.Cu")
		(net 596)
	)
	(segment
		(start 151.026459 133.812329)
		(end 151.026461 133.81233)
		(width 0.13)
		(layer "In2.Cu")
		(net 596)
	)
	(segment
		(start 178.208578 139.9)
		(end 177.875 140.233578)
		(width 0.1)
		(layer "In2.Cu")
		(net 596)
	)
	(segment
		(start 147.6964 130.057591)
		(end 148.410144 130.771335)
		(width 0.13)
		(layer "In2.Cu")
		(net 596)
	)
	(segment
		(start 177.65 142)
		(end 177.5 141.85)
		(width 0.1)
		(layer "In2.Cu")
		(net 596)
	)
	(segment
		(start 145.793874 128.579738)
		(end 145.793875 128.579737)
		(width 0.13)
		(layer "In2.Cu")
		(net 596)
	)
	(segment
		(start 130.68 111.149706)
		(end 130.68 112.2)
		(width 0.13)
		(layer "In2.Cu")
		(net 596)
	)
	(segment
		(start 177.75 142)
		(end 177.65 142)
		(width 0.1)
		(layer "In2.Cu")
		(net 596)
	)
	(segment
		(start 178.895325 139.077414)
		(end 178.895325 139.15147)
		(width 0.1)
		(layer "In2.Cu")
		(net 596)
	)
	(segment
		(start 129.920158 110.912462)
		(end 130.442756 110.912462)
		(width 0.13)
		(layer "In2.Cu")
		(net 596)
	)
	(segment
		(start 150.312736 132.673886)
		(end 150.312737 132.673887)
		(width 0.13)
		(layer "In2.Cu")
		(net 596)
	)
	(segment
		(start 130.1 111.75)
		(end 129.795 111.445)
		(width 0.13)
		(layer "In2.Cu")
		(net 596)
	)
	(segment
		(start 154.850294 138.57)
		(end 178.550294 138.57)
		(width 0.13)
		(layer "In2.Cu")
		(net 596)
	)
	(segment
		(start 129.795 111.445)
		(end 129.795 111.03762)
		(width 0.13)
		(layer "In2.Cu")
		(net 596)
	)
	(segment
		(start 149.803166 132.758741)
		(end 149.888017 132.673887)
		(width 0.13)
		(layer "In2.Cu")
		(net 596)
	)
	(segment
		(start 147.186848 130.142445)
		(end 147.186848 130.142444)
		(width 0.13)
		(layer "In2.Cu")
		(net 596)
	)
	(segment
		(start 145.080159 127.441295)
		(end 145.793875 128.155011)
		(width 0.13)
		(layer "In2.Cu")
		(net 596)
	)
	(segment
		(start 144.570582 127.526149)
		(end 144.57058 127.526148)
		(width 0.13)
		(layer "In2.Cu")
		(net 596)
	)
	(segment
		(start 141.954324 124.909852)
		(end 142.039178 124.824999)
		(width 0.13)
		(layer "In2.Cu")
		(net 596)
	)
	(segment
		(start 142.463944 124.824999)
		(end 143.17762 125.538675)
		(width 0.13)
		(layer "In2.Cu")
		(net 596)
	)
	(segment
		(start 130.68 113.89655)
		(end 130.68 114)
		(width 0.13)
		(layer "In2.Cu")
		(net 596)
	)
	(segment
		(start 143.092766 126.812471)
		(end 143.806442 127.526147)
		(width 0.13)
		(layer "In2.Cu")
		(net 596)
	)
	(segment
		(start 149.039035 132.75874)
		(end 149.039034 132.758739)
		(width 0.13)
		(layer "In2.Cu")
		(net 596)
	)
	(segment
		(start 178.880325 138.900031)
		(end 178.880325 139.062414)
		(width 0.13)
		(layer "In2.Cu")
		(net 596)
	)
	(segment
		(start 141.954324 124.909853)
		(end 141.954324 124.909852)
		(width 0.13)
		(layer "In2.Cu")
		(net 596)
	)
	(segment
		(start 130.506724 113.723275)
		(end 130.506725 113.723275)
		(width 0.13)
		(layer "In2.Cu")
		(net 596)
	)
	(segment
		(start 130.68 112.996454)
		(end 130.68 113.1)
		(width 0.13)
		(layer "In2.Cu")
		(net 596)
	)
	(segment
		(start 133.250294 117.77)
		(end 134.050294 117.77)
		(width 0.13)
		(layer "In2.Cu")
		(net 596)
	)
	(segment
		(start 143.092765 126.812471)
		(end 143.092766 126.812471)
		(width 0.13)
		(layer "In2.Cu")
		(net 596)
	)
	(segment
		(start 130.442756 110.912462)
		(end 130.68 111.149706)
		(width 0.13)
		(layer "In2.Cu")
		(net 596)
	)
	(segment
		(start 178.658578 139.9)
		(end 178.208578 139.9)
		(width 0.1)
		(layer "In2.Cu")
		(net 596)
	)
	(segment
		(start 143.17762 125.963441)
		(end 143.092765 126.048293)
		(width 0.13)
		(layer "In2.Cu")
		(net 596)
	)
	(segment
		(start 145.793875 128.579737)
		(end 145.709023 128.66459)
		(width 0.13)
		(layer "In2.Cu")
		(net 596)
	)
	(segment
		(start 177.875 140.233578)
		(end 177.875 141.875)
		(width 0.1)
		(layer "In2.Cu")
		(net 596)
	)
	(segment
		(start 130.506725 113.273275)
		(end 130.506724 113.273275)
		(width 0.13)
		(layer "In2.Cu")
		(net 596)
	)
	(segment
		(start 177.5 141.85)
		(end 177.5 141.5)
		(width 0.1)
		(layer "In2.Cu")
		(net 596)
	)
	(segment
		(start 144.57058 127.526148)
		(end 144.655433 127.441296)
		(width 0.13)
		(layer "In2.Cu")
		(net 596)
	)
	(segment
		(start 130.68 115.199706)
		(end 133.250294 117.77)
		(width 0.13)
		(layer "In2.Cu")
		(net 596)
	)
	(segment
		(start 148.325289 132.044995)
		(end 149.039035 132.75874)
		(width 0.13)
		(layer "In2.Cu")
		(net 596)
	)
	(segment
		(start 148.410144 131.196033)
		(end 148.325289 131.280885)
		(width 0.13)
		(layer "In2.Cu")
		(net 596)
	)
	(segment
		(start 177.875 141.875)
		(end 177.75 142)
		(width 0.1)
		(layer "In2.Cu")
		(net 596)
	)
	(segment
		(start 130.333546 112.546454)
		(end 130.333546 112.65)
		(width 0.13)
		(layer "In2.Cu")
		(net 596)
	)
	(segment
		(start 129.795 111.03762)
		(end 129.920158 110.912462)
		(width 0.13)
		(layer "In2.Cu")
		(net 596)
	)
	(segment
		(start 147.186848 130.142444)
		(end 147.271702 130.057591)
		(width 0.13)
		(layer "In2.Cu")
		(net 596)
	)
	(segment
		(start 145.709023 129.428728)
		(end 146.422739 130.142444)
		(width 0.13)
		(layer "In2.Cu")
		(net 596)
	)
	(segment
		(start 145.08016 127.441295)
		(end 145.080159 127.441295)
		(width 0.13)
		(layer "In2.Cu")
		(net 596)
	)
	(segment
		(start 178.9 139.156145)
		(end 178.9 139.658578)
		(width 0.1)
		(layer "In2.Cu")
		(net 596)
	)
	(segment
		(start 151.026461 133.81233)
		(end 150.941607 133.897181)
		(width 0.13)
		(layer "In2.Cu")
		(net 596)
	)
	(segment
		(start 130.68 114)
		(end 130.68 115.199706)
		(width 0.13)
		(layer "In2.Cu")
		(net 596)
	)
	(segment
		(start 150.941608 134.661313)
		(end 154.850294 138.57)
		(width 0.13)
		(layer "In2.Cu")
		(net 596)
	)
	(segment
		(start 178.880325 139.062414)
		(end 178.895325 139.077414)
		(width 0.1)
		(layer "In2.Cu")
		(net 596)
	)
	(segment
		(start 146.422739 130.142444)
		(end 146.422738 130.142443)
		(width 0.13)
		(layer "In2.Cu")
		(net 596)
	)
	(segment
		(start 178.9 139.658578)
		(end 178.658578 139.9)
		(width 0.1)
		(layer "In2.Cu")
		(net 596)
	)
	(segment
		(start 134.050294 117.77)
		(end 141.190146 124.909851)
		(width 0.13)
		(layer "In2.Cu")
		(net 596)
	)
	(segment
		(start 150.941606 134.661312)
		(end 150.941608 134.661313)
		(width 0.13)
		(layer "In2.Cu")
		(net 596)
	)
	(segment
		(start 178.550294 138.57)
		(end 178.880325 138.900031)
		(width 0.13)
		(layer "In2.Cu")
		(net 596)
	)
	(arc
		(start 147.271702 130.057591)
		(mid 147.48405 129.969632)
		(end 147.6964 130.057591)
		(width 0.13)
		(layer "In2.Cu")
		(net 596)
	)
	(arc
		(start 148.410144 130.771335)
		(mid 148.498101 130.983683)
		(end 148.410144 131.196033)
		(width 0.13)
		(layer "In2.Cu")
		(net 596)
	)
	(arc
		(start 150.941607 133.897181)
		(mid 150.78335 134.279246)
		(end 150.941606 134.661312)
		(width 0.13)
		(layer "In2.Cu")
		(net 596)
	)
	(arc
		(start 130.68 112.2)
		(mid 130.629263 112.32249)
		(end 130.506773 112.373227)
		(width 0.13)
		(layer "In2.Cu")
		(net 596)
	)
	(arc
		(start 143.17762 125.538675)
		(mid 143.265591 125.751057)
		(end 143.17762 125.963441)
		(width 0.13)
		(layer "In2.Cu")
		(net 596)
	)
	(arc
		(start 145.709023 128.66459)
		(mid 145.550764 129.046658)
		(end 145.709023 129.428728)
		(width 0.13)
		(layer "In2.Cu")
		(net 596)
	)
	(arc
		(start 130.333449 113.55)
		(mid 130.3842 113.672524)
		(end 130.506724 113.723275)
		(width 0.13)
		(layer "In2.Cu")
		(net 596)
	)
	(arc
		(start 146.422738 130.142443)
		(mid 146.804794 130.300697)
		(end 147.186848 130.142445)
		(width 0.13)
		(layer "In2.Cu")
		(net 596)
	)
	(arc
		(start 144.655433 127.441296)
		(mid 144.867795 127.353331)
		(end 145.08016 127.441295)
		(width 0.13)
		(layer "In2.Cu")
		(net 596)
	)
	(arc
		(start 130.68 113.1)
		(mid 130.629249 113.222524)
		(end 130.506725 113.273275)
		(width 0.13)
		(layer "In2.Cu")
		(net 596)
	)
	(arc
		(start 141.190146 124.909851)
		(mid 141.572236 125.068119)
		(end 141.954324 124.909853)
		(width 0.13)
		(layer "In2.Cu")
		(net 596)
	)
	(arc
		(start 130.506725 113.723275)
		(mid 130.629249 113.774026)
		(end 130.68 113.89655)
		(width 0.13)
		(layer "In2.Cu")
		(net 596)
	)
	(arc
		(start 145.793875 128.155011)
		(mid 145.881839 128.367376)
		(end 145.793874 128.579738)
		(width 0.13)
		(layer "In2.Cu")
		(net 596)
	)
	(arc
		(start 151.02646 133.38761)
		(mid 151.114422 133.59997)
		(end 151.026459 133.812329)
		(width 0.13)
		(layer "In2.Cu")
		(net 596)
	)
	(arc
		(start 130.333546 112.65)
		(mid 130.384283 112.77249)
		(end 130.506773 112.823227)
		(width 0.13)
		(layer "In2.Cu")
		(net 596)
	)
	(arc
		(start 130.506773 112.373227)
		(mid 130.384283 112.423964)
		(end 130.333546 112.546454)
		(width 0.13)
		(layer "In2.Cu")
		(net 596)
	)
	(arc
		(start 148.325289 131.280885)
		(mid 148.167038 131.662941)
		(end 148.325289 132.044995)
		(width 0.13)
		(layer "In2.Cu")
		(net 596)
	)
	(arc
		(start 130.506724 113.273275)
		(mid 130.3842 113.324026)
		(end 130.333449 113.44655)
		(width 0.13)
		(layer "In2.Cu")
		(net 596)
	)
	(arc
		(start 143.806442 127.526147)
		(mid 144.188512 127.684406)
		(end 144.570582 127.526149)
		(width 0.13)
		(layer "In2.Cu")
		(net 596)
	)
	(arc
		(start 149.888017 132.673887)
		(mid 150.100376 132.585924)
		(end 150.312736 132.673886)
		(width 0.13)
		(layer "In2.Cu")
		(net 596)
	)
	(arc
		(start 149.039034 132.758739)
		(mid 149.421101 132.916998)
		(end 149.803166 132.758741)
		(width 0.13)
		(layer "In2.Cu")
		(net 596)
	)
	(arc
		(start 142.039178 124.824999)
		(mid 142.25156 124.737026)
		(end 142.463944 124.824999)
		(width 0.13)
		(layer "In2.Cu")
		(net 596)
	)
	(arc
		(start 130.506773 112.823227)
		(mid 130.629263 112.873964)
		(end 130.68 112.996454)
		(width 0.13)
		(layer "In2.Cu")
		(net 596)
	)
	(arc
		(start 143.092765 126.048293)
		(mid 142.9345 126.430383)
		(end 143.092765 126.812471)
		(width 0.13)
		(layer "In2.Cu")
		(net 596)
	)
	(segment
		(start 178.9995 142.9995)
		(end 178.5 142.5)
		(width 0.256)
		(layer "F.Cu")
		(net 597)
	)
	(segment
		(start 129.25 110.598)
		(end 129.25 111.75)
		(width 0.38)
		(layer "F.Cu")
		(net 597)
	)
	(via
		(at 178.5 142.5)
		(size 0.45)
		(drill 0.1)
		(layers "F.Cu" "B.Cu")
		(remove_unused_layers yes)
		(keep_end_layers yes)
		(zone_layer_connections)
		(net 597)
	)
	(via
		(at 129.25 111.75)
		(size 0.45)
		(drill 0.1)
		(layers "F.Cu" "B.Cu")
		(remove_unused_layers yes)
		(keep_end_layers yes)
		(zone_layer_connections)
		(net 597)
	)
	(segment
		(start 129.820746 110.672462)
		(end 130.542168 110.672462)
		(width 0.13)
		(layer "In2.Cu")
		(net 597)
	)
	(segment
		(start 143.347324 126.133146)
		(end 143.262471 126.218)
		(width 0.13)
		(layer "In2.Cu")
		(net 597)
	)
	(segment
		(start 147.017143 129.972739)
		(end 147.101997 129.887886)
		(width 0.13)
		(layer "In2.Cu")
		(net 597)
	)
	(segment
		(start 144.400875 127.356443)
		(end 144.485728 127.271591)
		(width 0.13)
		(layer "In2.Cu")
		(net 597)
	)
	(segment
		(start 148.57985 131.365738)
		(end 148.494997 131.450592)
		(width 0.13)
		(layer "In2.Cu")
		(net 597)
	)
	(segment
		(start 154.949706 138.33)
		(end 178.649706 138.33)
		(width 0.13)
		(layer "In2.Cu")
		(net 597)
	)
	(segment
		(start 143.347325 126.133148)
		(end 143.347324 126.133146)
		(width 0.13)
		(layer "In2.Cu")
		(net 597)
	)
	(segment
		(start 143.976148 127.356443)
		(end 143.976147 127.356442)
		(width 0.13)
		(layer "In2.Cu")
		(net 597)
	)
	(segment
		(start 142.633649 124.655293)
		(end 142.633649 124.655294)
		(width 0.13)
		(layer "In2.Cu")
		(net 597)
	)
	(segment
		(start 145.963581 128.749443)
		(end 145.878729 128.834296)
		(width 0.13)
		(layer "In2.Cu")
		(net 597)
	)
	(segment
		(start 147.017143 129.97274)
		(end 147.017143 129.972739)
		(width 0.13)
		(layer "In2.Cu")
		(net 597)
	)
	(segment
		(start 151.111312 134.491606)
		(end 151.111313 134.491607)
		(width 0.13)
		(layer "In2.Cu")
		(net 597)
	)
	(segment
		(start 178.291422 140.1)
		(end 178.741422 140.1)
		(width 0.1)
		(layer "In2.Cu")
		(net 597)
	)
	(segment
		(start 133.349706 117.53)
		(end 134.149706 117.53)
		(width 0.13)
		(layer "In2.Cu")
		(net 597)
	)
	(segment
		(start 130.92 111.050294)
		(end 130.92 115.100294)
		(width 0.13)
		(layer "In2.Cu")
		(net 597)
	)
	(segment
		(start 150.482444 132.504183)
		(end 151.196167 133.217906)
		(width 0.13)
		(layer "In2.Cu")
		(net 597)
	)
	(segment
		(start 179.1 139.072739)
		(end 179.110325 139.062414)
		(width 0.1)
		(layer "In2.Cu")
		(net 597)
	)
	(segment
		(start 151.196166 133.982037)
		(end 151.196167 133.982036)
		(width 0.13)
		(layer "In2.Cu")
		(net 597)
	)
	(segment
		(start 129.555 110.938208)
		(end 129.820746 110.672462)
		(width 0.13)
		(layer "In2.Cu")
		(net 597)
	)
	(segment
		(start 178.5 142.5)
		(end 178.07498 142.07498)
		(width 0.1)
		(layer "In2.Cu")
		(net 597)
	)
	(segment
		(start 179.1 139.741422)
		(end 179.1 139.072739)
		(width 0.1)
		(layer "In2.Cu")
		(net 597)
	)
	(segment
		(start 147.866107 129.887886)
		(end 148.579851 130.60163)
		(width 0.13)
		(layer "In2.Cu")
		(net 597)
	)
	(segment
		(start 134.149706 117.53)
		(end 141.359851 124.740146)
		(width 0.13)
		(layer "In2.Cu")
		(net 597)
	)
	(segment
		(start 150.482443 132.504181)
		(end 150.482444 132.504183)
		(width 0.13)
		(layer "In2.Cu")
		(net 597)
	)
	(segment
		(start 143.262471 126.642766)
		(end 143.976148 127.356443)
		(width 0.13)
		(layer "In2.Cu")
		(net 597)
	)
	(segment
		(start 145.963581 128.749444)
		(end 145.963581 128.749443)
		(width 0.13)
		(layer "In2.Cu")
		(net 597)
	)
	(segment
		(start 178.07498 142.07498)
		(end 178.07498 140.316442)
		(width 0.1)
		(layer "In2.Cu")
		(net 597)
	)
	(segment
		(start 145.249866 127.271591)
		(end 145.963582 127.985307)
		(width 0.13)
		(layer "In2.Cu")
		(net 597)
	)
	(segment
		(start 129.25 111.75)
		(end 129.555 111.445)
		(width 0.13)
		(layer "In2.Cu")
		(net 597)
	)
	(segment
		(start 130.542168 110.672462)
		(end 130.92 111.050294)
		(width 0.13)
		(layer "In2.Cu")
		(net 597)
	)
	(segment
		(start 141.784619 124.740148)
		(end 141.869471 124.655293)
		(width 0.13)
		(layer "In2.Cu")
		(net 597)
	)
	(segment
		(start 148.494997 131.87529)
		(end 149.20874 132.589035)
		(width 0.13)
		(layer "In2.Cu")
		(net 597)
	)
	(segment
		(start 151.196167 133.982036)
		(end 151.111313 134.066887)
		(width 0.13)
		(layer "In2.Cu")
		(net 597)
	)
	(segment
		(start 129.555 111.445)
		(end 129.555 110.938208)
		(width 0.13)
		(layer "In2.Cu")
		(net 597)
	)
	(segment
		(start 149.633461 132.589036)
		(end 149.718312 132.504182)
		(width 0.13)
		(layer "In2.Cu")
		(net 597)
	)
	(segment
		(start 178.07498 140.316442)
		(end 178.291422 140.1)
		(width 0.1)
		(layer "In2.Cu")
		(net 597)
	)
	(segment
		(start 145.878728 129.259023)
		(end 145.878728 129.259022)
		(width 0.13)
		(layer "In2.Cu")
		(net 597)
	)
	(segment
		(start 145.878728 129.259022)
		(end 146.592443 129.972738)
		(width 0.13)
		(layer "In2.Cu")
		(net 597)
	)
	(segment
		(start 151.111313 134.491607)
		(end 154.949706 138.33)
		(width 0.13)
		(layer "In2.Cu")
		(net 597)
	)
	(segment
		(start 148.579851 131.36574)
		(end 148.57985 131.365738)
		(width 0.13)
		(layer "In2.Cu")
		(net 597)
	)
	(segment
		(start 144.400877 127.356444)
		(end 144.400875 127.356443)
		(width 0.13)
		(layer "In2.Cu")
		(net 597)
	)
	(segment
		(start 142.633649 124.655294)
		(end 143.347325 125.36897)
		(width 0.13)
		(layer "In2.Cu")
		(net 597)
	)
	(segment
		(start 178.741422 140.1)
		(end 179.1 139.741422)
		(width 0.1)
		(layer "In2.Cu")
		(net 597)
	)
	(segment
		(start 178.649706 138.33)
		(end 179.110325 138.790619)
		(width 0.13)
		(layer "In2.Cu")
		(net 597)
	)
	(segment
		(start 149.20874 132.589035)
		(end 149.208739 132.589034)
		(width 0.13)
		(layer "In2.Cu")
		(net 597)
	)
	(segment
		(start 179.110325 138.790619)
		(end 179.110325 139.062414)
		(width 0.13)
		(layer "In2.Cu")
		(net 597)
	)
	(segment
		(start 130.92 115.100294)
		(end 133.349706 117.53)
		(width 0.13)
		(layer "In2.Cu")
		(net 597)
	)
	(arc
		(start 151.111313 134.066887)
		(mid 151.02335 134.279246)
		(end 151.111312 134.491606)
		(width 0.13)
		(layer "In2.Cu")
		(net 597)
	)
	(arc
		(start 146.592443 129.972738)
		(mid 146.804793 130.060697)
		(end 147.017143 129.97274)
		(width 0.13)
		(layer "In2.Cu")
		(net 597)
	)
	(arc
		(start 143.976147 127.356442)
		(mid 144.188513 127.444408)
		(end 144.400877 127.356444)
		(width 0.13)
		(layer "In2.Cu")
		(net 597)
	)
	(arc
		(start 143.347325 125.36897)
		(mid 143.50559 125.751058)
		(end 143.347325 126.133148)
		(width 0.13)
		(layer "In2.Cu")
		(net 597)
	)
	(arc
		(start 145.878729 128.834296)
		(mid 145.790764 129.046658)
		(end 145.878728 129.259023)
		(width 0.13)
		(layer "In2.Cu")
		(net 597)
	)
	(arc
		(start 147.101997 129.887886)
		(mid 147.484051 129.729633)
		(end 147.866107 129.887886)
		(width 0.13)
		(layer "In2.Cu")
		(net 597)
	)
	(arc
		(start 141.869471 124.655293)
		(mid 142.251561 124.497028)
		(end 142.633649 124.655293)
		(width 0.13)
		(layer "In2.Cu")
		(net 597)
	)
	(arc
		(start 143.262471 126.218)
		(mid 143.174498 126.430382)
		(end 143.262471 126.642766)
		(width 0.13)
		(layer "In2.Cu")
		(net 597)
	)
	(arc
		(start 148.579851 130.60163)
		(mid 148.738102 130.983684)
		(end 148.579851 131.36574)
		(width 0.13)
		(layer "In2.Cu")
		(net 597)
	)
	(arc
		(start 148.494997 131.450592)
		(mid 148.407038 131.66294)
		(end 148.494997 131.87529)
		(width 0.13)
		(layer "In2.Cu")
		(net 597)
	)
	(arc
		(start 144.485728 127.271591)
		(mid 144.867796 127.113332)
		(end 145.249866 127.271591)
		(width 0.13)
		(layer "In2.Cu")
		(net 597)
	)
	(arc
		(start 141.359851 124.740146)
		(mid 141.572235 124.828119)
		(end 141.784619 124.740148)
		(width 0.13)
		(layer "In2.Cu")
		(net 597)
	)
	(arc
		(start 145.963582 127.985307)
		(mid 146.121839 128.367376)
		(end 145.963581 128.749444)
		(width 0.13)
		(layer "In2.Cu")
		(net 597)
	)
	(arc
		(start 149.208739 132.589034)
		(mid 149.421101 132.676998)
		(end 149.633461 132.589036)
		(width 0.13)
		(layer "In2.Cu")
		(net 597)
	)
	(arc
		(start 149.718312 132.504182)
		(mid 150.100377 132.345925)
		(end 150.482443 132.504181)
		(width 0.13)
		(layer "In2.Cu")
		(net 597)
	)
	(arc
		(start 151.196167 133.217906)
		(mid 151.354423 133.599972)
		(end 151.196166 133.982037)
		(width 0.13)
		(layer "In2.Cu")
		(net 597)
	)
	(segment
		(start 189.0005 153.0005)
		(end 189.5 153.5)
		(width 0.256)
		(layer "F.Cu")
		(net 598)
	)
	(via
		(at 189.5 153.5)
		(size 0.45)
		(drill 0.1)
		(layers "F.Cu" "B.Cu")
		(remove_unused_layers yes)
		(keep_end_layers yes)
		(zone_layer_connections)
		(net 598)
	)
	(segment
		(start 205.166422 151.075)
		(end 204.441422 151.8)
		(width 0.1)
		(layer "B.Cu")
		(net 598)
	)
	(segment
		(start 205.601749 151.15)
		(end 205.526749 151.075)
		(width 0.1)
		(layer "B.Cu")
		(net 598)
	)
	(segment
		(start 205.697 151.15)
		(end 205.601749 151.15)
		(width 0.1)
		(layer "B.Cu")
		(net 598)
	)
	(segment
		(start 202.041422 152.6)
		(end 190.4 152.6)
		(width 0.1)
		(layer "B.Cu")
		(net 598)
	)
	(segment
		(start 202.841422 151.8)
		(end 202.041422 152.6)
		(width 0.1)
		(layer "B.Cu")
		(net 598)
	)
	(segment
		(start 190 153)
		(end 189.5 153.5)
		(width 0.256)
		(layer "B.Cu")
		(net 598)
	)
	(segment
		(start 205.526749 151.075)
		(end 205.166422 151.075)
		(width 0.1)
		(layer "B.Cu")
		(net 598)
	)
	(segment
		(start 204.441422 151.8)
		(end 202.841422 151.8)
		(width 0.1)
		(layer "B.Cu")
		(net 598)
	)
	(segment
		(start 190.4 152.6)
		(end 190 153)
		(width 0.1)
		(layer "B.Cu")
		(net 598)
	)
	(segment
		(start 190.000499 151.9995)
		(end 190.5 151.5)
		(width 0.256)
		(layer "F.Cu")
		(net 599)
	)
	(via
		(at 190.5 151.5)
		(size 0.45)
		(drill 0.1)
		(layers "F.Cu" "B.Cu")
		(remove_unused_layers yes)
		(keep_end_layers yes)
		(zone_layer_connections)
		(net 599)
	)
	(segment
		(start 190 152.002)
		(end 190 152)
		(width 0.256)
		(layer "B.Cu")
		(net 599)
	)
	(segment
		(start 205.526749 150.875)
		(end 205.083578 150.875)
		(width 0.1)
		(layer "B.Cu")
		(net 599)
	)
	(segment
		(start 190.398 152.4)
		(end 190 152.002)
		(width 0.1)
		(layer "B.Cu")
		(net 599)
	)
	(segment
		(start 205.083578 150.875)
		(end 204.358578 151.6)
		(width 0.1)
		(layer "B.Cu")
		(net 599)
	)
	(segment
		(start 205.601749 150.8)
		(end 205.526749 150.875)
		(width 0.1)
		(layer "B.Cu")
		(net 599)
	)
	(segment
		(start 190 152)
		(end 190.5 151.5)
		(width 0.256)
		(layer "B.Cu")
		(net 599)
	)
	(segment
		(start 205.697 150.8)
		(end 205.601749 150.8)
		(width 0.1)
		(layer "B.Cu")
		(net 599)
	)
	(segment
		(start 202.758578 151.6)
		(end 201.958578 152.4)
		(width 0.1)
		(layer "B.Cu")
		(net 599)
	)
	(segment
		(start 201.958578 152.4)
		(end 190.398 152.4)
		(width 0.1)
		(layer "B.Cu")
		(net 599)
	)
	(segment
		(start 204.358578 151.6)
		(end 202.758578 151.6)
		(width 0.1)
		(layer "B.Cu")
		(net 599)
	)
	(segment
		(start 187 144)
		(end 186.5005 143.5005)
		(width 0.256)
		(layer "F.Cu")
		(net 600)
	)
	(via
		(at 186.5005 143.5005)
		(size 0.45)
		(drill 0.1)
		(layers "F.Cu" "B.Cu")
		(remove_unused_layers yes)
		(keep_end_layers yes)
		(zone_layer_connections)
		(net 600)
	)
	(segment
		(start 186.4995 143.5005)
		(end 186 144)
		(width 0.256)
		(layer "B.Cu")
		(net 600)
	)
	(segment
		(start 186.5005 143.5005)
		(end 186.4995 143.5005)
		(width 0.256)
		(layer "B.Cu")
		(net 600)
	)
	(segment
		(start 180.9995 148.9995)
		(end 180.5 148.5)
		(width 0.256)
		(layer "F.Cu")
		(net 601)
	)
	(via
		(at 180.5 148.5)
		(size 0.45)
		(drill 0.1)
		(layers "F.Cu" "B.Cu")
		(remove_unused_layers yes)
		(keep_end_layers yes)
		(zone_layer_connections)
		(net 601)
	)
	(segment
		(start 180 149)
		(end 180.5 148.5)
		(width 0.256)
		(layer "B.Cu")
		(net 601)
	)
	(segment
		(start 211.525 139)
		(end 210.9 139)
		(width 0.198)
		(layer "F.Cu")
		(net 602)
	)
	(segment
		(start 187.9995 139.9995)
		(end 187.5 139.499999)
		(width 0.256)
		(layer "F.Cu")
		(net 602)
	)
	(segment
		(start 209.5 137.6)
		(end 189.399999 137.6)
		(width 0.198)
		(layer "F.Cu")
		(net 602)
	)
	(segment
		(start 189.399999 137.6)
		(end 187.5 139.499999)
		(width 0.198)
		(layer "F.Cu")
		(net 602)
	)
	(segment
		(start 210.9 139)
		(end 209.5 137.6)
		(width 0.198)
		(layer "F.Cu")
		(net 602)
	)
	(segment
		(start 249.95 110.598)
		(end 249.95 109.446)
		(width 0.38)
		(layer "F.Cu")
		(net 602)
	)
	(via
		(at 249.95 109.446)
		(size 0.45)
		(drill 0.1)
		(layers "F.Cu" "B.Cu")
		(remove_unused_layers yes)
		(keep_end_layers yes)
		(zone_layer_connections)
		(net 602)
	)
	(via
		(at 211.525 139)
		(size 0.45)
		(drill 0.1)
		(layers "F.Cu" "B.Cu")
		(remove_unused_layers yes)
		(keep_end_layers yes)
		(zone_layer_connections)
		(net 602)
	)
	(via
		(at 187.5 139.499999)
		(size 0.45)
		(drill 0.1)
		(layers "F.Cu" "B.Cu")
		(remove_unused_layers yes)
		(keep_end_layers yes)
		(zone_layer_connections)
		(net 602)
	)
	(segment
		(start 212.95 139)
		(end 234.375 117.575)
		(width 0.1)
		(layer "In6.Cu")
		(net 602)
	)
	(segment
		(start 247.925 114.175)
		(end 247.925 111.925)
		(width 0.1)
		(layer "In6.Cu")
		(net 602)
	)
	(segment
		(start 234.375 117.575)
		(end 244.525 117.575)
		(width 0.1)
		(layer "In6.Cu")
		(net 602)
	)
	(segment
		(start 244.525 117.575)
		(end 247.925 114.175)
		(width 0.1)
		(layer "In6.Cu")
		(net 602)
	)
	(segment
		(start 247.925 111.925)
		(end 249.95 109.9)
		(width 0.1)
		(layer "In6.Cu")
		(net 602)
	)
	(segment
		(start 249.95 109.9)
		(end 249.95 109.446)
		(width 0.1)
		(layer "In6.Cu")
		(net 602)
	)
	(segment
		(start 211.525 139)
		(end 212.95 139)
		(width 0.1)
		(layer "In6.Cu")
		(net 602)
	)
	(segment
		(start 108.188 164.867)
		(end 108.189 164.866)
		(width 0.201)
		(layer "B.Cu")
		(net 604)
	)
	(segment
		(start 110.38 165.77)
		(end 110.38 166.47)
		(width 0.201)
		(layer "B.Cu")
		(net 604)
	)
	(segment
		(start 108.191 164.866)
		(end 109.476 164.866)
		(width 0.201)
		(layer "B.Cu")
		(net 604)
	)
	(segment
		(start 105.17 164.867)
		(end 108.188 164.867)
		(width 0.201)
		(layer "B.Cu")
		(net 604)
	)
	(segment
		(start 109.476 164.866)
		(end 110.38 165.77)
		(width 0.201)
		(layer "B.Cu")
		(net 604)
	)
	(segment
		(start 110.38 166.47)
		(end 111.33 166.47)
		(width 0.201)
		(layer "B.Cu")
		(net 604)
	)
	(segment
		(start 113.915499 174.867)
		(end 113.917499 174.869)
		(width 0.201)
		(layer "F.Cu")
		(net 605)
	)
	(segment
		(start 109.375 174.7685)
		(end 113.915499 174.7685)
		(width 0.201)
		(layer "F.Cu")
		(net 605)
	)
	(segment
		(start 114.599 174.869)
		(end 114.806 174.662)
		(width 0.201)
		(layer "F.Cu")
		(net 605)
	)
	(segment
		(start 113.917499 174.869)
		(end 114.599 174.869)
		(width 0.201)
		(layer "F.Cu")
		(net 605)
	)
	(segment
		(start 114.806 174.662)
		(end 114.806 173.802)
		(width 0.201)
		(layer "F.Cu")
		(net 605)
	)
	(segment
		(start 117.69 163.18)
		(end 113.23 163.18)
		(width 0.256)
		(layer "F.Cu")
		(net 606)
	)
	(segment
		(start 118.14 162.73)
		(end 117.69 163.18)
		(width 0.256)
		(layer "F.Cu")
		(net 606)
	)
	(segment
		(start 118.14 160.45)
		(end 118.14 161.09)
		(width 0.256)
		(layer "F.Cu")
		(net 606)
	)
	(segment
		(start 118.14 162.3883)
		(end 118.14 162.49)
		(width 0.256)
		(layer "F.Cu")
		(net 606)
	)
	(segment
		(start 119.2 159.998)
		(end 118.592 159.998)
		(width 0.256)
		(layer "F.Cu")
		(net 606)
	)
	(segment
		(start 118.14 162.49)
		(end 118.14 162.73)
		(width 0.256)
		(layer "F.Cu")
		(net 606)
	)
	(segment
		(start 118.7383 161.6883)
		(end 118.7383 161.79)
		(width 0.256)
		(layer "F.Cu")
		(net 606)
	)
	(segment
		(start 118.592 159.998)
		(end 118.14 160.45)
		(width 0.256)
		(layer "F.Cu")
		(net 606)
	)
	(segment
		(start 113.23 163.18)
		(end 113.164 163.114)
		(width 0.256)
		(layer "F.Cu")
		(net 606)
	)
	(arc
		(start 118.14 161.09)
		(mid 118.227619 161.301531)
		(end 118.43915 161.38915)
		(width 0.256)
		(layer "F.Cu")
		(net 606)
	)
	(arc
		(start 118.43915 161.38915)
		(mid 118.650681 161.476769)
		(end 118.7383 161.6883)
		(width 0.256)
		(layer "F.Cu")
		(net 606)
	)
	(arc
		(start 118.7383 161.79)
		(mid 118.650681 162.001531)
		(end 118.43915 162.08915)
		(width 0.256)
		(layer "F.Cu")
		(net 606)
	)
	(arc
		(start 118.43915 162.08915)
		(mid 118.227619 162.176769)
		(end 118.14 162.3883)
		(width 0.256)
		(layer "F.Cu")
		(net 606)
	)
	(segment
		(start 113.164 162.013)
		(end 113.341 162.19)
		(width 0.256)
		(layer "F.Cu")
		(net 607)
	)
	(segment
		(start 117.57 160.19)
		(end 118.16 159.6)
		(width 0.256)
		(layer "F.Cu")
		(net 607)
	)
	(segment
		(start 118.16 159.6)
		(end 119.2 159.6)
		(width 0.256)
		(layer "F.Cu")
		(net 607)
	)
	(segment
		(start 113.341 162.19)
		(end 114.27 162.19)
		(width 0.256)
		(layer "F.Cu")
		(net 607)
	)
	(segment
		(start 117.57 161.82)
		(end 117.57 160.19)
		(width 0.256)
		(layer "F.Cu")
		(net 607)
	)
	(segment
		(start 116.923234 162.19)
		(end 117.07 162.19)
		(width 0.256)
		(layer "F.Cu")
		(net 607)
	)
	(segment
		(start 114.823234 161.636766)
		(end 114.97 161.636766)
		(width 0.256)
		(layer "F.Cu")
		(net 607)
	)
	(segment
		(start 117.07 162.19)
		(end 117.2 162.19)
		(width 0.256)
		(layer "F.Cu")
		(net 607)
	)
	(segment
		(start 115.523234 162.19)
		(end 115.67 162.19)
		(width 0.256)
		(layer "F.Cu")
		(net 607)
	)
	(segment
		(start 116.223234 161.636766)
		(end 116.37 161.636766)
		(width 0.256)
		(layer "F.Cu")
		(net 607)
	)
	(segment
		(start 117.2 162.19)
		(end 117.57 161.82)
		(width 0.256)
		(layer "F.Cu")
		(net 607)
	)
	(arc
		(start 116.646617 161.913383)
		(mid 116.727636 162.108981)
		(end 116.923234 162.19)
		(width 0.256)
		(layer "F.Cu")
		(net 607)
	)
	(arc
		(start 115.67 162.19)
		(mid 115.865598 162.108981)
		(end 115.946617 161.913383)
		(width 0.256)
		(layer "F.Cu")
		(net 607)
	)
	(arc
		(start 114.27 162.19)
		(mid 114.465598 162.108981)
		(end 114.546617 161.913383)
		(width 0.256)
		(layer "F.Cu")
		(net 607)
	)
	(arc
		(start 114.97 161.636766)
		(mid 115.165598 161.717785)
		(end 115.246617 161.913383)
		(width 0.256)
		(layer "F.Cu")
		(net 607)
	)
	(arc
		(start 114.546617 161.913383)
		(mid 114.627636 161.717785)
		(end 114.823234 161.636766)
		(width 0.256)
		(layer "F.Cu")
		(net 607)
	)
	(arc
		(start 115.946617 161.913383)
		(mid 116.027636 161.717785)
		(end 116.223234 161.636766)
		(width 0.256)
		(layer "F.Cu")
		(net 607)
	)
	(arc
		(start 115.246617 161.913383)
		(mid 115.327636 162.108981)
		(end 115.523234 162.19)
		(width 0.256)
		(layer "F.Cu")
		(net 607)
	)
	(arc
		(start 116.37 161.636766)
		(mid 116.565598 161.717785)
		(end 116.646617 161.913383)
		(width 0.256)
		(layer "F.Cu")
		(net 607)
	)
	(segment
		(start 114.61 161.03)
		(end 115.05 160.59)
		(width 0.256)
		(layer "F.Cu")
		(net 608)
	)
	(segment
		(start 118.79432 160.59432)
		(end 119.20468 160.59432)
		(width 0.182)
		(layer "F.Cu")
		(net 608)
	)
	(segment
		(start 115.05 160.59)
		(end 117.06 160.59)
		(width 0.256)
		(layer "F.Cu")
		(net 608)
	)
	(segment
		(start 113.164 160.915)
		(end 113.279 161.03)
		(width 0.256)
		(layer "F.Cu")
		(net 608)
	)
	(segment
		(start 119.20468 160.59432)
		(end 119.225 160.574)
		(width 0.182)
		(layer "F.Cu")
		(net 608)
	)
	(segment
		(start 113.279 161.03)
		(end 114.61 161.03)
		(width 0.256)
		(layer "F.Cu")
		(net 608)
	)
	(via
		(at 117.06 160.59)
		(size 0.45)
		(drill 0.1)
		(layers "F.Cu" "B.Cu")
		(remove_unused_layers yes)
		(keep_end_layers yes)
		(zone_layer_connections)
		(net 608)
	)
	(via
		(at 118.79432 160.59432)
		(size 0.45)
		(drill 0.1)
		(layers "F.Cu" "B.Cu")
		(remove_unused_layers yes)
		(keep_end_layers yes)
		(zone_layer_connections)
		(net 608)
	)
	(segment
		(start 118.79 160.59)
		(end 117.06 160.59)
		(width 0.256)
		(layer "B.Cu")
		(net 608)
	)
	(segment
		(start 118.79432 160.59432)
		(end 118.79 160.59)
		(width 0.256)
		(layer "B.Cu")
		(net 608)
	)
	(segment
		(start 119.222 158.22)
		(end 119.225 158.223)
		(width 0.182)
		(layer "F.Cu")
		(net 609)
	)
	(segment
		(start 117.02 158.73)
		(end 113.179 158.73)
		(width 0.256)
		(layer "F.Cu")
		(net 609)
	)
	(segment
		(start 118.67733 158.17787)
		(end 118.71946 158.22)
		(width 0.182)
		(layer "F.Cu")
		(net 609)
	)
	(segment
		(start 118.71946 158.22)
		(end 119.222 158.22)
		(width 0.182)
		(layer "F.Cu")
		(net 609)
	)
	(segment
		(start 113.179 158.73)
		(end 113.164 158.715)
		(width 0.256)
		(layer "F.Cu")
		(net 609)
	)
	(via
		(at 118.67733 158.17787)
		(size 0.45)
		(drill 0.1)
		(layers "F.Cu" "B.Cu")
		(remove_unused_layers yes)
		(keep_end_layers yes)
		(zone_layer_connections)
		(net 609)
	)
	(via
		(at 117.02 158.73)
		(size 0.45)
		(drill 0.1)
		(layers "F.Cu" "B.Cu")
		(remove_unused_layers yes)
		(keep_end_layers yes)
		(zone_layer_connections)
		(net 609)
	)
	(segment
		(start 118.67733 158.17787)
		(end 118.1252 158.73)
		(width 0.182)
		(layer "B.Cu")
		(net 609)
	)
	(segment
		(start 118.1252 158.73)
		(end 117.02 158.73)
		(width 0.182)
		(layer "B.Cu")
		(net 609)
	)
	(segment
		(start 181.9995 148.9995)
		(end 181.5 148.5)
		(width 0.256)
		(layer "F.Cu")
		(net 610)
	)
	(segment
		(start 165.1 150.5)
		(end 164.6 151)
		(width 0.256)
		(layer "F.Cu")
		(net 610)
	)
	(via
		(at 164.6 151)
		(size 0.45)
		(drill 0.1)
		(layers "F.Cu" "B.Cu")
		(remove_unused_layers yes)
		(keep_end_layers yes)
		(zone_layer_connections)
		(net 610)
	)
	(via
		(at 181.5 148.5)
		(size 0.45)
		(drill 0.1)
		(layers "F.Cu" "B.Cu")
		(remove_unused_layers yes)
		(keep_end_layers yes)
		(zone_layer_connections)
		(net 610)
	)
	(segment
		(start 164.638748 149.65)
		(end 164.26 149.65)
		(width 0.1)
		(layer "In4.Cu")
		(net 610)
	)
	(segment
		(start 164.26 147.65)
		(end 164.488751 147.65)
		(width 0.1)
		(layer "In4.Cu")
		(net 610)
	)
	(segment
		(start 174.72 145.55)
		(end 175.17 146)
		(width 0.1)
		(layer "In4.Cu")
		(net 610)
	)
	(segment
		(start 164.26 150.05)
		(end 164.638748 150.05)
		(width 0.1)
		(layer "In4.Cu")
		(net 610)
	)
	(segment
		(start 180.2 148)
		(end 181 148)
		(width 0.1)
		(layer "In4.Cu")
		(net 610)
	)
	(segment
		(start 164.06 150.46)
		(end 164.06 150.25)
		(width 0.1)
		(layer "In4.Cu")
		(net 610)
	)
	(segment
		(start 181 148)
		(end 181.5 148.5)
		(width 0.1)
		(layer "In4.Cu")
		(net 610)
	)
	(segment
		(start 164.06 146.99)
		(end 165.5 145.55)
		(width 0.1)
		(layer "In4.Cu")
		(net 610)
	)
	(segment
		(start 164.26 148.45)
		(end 164.488743 148.45)
		(width 0.1)
		(layer "In4.Cu")
		(net 610)
	)
	(segment
		(start 164.788746 148.85)
		(end 164.26 148.85)
		(width 0.1)
		(layer "In4.Cu")
		(net 610)
	)
	(segment
		(start 164.488743 148.05)
		(end 164.26 148.05)
		(width 0.1)
		(layer "In4.Cu")
		(net 610)
	)
	(segment
		(start 164.6 151)
		(end 164.06 150.46)
		(width 0.1)
		(layer "In4.Cu")
		(net 610)
	)
	(segment
		(start 175.17 146)
		(end 179.7 146)
		(width 0.1)
		(layer "In4.Cu")
		(net 610)
	)
	(segment
		(start 164.06 147.05)
		(end 164.06 146.99)
		(width 0.1)
		(layer "In4.Cu")
		(net 610)
	)
	(segment
		(start 164.488751 147.25)
		(end 164.26 147.25)
		(width 0.1)
		(layer "In4.Cu")
		(net 610)
	)
	(segment
		(start 179.97 146.27)
		(end 179.97 147.77)
		(width 0.1)
		(layer "In4.Cu")
		(net 610)
	)
	(segment
		(start 179.97 147.77)
		(end 180.2 148)
		(width 0.1)
		(layer "In4.Cu")
		(net 610)
	)
	(segment
		(start 164.26 149.25)
		(end 164.788746 149.25)
		(width 0.1)
		(layer "In4.Cu")
		(net 610)
	)
	(segment
		(start 165.5 145.55)
		(end 174.72 145.55)
		(width 0.1)
		(layer "In4.Cu")
		(net 610)
	)
	(segment
		(start 179.7 146)
		(end 179.97 146.27)
		(width 0.1)
		(layer "In4.Cu")
		(net 610)
	)
	(arc
		(start 164.838748 149.85)
		(mid 164.780169 149.708579)
		(end 164.638748 149.65)
		(width 0.1)
		(layer "In4.Cu")
		(net 610)
	)
	(arc
		(start 164.06 148.65)
		(mid 164.118579 148.508579)
		(end 164.26 148.45)
		(width 0.1)
		(layer "In4.Cu")
		(net 610)
	)
	(arc
		(start 164.26 148.85)
		(mid 164.118579 148.791421)
		(end 164.06 148.65)
		(width 0.1)
		(layer "In4.Cu")
		(net 610)
	)
	(arc
		(start 164.06 147.85)
		(mid 164.118579 147.708579)
		(end 164.26 147.65)
		(width 0.1)
		(layer "In4.Cu")
		(net 610)
	)
	(arc
		(start 164.688743 148.25)
		(mid 164.630164 148.108579)
		(end 164.488743 148.05)
		(width 0.1)
		(layer "In4.Cu")
		(net 610)
	)
	(arc
		(start 164.06 150.25)
		(mid 164.118579 150.108579)
		(end 164.26 150.05)
		(width 0.1)
		(layer "In4.Cu")
		(net 610)
	)
	(arc
		(start 164.688751 147.45)
		(mid 164.630172 147.308579)
		(end 164.488751 147.25)
		(width 0.1)
		(layer "In4.Cu")
		(net 610)
	)
	(arc
		(start 164.488751 147.65)
		(mid 164.630172 147.591421)
		(end 164.688751 147.45)
		(width 0.1)
		(layer "In4.Cu")
		(net 610)
	)
	(arc
		(start 164.788746 149.25)
		(mid 164.930167 149.191421)
		(end 164.988746 149.05)
		(width 0.1)
		(layer "In4.Cu")
		(net 610)
	)
	(arc
		(start 164.988746 149.05)
		(mid 164.930167 148.908579)
		(end 164.788746 148.85)
		(width 0.1)
		(layer "In4.Cu")
		(net 610)
	)
	(arc
		(start 164.26 149.65)
		(mid 164.118579 149.591421)
		(end 164.06 149.45)
		(width 0.1)
		(layer "In4.Cu")
		(net 610)
	)
	(arc
		(start 164.26 148.05)
		(mid 164.118579 147.991421)
		(end 164.06 147.85)
		(width 0.1)
		(layer "In4.Cu")
		(net 610)
	)
	(arc
		(start 164.26 147.25)
		(mid 164.118579 147.191421)
		(end 164.06 147.05)
		(width 0.1)
		(layer "In4.Cu")
		(net 610)
	)
	(arc
		(start 164.488743 148.45)
		(mid 164.630164 148.391421)
		(end 164.688743 148.25)
		(width 0.1)
		(layer "In4.Cu")
		(net 610)
	)
	(arc
		(start 164.638748 150.05)
		(mid 164.780169 149.991421)
		(end 164.838748 149.85)
		(width 0.1)
		(layer "In4.Cu")
		(net 610)
	)
	(arc
		(start 164.06 149.45)
		(mid 164.118579 149.308579)
		(end 164.26 149.25)
		(width 0.1)
		(layer "In4.Cu")
		(net 610)
	)
	(segment
		(start 118.2 159.2)
		(end 118.202 159.198)
		(width 0.256)
		(layer "F.Cu")
		(net 611)
	)
	(segment
		(start 115.908202 158.061747)
		(end 115.908201 158.061746)
		(width 0.256)
		(layer "F.Cu")
		(net 611)
	)
	(segment
		(start 116.295 157.179974)
		(end 115.908201 157.566772)
		(width 0.256)
		(layer "F.Cu")
		(net 611)
	)
	(segment
		(start 117.284947 157.674947)
		(end 117.64 158.03)
		(width 0.256)
		(layer "F.Cu")
		(net 611)
	)
	(segment
		(start 117.284948 157.674948)
		(end 117.284947 157.674947)
		(width 0.256)
		(layer "F.Cu")
		(net 611)
	)
	(segment
		(start 116.294999 157.179975)
		(end 116.295 157.179974)
		(width 0.256)
		(layer "F.Cu")
		(net 611)
	)
	(segment
		(start 116.403175 158.061746)
		(end 116.789973 157.674947)
		(width 0.256)
		(layer "F.Cu")
		(net 611)
	)
	(segment
		(start 116.124 156.514)
		(end 116.295 156.685)
		(width 0.256)
		(layer "F.Cu")
		(net 611)
	)
	(segment
		(start 118.202 159.198)
		(end 119.2 159.198)
		(width 0.256)
		(layer "F.Cu")
		(net 611)
	)
	(segment
		(start 116.403176 158.061745)
		(end 116.403175 158.061746)
		(width 0.256)
		(layer "F.Cu")
		(net 611)
	)
	(segment
		(start 117.64 158.64)
		(end 118.2 159.2)
		(width 0.256)
		(layer "F.Cu")
		(net 611)
	)
	(segment
		(start 113.164 156.514)
		(end 116.124 156.514)
		(width 0.256)
		(layer "F.Cu")
		(net 611)
	)
	(segment
		(start 117.64 158.03)
		(end 117.64 158.64)
		(width 0.256)
		(layer "F.Cu")
		(net 611)
	)
	(arc
		(start 115.908201 158.061746)
		(mid 116.155689 158.164258)
		(end 116.403176 158.061745)
		(width 0.256)
		(layer "F.Cu")
		(net 611)
	)
	(arc
		(start 115.908201 157.566772)
		(mid 115.805689 157.81426)
		(end 115.908202 158.061747)
		(width 0.256)
		(layer "F.Cu")
		(net 611)
	)
	(arc
		(start 116.295 156.685)
		(mid 116.397512 156.932488)
		(end 116.294999 157.179975)
		(width 0.256)
		(layer "F.Cu")
		(net 611)
	)
	(arc
		(start 116.789973 157.674947)
		(mid 117.037461 157.572435)
		(end 117.284948 157.674948)
		(width 0.256)
		(layer "F.Cu")
		(net 611)
	)
	(segment
		(start 118.2 158.38)
		(end 118.2 157.383862)
		(width 0.256)
		(layer "F.Cu")
		(net 612)
	)
	(segment
		(start 119.2 158.8)
		(end 118.62 158.8)
		(width 0.256)
		(layer "F.Cu")
		(net 612)
	)
	(segment
		(start 114.78 155.413)
		(end 113.164 155.413)
		(width 0.256)
		(layer "F.Cu")
		(net 612)
	)
	(segment
		(start 118.2 157.383862)
		(end 116.229138 155.413)
		(width 0.256)
		(layer "F.Cu")
		(net 612)
	)
	(segment
		(start 115.105 154.758538)
		(end 115.105 155.088)
		(width 0.256)
		(layer "F.Cu")
		(net 612)
	)
	(segment
		(start 116.229138 155.413)
		(end 116.08 155.413)
		(width 0.256)
		(layer "F.Cu")
		(net 612)
	)
	(segment
		(start 115.755 155.088)
		(end 115.755 154.758538)
		(width 0.256)
		(layer "F.Cu")
		(net 612)
	)
	(segment
		(start 118.62 158.8)
		(end 118.2 158.38)
		(width 0.256)
		(layer "F.Cu")
		(net 612)
	)
	(arc
		(start 116.08 155.413)
		(mid 115.85019 155.31781)
		(end 115.755 155.088)
		(width 0.256)
		(layer "F.Cu")
		(net 612)
	)
	(arc
		(start 115.755 154.758538)
		(mid 115.65981 154.528728)
		(end 115.43 154.433538)
		(width 0.256)
		(layer "F.Cu")
		(net 612)
	)
	(arc
		(start 115.105 155.088)
		(mid 115.00981 155.31781)
		(end 114.78 155.413)
		(width 0.256)
		(layer "F.Cu")
		(net 612)
	)
	(arc
		(start 115.43 154.433538)
		(mid 115.20019 154.528728)
		(end 115.105 154.758538)
		(width 0.256)
		(layer "F.Cu")
		(net 612)
	)
	(segment
		(start 178.9995 150.9995)
		(end 178.5 150.5)
		(width 0.256)
		(layer "F.Cu")
		(net 613)
	)
	(segment
		(start 166.1 153.5)
		(end 165.599 154.001)
		(width 0.256)
		(layer "F.Cu")
		(net 613)
	)
	(via
		(at 165.599 154.001)
		(size 0.45)
		(drill 0.1)
		(layers "F.Cu" "B.Cu")
		(remove_unused_layers yes)
		(keep_end_layers yes)
		(zone_layer_connections)
		(net 613)
	)
	(via
		(at 178.5 150.5)
		(size 0.45)
		(drill 0.1)
		(layers "F.Cu" "B.Cu")
		(remove_unused_layers yes)
		(keep_end_layers yes)
		(zone_layer_connections)
		(net 613)
	)
	(segment
		(start 175.01 150.31)
		(end 172.84 148.14)
		(width 0.1)
		(layer "In4.Cu")
		(net 613)
	)
	(segment
		(start 167.29 153.01)
		(end 166.8 153.5)
		(width 0.1)
		(layer "In4.Cu")
		(net 613)
	)
	(segment
		(start 172.84 148.14)
		(end 172.16 148.14)
		(width 0.1)
		(layer "In4.Cu")
		(net 613)
	)
	(segment
		(start 171.26 148.14)
		(end 171.15 148.14)
		(width 0.1)
		(layer "In4.Cu")
		(net 613)
	)
	(segment
		(start 172.98 149.38)
		(end 173.34 149.38)
		(width 0.1)
		(layer "In4.Cu")
		(net 613)
	)
	(segment
		(start 171.79 149.38)
		(end 172.08 149.38)
		(width 0.1)
		(layer "In4.Cu")
		(net 613)
	)
	(segment
		(start 178.15 150.5)
		(end 177.67 150.98)
		(width 0.1)
		(layer "In4.Cu")
		(net 613)
	)
	(segment
		(start 171.15 148.14)
		(end 171.01 148.28)
		(width 0.1)
		(layer "In4.Cu")
		(net 613)
	)
	(segment
		(start 178.5 150.5)
		(end 178.15 150.5)
		(width 0.1)
		(layer "In4.Cu")
		(net 613)
	)
	(segment
		(start 171.54 150.13)
		(end 171.54 152.15)
		(width 0.1)
		(layer "In4.Cu")
		(net 613)
	)
	(segment
		(start 171.485 148.465)
		(end 171.485 148.365)
		(width 0.1)
		(layer "In4.Cu")
		(net 613)
	)
	(segment
		(start 171.54 152.15)
		(end 170.68 153.01)
		(width 0.1)
		(layer "In4.Cu")
		(net 613)
	)
	(segment
		(start 177.67 150.98)
		(end 175.31 150.98)
		(width 0.1)
		(layer "In4.Cu")
		(net 613)
	)
	(segment
		(start 172.305 149.155)
		(end 172.305 148.702725)
		(width 0.1)
		(layer "In4.Cu")
		(net 613)
	)
	(segment
		(start 165.881843 154.001)
		(end 165.599 154.001)
		(width 0.1)
		(layer "In4.Cu")
		(net 613)
	)
	(segment
		(start 166.382843 153.5)
		(end 165.881843 154.001)
		(width 0.1)
		(layer "In4.Cu")
		(net 613)
	)
	(segment
		(start 166.8 153.5)
		(end 166.382843 153.5)
		(width 0.1)
		(layer "In4.Cu")
		(net 613)
	)
	(segment
		(start 171.935 148.365)
		(end 171.935 148.465)
		(width 0.1)
		(layer "In4.Cu")
		(net 613)
	)
	(segment
		(start 175.31 150.98)
		(end 175.01 150.68)
		(width 0.1)
		(layer "In4.Cu")
		(net 613)
	)
	(segment
		(start 172.755 148.702725)
		(end 172.755 149.155)
		(width 0.1)
		(layer "In4.Cu")
		(net 613)
	)
	(segment
		(start 175.01 150.68)
		(end 175.01 150.31)
		(width 0.1)
		(layer "In4.Cu")
		(net 613)
	)
	(segment
		(start 171.01 148.6)
		(end 171.54 149.13)
		(width 0.1)
		(layer "In4.Cu")
		(net 613)
	)
	(segment
		(start 170.68 153.01)
		(end 167.29 153.01)
		(width 0.1)
		(layer "In4.Cu")
		(net 613)
	)
	(segment
		(start 171.01 148.28)
		(end 171.01 148.6)
		(width 0.1)
		(layer "In4.Cu")
		(net 613)
	)
	(segment
		(start 173.34 149.88)
		(end 171.79 149.88)
		(width 0.1)
		(layer "In4.Cu")
		(net 613)
	)
	(arc
		(start 172.08 149.38)
		(mid 172.239099 149.314099)
		(end 172.305 149.155)
		(width 0.1)
		(layer "In4.Cu")
		(net 613)
	)
	(arc
		(start 172.755 149.155)
		(mid 172.820901 149.314099)
		(end 172.98 149.38)
		(width 0.1)
		(layer "In4.Cu")
		(net 613)
	)
	(arc
		(start 173.59 149.63)
		(mid 173.516777 149.806777)
		(end 173.34 149.88)
		(width 0.1)
		(layer "In4.Cu")
		(net 613)
	)
	(arc
		(start 173.34 149.38)
		(mid 173.516777 149.453223)
		(end 173.59 149.63)
		(width 0.1)
		(layer "In4.Cu")
		(net 613)
	)
	(arc
		(start 171.935 148.465)
		(mid 171.869099 148.624099)
		(end 171.71 148.69)
		(width 0.1)
		(layer "In4.Cu")
		(net 613)
	)
	(arc
		(start 172.53 148.477725)
		(mid 172.689099 148.543626)
		(end 172.755 148.702725)
		(width 0.1)
		(layer "In4.Cu")
		(net 613)
	)
	(arc
		(start 171.79 149.88)
		(mid 171.613223 149.953223)
		(end 171.54 150.13)
		(width 0.1)
		(layer "In4.Cu")
		(net 613)
	)
	(arc
		(start 172.305 148.702725)
		(mid 172.370901 148.543626)
		(end 172.53 148.477725)
		(width 0.1)
		(layer "In4.Cu")
		(net 613)
	)
	(arc
		(start 171.54 149.13)
		(mid 171.613223 149.306777)
		(end 171.79 149.38)
		(width 0.1)
		(layer "In4.Cu")
		(net 613)
	)
	(arc
		(start 171.485 148.365)
		(mid 171.419099 148.205901)
		(end 171.26 148.14)
		(width 0.1)
		(layer "In4.Cu")
		(net 613)
	)
	(arc
		(start 172.16 148.14)
		(mid 172.000901 148.205901)
		(end 171.935 148.365)
		(width 0.1)
		(layer "In4.Cu")
		(net 613)
	)
	(arc
		(start 171.71 148.69)
		(mid 171.550901 148.624099)
		(end 171.485 148.465)
		(width 0.1)
		(layer "In4.Cu")
		(net 613)
	)
	(segment
		(start 178.9995 149.999499)
		(end 178.500001 149.5)
		(width 0.256)
		(layer "F.Cu")
		(net 614)
	)
	(segment
		(start 165.1 151.5)
		(end 164.6 152)
		(width 0.256)
		(layer "F.Cu")
		(net 614)
	)
	(via
		(at 178.500001 149.5)
		(size 0.45)
		(drill 0.1)
		(layers "F.Cu" "B.Cu")
		(remove_unused_layers yes)
		(keep_end_layers yes)
		(zone_layer_connections)
		(net 614)
	)
	(via
		(at 164.6 152)
		(size 0.45)
		(drill 0.1)
		(layers "F.Cu" "B.Cu")
		(remove_unused_layers yes)
		(keep_end_layers yes)
		(zone_layer_connections)
		(net 614)
	)
	(segment
		(start 169.95 149.3)
		(end 168.93 148.28)
		(width 0.1)
		(layer "In4.Cu")
		(net 614)
	)
	(segment
		(start 178.500001 149.190001)
		(end 178.500001 149.5)
		(width 0.1)
		(layer "In4.Cu")
		(net 614)
	)
	(segment
		(start 174.93 147.98)
		(end 177.7 147.98)
		(width 0.1)
		(layer "In4.Cu")
		(net 614)
	)
	(segment
		(start 164.6 152)
		(end 165.12 151.48)
		(width 0.1)
		(layer "In4.Cu")
		(net 614)
	)
	(segment
		(start 178 148.28)
		(end 178 148.69)
		(width 0.1)
		(layer "In4.Cu")
		(net 614)
	)
	(segment
		(start 177.7 147.98)
		(end 178 148.28)
		(width 0.1)
		(layer "In4.Cu")
		(net 614)
	)
	(segment
		(start 168.02 151.21)
		(end 168.31 151.5)
		(width 0.1)
		(layer "In4.Cu")
		(net 614)
	)
	(segment
		(start 165.41 149.44)
		(end 167.71 149.44)
		(width 0.1)
		(layer "In4.Cu")
		(net 614)
	)
	(segment
		(start 169.95 150.66)
		(end 169.95 149.3)
		(width 0.1)
		(layer "In4.Cu")
		(net 614)
	)
	(segment
		(start 168.02 149.75)
		(end 168.02 151.21)
		(width 0.1)
		(layer "In4.Cu")
		(net 614)
	)
	(segment
		(start 168.86 146.87)
		(end 173.82 146.87)
		(width 0.1)
		(layer "In4.Cu")
		(net 614)
	)
	(segment
		(start 168.31 151.5)
		(end 169.11 151.5)
		(width 0.1)
		(layer "In4.Cu")
		(net 614)
	)
	(segment
		(start 178 148.69)
		(end 178.500001 149.190001)
		(width 0.1)
		(layer "In4.Cu")
		(net 614)
	)
	(segment
		(start 168.55 147.18)
		(end 168.86 146.87)
		(width 0.1)
		(layer "In4.Cu")
		(net 614)
	)
	(segment
		(start 173.82 146.87)
		(end 174.93 147.98)
		(width 0.1)
		(layer "In4.Cu")
		(net 614)
	)
	(segment
		(start 167.71 149.44)
		(end 168.02 149.75)
		(width 0.1)
		(layer "In4.Cu")
		(net 614)
	)
	(segment
		(start 165.12 151.48)
		(end 165.12 149.73)
		(width 0.1)
		(layer "In4.Cu")
		(net 614)
	)
	(segment
		(start 169.11 151.5)
		(end 169.95 150.66)
		(width 0.1)
		(layer "In4.Cu")
		(net 614)
	)
	(segment
		(start 168.7 148.28)
		(end 168.55 148.13)
		(width 0.1)
		(layer "In4.Cu")
		(net 614)
	)
	(segment
		(start 168.55 148.13)
		(end 168.55 147.18)
		(width 0.1)
		(layer "In4.Cu")
		(net 614)
	)
	(segment
		(start 165.12 149.73)
		(end 165.41 149.44)
		(width 0.1)
		(layer "In4.Cu")
		(net 614)
	)
	(segment
		(start 168.93 148.28)
		(end 168.7 148.28)
		(width 0.1)
		(layer "In4.Cu")
		(net 614)
	)
	(segment
		(start 179.9995 150.9995)
		(end 179.5 150.5)
		(width 0.256)
		(layer "F.Cu")
		(net 615)
	)
	(segment
		(start 167.1 153.5)
		(end 166.6 154)
		(width 0.256)
		(layer "F.Cu")
		(net 615)
	)
	(via
		(at 179.5 150.5)
		(size 0.45)
		(drill 0.1)
		(layers "F.Cu" "B.Cu")
		(remove_unused_layers yes)
		(keep_end_layers yes)
		(zone_layer_connections)
		(net 615)
	)
	(via
		(at 166.6 154)
		(size 0.45)
		(drill 0.1)
		(layers "F.Cu" "B.Cu")
		(remove_unused_layers yes)
		(keep_end_layers yes)
		(zone_layer_connections)
		(net 615)
	)
	(segment
		(start 172.03 150.64)
		(end 172.03 150.551421)
		(width 0.1)
		(layer "In4.Cu")
		(net 615)
	)
	(segment
		(start 170.97 153.5)
		(end 172.03 152.44)
		(width 0.1)
		(layer "In4.Cu")
		(net 615)
	)
	(segment
		(start 174.155 150.815)
		(end 172.205 150.815)
		(width 0.1)
		(layer "In4.Cu")
		(net 615)
	)
	(segment
		(start 174.155 151.515)
		(end 172.205 151.515)
		(width 0.1)
		(layer "In4.Cu")
		(net 615)
	)
	(segment
		(start 166.9 154)
		(end 167.4 153.5)
		(width 0.1)
		(layer "In4.Cu")
		(net 615)
	)
	(segment
		(start 166.6 154)
		(end 166.9 154)
		(width 0.1)
		(layer "In4.Cu")
		(net 615)
	)
	(segment
		(start 175.171421 151.92)
		(end 177.7825 151.92)
		(width 0.1)
		(layer "In4.Cu")
		(net 615)
	)
	(segment
		(start 172.205 151.865)
		(end 174.155 151.865)
		(width 0.1)
		(layer "In4.Cu")
		(net 615)
	)
	(segment
		(start 172.205 151.165)
		(end 174.155 151.165)
		(width 0.1)
		(layer "In4.Cu")
		(net 615)
	)
	(segment
		(start 167.4 153.5)
		(end 170.97 153.5)
		(width 0.1)
		(layer "In4.Cu")
		(net 615)
	)
	(segment
		(start 172.05929 150.48071)
		(end 172.200711 150.339289)
		(width 0.1)
		(layer "In4.Cu")
		(net 615)
	)
	(segment
		(start 178 151.35)
		(end 178.35 151)
		(width 0.1)
		(layer "In4.Cu")
		(net 615)
	)
	(segment
		(start 178.35 151)
		(end 179.01 151)
		(width 0.1)
		(layer "In4.Cu")
		(net 615)
	)
	(segment
		(start 172.271421 150.31)
		(end 174.20636 150.31)
		(width 0.1)
		(layer "In4.Cu")
		(net 615)
	)
	(segment
		(start 179.01 151)
		(end 179.5 150.51)
		(width 0.1)
		(layer "In4.Cu")
		(net 615)
	)
	(segment
		(start 177.7825 151.92)
		(end 178 151.7025)
		(width 0.1)
		(layer "In4.Cu")
		(net 615)
	)
	(segment
		(start 174.71 150.701421)
		(end 174.71 151.458579)
		(width 0.1)
		(layer "In4.Cu")
		(net 615)
	)
	(segment
		(start 179.5 150.51)
		(end 179.5 150.5)
		(width 0.1)
		(layer "In4.Cu")
		(net 615)
	)
	(segment
		(start 174.73929 151.52929)
		(end 175.100711 151.890711)
		(width 0.1)
		(layer "In4.Cu")
		(net 615)
	)
	(segment
		(start 178 151.7025)
		(end 178 151.35)
		(width 0.1)
		(layer "In4.Cu")
		(net 615)
	)
	(segment
		(start 172.03 152.44)
		(end 172.03 152.04)
		(width 0.1)
		(layer "In4.Cu")
		(net 615)
	)
	(segment
		(start 174.46864 150.41864)
		(end 174.680711 150.630711)
		(width 0.1)
		(layer "In4.Cu")
		(net 615)
	)
	(arc
		(start 174.155 151.165)
		(mid 174.278744 151.113744)
		(end 174.33 150.99)
		(width 0.1)
		(layer "In4.Cu")
		(net 615)
	)
	(arc
		(start 172.200711 150.339289)
		(mid 172.233153 150.317612)
		(end 172.271421 150.31)
		(width 0.1)
		(layer "In4.Cu")
		(net 615)
	)
	(arc
		(start 174.680711 150.630711)
		(mid 174.702388 150.663153)
		(end 174.71 150.701421)
		(width 0.1)
		(layer "In4.Cu")
		(net 615)
	)
	(arc
		(start 172.205 151.515)
		(mid 172.081256 151.463744)
		(end 172.03 151.34)
		(width 0.1)
		(layer "In4.Cu")
		(net 615)
	)
	(arc
		(start 172.03 151.34)
		(mid 172.081256 151.216256)
		(end 172.205 151.165)
		(width 0.1)
		(layer "In4.Cu")
		(net 615)
	)
	(arc
		(start 174.155 151.865)
		(mid 174.278744 151.813744)
		(end 174.33 151.69)
		(width 0.1)
		(layer "In4.Cu")
		(net 615)
	)
	(arc
		(start 175.100711 151.890711)
		(mid 175.133153 151.912388)
		(end 175.171421 151.92)
		(width 0.1)
		(layer "In4.Cu")
		(net 615)
	)
	(arc
		(start 174.20636 150.31)
		(mid 174.348305 150.338235)
		(end 174.46864 150.41864)
		(width 0.1)
		(layer "In4.Cu")
		(net 615)
	)
	(arc
		(start 174.33 150.99)
		(mid 174.278744 150.866256)
		(end 174.155 150.815)
		(width 0.1)
		(layer "In4.Cu")
		(net 615)
	)
	(arc
		(start 174.71 151.458579)
		(mid 174.717612 151.496848)
		(end 174.73929 151.52929)
		(width 0.1)
		(layer "In4.Cu")
		(net 615)
	)
	(arc
		(start 172.03 150.551421)
		(mid 172.037612 150.513152)
		(end 172.05929 150.48071)
		(width 0.1)
		(layer "In4.Cu")
		(net 615)
	)
	(arc
		(start 172.03 152.04)
		(mid 172.081256 151.916256)
		(end 172.205 151.865)
		(width 0.1)
		(layer "In4.Cu")
		(net 615)
	)
	(arc
		(start 174.33 151.69)
		(mid 174.278744 151.566256)
		(end 174.155 151.515)
		(width 0.1)
		(layer "In4.Cu")
		(net 615)
	)
	(arc
		(start 172.205 150.815)
		(mid 172.081256 150.763744)
		(end 172.03 150.64)
		(width 0.1)
		(layer "In4.Cu")
		(net 615)
	)
	(segment
		(start 179.9995 149.9995)
		(end 179.499999 149.5)
		(width 0.256)
		(layer "F.Cu")
		(net 616)
	)
	(segment
		(start 168.1 151.5)
		(end 168.6 151)
		(width 0.256)
		(layer "F.Cu")
		(net 616)
	)
	(via
		(at 168.6 151)
		(size 0.45)
		(drill 0.1)
		(layers "F.Cu" "B.Cu")
		(remove_unused_layers yes)
		(keep_end_layers yes)
		(zone_layer_connections)
		(net 616)
	)
	(via
		(at 179.499999 149.5)
		(size 0.45)
		(drill 0.1)
		(layers "F.Cu" "B.Cu")
		(remove_unused_layers yes)
		(keep_end_layers yes)
		(zone_layer_connections)
		(net 616)
	)
	(segment
		(start 165.2 148.368578)
		(end 165.651422 148.82)
		(width 0.1)
		(layer "In4.Cu")
		(net 616)
	)
	(segment
		(start 179.208578 149.1)
		(end 178.9 148.791422)
		(width 0.1)
		(layer "In4.Cu")
		(net 616)
	)
	(segment
		(start 167.76 148.82)
		(end 168.681422 148.82)
		(width 0.1)
		(layer "In4.Cu")
		(net 616)
	)
	(segment
		(start 174.908578 147.1)
		(end 174.118578 146.31)
		(width 0.1)
		(layer "In4.Cu")
		(net 616)
	)
	(segment
		(start 168.681422 148.82)
		(end 169.37 149.508578)
		(width 0.1)
		(layer "In4.Cu")
		(net 616)
	)
	(segment
		(start 178.9 148.791422)
		(end 178.9 147.291422)
		(width 0.1)
		(layer "In4.Cu")
		(net 616)
	)
	(segment
		(start 178.9 147.291422)
		(end 178.708578 147.1)
		(width 0.1)
		(layer "In4.Cu")
		(net 616)
	)
	(segment
		(start 168.65 150.6)
		(end 168.6 150.65)
		(width 0.1)
		(layer "In4.Cu")
		(net 616)
	)
	(segment
		(start 178.708578 147.1)
		(end 174.908578 147.1)
		(width 0.1)
		(layer "In4.Cu")
		(net 616)
	)
	(segment
		(start 169.37 150.321422)
		(end 169.091422 150.6)
		(width 0.1)
		(layer "In4.Cu")
		(net 616)
	)
	(segment
		(start 167.408325 148.371675)
		(end 167.408325 148.471675)
		(width 0.1)
		(layer "In4.Cu")
		(net 616)
	)
	(segment
		(start 174.118578 146.31)
		(end 166.041422 146.31)
		(width 0.1)
		(layer "In4.Cu")
		(net 616)
	)
	(segment
		(start 169.37 149.508578)
		(end 169.37 150.321422)
		(width 0.1)
		(layer "In4.Cu")
		(net 616)
	)
	(segment
		(start 167.75665 148.82)
		(end 167.76 148.82)
		(width 0.1)
		(layer "In4.Cu")
		(net 616)
	)
	(segment
		(start 166.308325 148.471675)
		(end 166.308325 148.371675)
		(width 0.1)
		(layer "In4.Cu")
		(net 616)
	)
	(segment
		(start 166.85665 147.82335)
		(end 166.86 147.82335)
		(width 0.1)
		(layer "In4.Cu")
		(net 616)
	)
	(segment
		(start 169.091422 150.6)
		(end 168.65 150.6)
		(width 0.1)
		(layer "In4.Cu")
		(net 616)
	)
	(segment
		(start 166.041422 146.31)
		(end 165.2 147.151422)
		(width 0.1)
		(layer "In4.Cu")
		(net 616)
	)
	(segment
		(start 165.651422 148.82)
		(end 165.96 148.82)
		(width 0.1)
		(layer "In4.Cu")
		(net 616)
	)
	(segment
		(start 179.499999 149.5)
		(end 179.499999 149.149999)
		(width 0.1)
		(layer "In4.Cu")
		(net 616)
	)
	(segment
		(start 165.2 147.151422)
		(end 165.2 148.368578)
		(width 0.1)
		(layer "In4.Cu")
		(net 616)
	)
	(segment
		(start 179.45 149.1)
		(end 179.208578 149.1)
		(width 0.1)
		(layer "In4.Cu")
		(net 616)
	)
	(segment
		(start 179.499999 149.149999)
		(end 179.45 149.1)
		(width 0.1)
		(layer "In4.Cu")
		(net 616)
	)
	(segment
		(start 168.6 150.65)
		(end 168.6 151)
		(width 0.1)
		(layer "In4.Cu")
		(net 616)
	)
	(arc
		(start 167.408325 148.471675)
		(mid 167.510347 148.717978)
		(end 167.75665 148.82)
		(width 0.1)
		(layer "In4.Cu")
		(net 616)
	)
	(arc
		(start 166.308325 148.371675)
		(mid 166.468926 147.983951)
		(end 166.85665 147.82335)
		(width 0.1)
		(layer "In4.Cu")
		(net 616)
	)
	(arc
		(start 166.86 147.82335)
		(mid 167.247724 147.983951)
		(end 167.408325 148.371675)
		(width 0.1)
		(layer "In4.Cu")
		(net 616)
	)
	(arc
		(start 165.96 148.82)
		(mid 166.206303 148.717978)
		(end 166.308325 148.471675)
		(width 0.1)
		(layer "In4.Cu")
		(net 616)
	)
	(segment
		(start 179.9995 148.9995)
		(end 179.5 148.5)
		(width 0.256)
		(layer "F.Cu")
		(net 617)
	)
	(segment
		(start 168.1 150.5)
		(end 168.6 150)
		(width 0.256)
		(layer "F.Cu")
		(net 617)
	)
	(via
		(at 179.5 148.5)
		(size 0.45)
		(drill 0.1)
		(layers "F.Cu" "B.Cu")
		(remove_unused_layers yes)
		(keep_end_layers yes)
		(zone_layer_connections)
		(net 617)
	)
	(via
		(at 168.6 150)
		(size 0.45)
		(drill 0.1)
		(layers "F.Cu" "B.Cu")
		(remove_unused_layers yes)
		(keep_end_layers yes)
		(zone_layer_connections)
		(net 617)
	)
	(segment
		(start 165.958578 146.11)
		(end 165 147.068578)
		(width 0.1)
		(layer "In4.Cu")
		(net 617)
	)
	(segment
		(start 167.75665 149.02)
		(end 167.76 149.02)
		(width 0.1)
		(layer "In4.Cu")
		(net 617)
	)
	(segment
		(start 179.5 148.5)
		(end 179.5 148.8)
		(width 0.1)
		(layer "In4.Cu")
		(net 617)
	)
	(segment
		(start 179.291422 148.9)
		(end 179.1 148.708578)
		(width 0.1)
		(layer "In4.Cu")
		(net 617)
	)
	(segment
		(start 169.17 149.591422)
		(end 169.17 150.238578)
		(width 0.1)
		(layer "In4.Cu")
		(net 617)
	)
	(segment
		(start 168.598578 149.02)
		(end 169.17 149.591422)
		(width 0.1)
		(layer "In4.Cu")
		(net 617)
	)
	(segment
		(start 174.991422 146.9)
		(end 174.201422 146.11)
		(width 0.1)
		(layer "In4.Cu")
		(net 617)
	)
	(segment
		(start 174.201422 146.11)
		(end 165.958578 146.11)
		(width 0.1)
		(layer "In4.Cu")
		(net 617)
	)
	(segment
		(start 179.1 148.708578)
		(end 179.1 147.208578)
		(width 0.1)
		(layer "In4.Cu")
		(net 617)
	)
	(segment
		(start 178.791422 146.9)
		(end 174.991422 146.9)
		(width 0.1)
		(layer "In4.Cu")
		(net 617)
	)
	(segment
		(start 169.17 150.238578)
		(end 169.008578 150.4)
		(width 0.1)
		(layer "In4.Cu")
		(net 617)
	)
	(segment
		(start 165 148.451422)
		(end 165.568578 149.02)
		(width 0.1)
		(layer "In4.Cu")
		(net 617)
	)
	(segment
		(start 166.85665 148.02335)
		(end 166.86 148.02335)
		(width 0.1)
		(layer "In4.Cu")
		(net 617)
	)
	(segment
		(start 179.4 148.9)
		(end 179.291422 148.9)
		(width 0.1)
		(layer "In4.Cu")
		(net 617)
	)
	(segment
		(start 169.008578 150.4)
		(end 168.7 150.4)
		(width 0.1)
		(layer "In4.Cu")
		(net 617)
	)
	(segment
		(start 165.568578 149.02)
		(end 165.96 149.02)
		(width 0.1)
		(layer "In4.Cu")
		(net 617)
	)
	(segment
		(start 179.1 147.208578)
		(end 178.791422 146.9)
		(width 0.1)
		(layer "In4.Cu")
		(net 617)
	)
	(segment
		(start 166.508325 148.471675)
		(end 166.508325 148.371675)
		(width 0.1)
		(layer "In4.Cu")
		(net 617)
	)
	(segment
		(start 168.7 150.4)
		(end 168.6 150.3)
		(width 0.1)
		(layer "In4.Cu")
		(net 617)
	)
	(segment
		(start 167.76 149.02)
		(end 168.598578 149.02)
		(width 0.1)
		(layer "In4.Cu")
		(net 617)
	)
	(segment
		(start 168.6 150.3)
		(end 168.6 150)
		(width 0.1)
		(layer "In4.Cu")
		(net 617)
	)
	(segment
		(start 179.5 148.8)
		(end 179.4 148.9)
		(width 0.1)
		(layer "In4.Cu")
		(net 617)
	)
	(segment
		(start 167.208325 148.371675)
		(end 167.208325 148.471675)
		(width 0.1)
		(layer "In4.Cu")
		(net 617)
	)
	(segment
		(start 165 147.068578)
		(end 165 148.451422)
		(width 0.1)
		(layer "In4.Cu")
		(net 617)
	)
	(arc
		(start 166.86 148.02335)
		(mid 167.106303 148.125372)
		(end 167.208325 148.371675)
		(width 0.1)
		(layer "In4.Cu")
		(net 617)
	)
	(arc
		(start 166.508325 148.371675)
		(mid 166.610347 148.125372)
		(end 166.85665 148.02335)
		(width 0.1)
		(layer "In4.Cu")
		(net 617)
	)
	(arc
		(start 165.96 149.02)
		(mid 166.347724 148.859399)
		(end 166.508325 148.471675)
		(width 0.1)
		(layer "In4.Cu")
		(net 617)
	)
	(arc
		(start 167.208325 148.471675)
		(mid 167.368926 148.859399)
		(end 167.75665 149.02)
		(width 0.1)
		(layer "In4.Cu")
		(net 617)
	)
	(segment
		(start 169.1 152.5)
		(end 169.6 152)
		(width 0.256)
		(layer "F.Cu")
		(net 618)
	)
	(segment
		(start 182.9995 147.9995)
		(end 182.5 147.5)
		(width 0.256)
		(layer "F.Cu")
		(net 618)
	)
	(via
		(at 182.5 147.5)
		(size 0.45)
		(drill 0.1)
		(layers "F.Cu" "B.Cu")
		(remove_unused_layers yes)
		(keep_end_layers yes)
		(zone_layer_connections)
		(net 618)
	)
	(via
		(at 169.6 152)
		(size 0.45)
		(drill 0.1)
		(layers "F.Cu" "B.Cu")
		(remove_unused_layers yes)
		(keep_end_layers yes)
		(zone_layer_connections)
		(net 618)
	)
	(segment
		(start 169.6 154.535)
		(end 169.6 152)
		(width 0.1)
		(layer "B.Cu")
		(net 618)
	)
	(segment
		(start 168.585 155.55)
		(end 169.6 154.535)
		(width 0.1)
		(layer "B.Cu")
		(net 618)
	)
	(segment
		(start 177.7 149.03)
		(end 175.28 149.03)
		(width 0.1)
		(layer "In4.Cu")
		(net 618)
	)
	(segment
		(start 179.99 149.85)
		(end 179.8 150.04)
		(width 0.1)
		(layer "In4.Cu")
		(net 618)
	)
	(segment
		(start 170.13 152)
		(end 169.6 152)
		(width 0.1)
		(layer "In4.Cu")
		(net 618)
	)
	(segment
		(start 173.55 147.3)
		(end 169.4 147.3)
		(width 0.1)
		(layer "In4.Cu")
		(net 618)
	)
	(segment
		(start 182.63 147.04)
		(end 182.86 147.04)
		(width 0.1)
		(layer "In4.Cu")
		(net 618)
	)
	(segment
		(start 180.3 149)
		(end 179.99 149.31)
		(width 0.1)
		(layer "In4.Cu")
		(net 618)
	)
	(segment
		(start 169.22 147.92)
		(end 170.47 149.17)
		(width 0.1)
		(layer "In4.Cu")
		(net 618)
	)
	(segment
		(start 178.3 150.04)
		(end 178.05 149.79)
		(width 0.1)
		(layer "In4.Cu")
		(net 618)
	)
	(segment
		(start 178.05 149.38)
		(end 177.7 149.03)
		(width 0.1)
		(layer "In4.Cu")
		(net 618)
	)
	(segment
		(start 179.8 150.04)
		(end 178.3 150.04)
		(width 0.1)
		(layer "In4.Cu")
		(net 618)
	)
	(segment
		(start 175.28 149.03)
		(end 173.55 147.3)
		(width 0.1)
		(layer "In4.Cu")
		(net 618)
	)
	(segment
		(start 183.01 147.19)
		(end 183.01 148.8)
		(width 0.1)
		(layer "In4.Cu")
		(net 618)
	)
	(segment
		(start 170.47 149.17)
		(end 170.47 150.98)
		(width 0.1)
		(layer "In4.Cu")
		(net 618)
	)
	(segment
		(start 178.05 149.79)
		(end 178.05 149.38)
		(width 0.1)
		(layer "In4.Cu")
		(net 618)
	)
	(segment
		(start 182.5 147.17)
		(end 182.63 147.04)
		(width 0.1)
		(layer "In4.Cu")
		(net 618)
	)
	(segment
		(start 182.81 149)
		(end 180.3 149)
		(width 0.1)
		(layer "In4.Cu")
		(net 618)
	)
	(segment
		(start 170.47 151.55206)
		(end 170.47 151.66)
		(width 0.1)
		(layer "In4.Cu")
		(net 618)
	)
	(segment
		(start 169.4 147.3)
		(end 169.22 147.48)
		(width 0.1)
		(layer "In4.Cu")
		(net 618)
	)
	(segment
		(start 170.47 151.66)
		(end 170.13 152)
		(width 0.1)
		(layer "In4.Cu")
		(net 618)
	)
	(segment
		(start 169.22 147.48)
		(end 169.22 147.92)
		(width 0.1)
		(layer "In4.Cu")
		(net 618)
	)
	(segment
		(start 182.86 147.04)
		(end 183.01 147.19)
		(width 0.1)
		(layer "In4.Cu")
		(net 618)
	)
	(segment
		(start 182.5 147.5)
		(end 182.5 147.17)
		(width 0.1)
		(layer "In4.Cu")
		(net 618)
	)
	(segment
		(start 179.99 149.31)
		(end 179.99 149.85)
		(width 0.1)
		(layer "In4.Cu")
		(net 618)
	)
	(segment
		(start 170.19794 151.25206)
		(end 170.19794 151.28)
		(width 0.1)
		(layer "In4.Cu")
		(net 618)
	)
	(segment
		(start 183.01 148.8)
		(end 182.81 149)
		(width 0.1)
		(layer "In4.Cu")
		(net 618)
	)
	(arc
		(start 170.19794 151.28)
		(mid 170.237782 151.376188)
		(end 170.33397 151.41603)
		(width 0.1)
		(layer "In4.Cu")
		(net 618)
	)
	(arc
		(start 170.33397 151.41603)
		(mid 170.430158 151.455872)
		(end 170.47 151.55206)
		(width 0.1)
		(layer "In4.Cu")
		(net 618)
	)
	(arc
		(start 170.33397 151.11603)
		(mid 170.237782 151.155872)
		(end 170.19794 151.25206)
		(width 0.1)
		(layer "In4.Cu")
		(net 618)
	)
	(arc
		(start 170.47 150.98)
		(mid 170.430158 151.076188)
		(end 170.33397 151.11603)
		(width 0.1)
		(layer "In4.Cu")
		(net 618)
	)
	(segment
		(start 182.9995 148.999501)
		(end 182.5 148.5)
		(width 0.256)
		(layer "F.Cu")
		(net 619)
	)
	(segment
		(start 164.6505 152.9505)
		(end 165.101 152.5)
		(width 0.256)
		(layer "F.Cu")
		(net 619)
	)
	(via
		(at 164.6505 152.9505)
		(size 0.45)
		(drill 0.1)
		(layers "F.Cu" "B.Cu")
		(remove_unused_layers yes)
		(keep_end_layers yes)
		(zone_layer_connections)
		(net 619)
	)
	(via
		(at 182.5 148.5)
		(size 0.45)
		(drill 0.1)
		(layers "F.Cu" "B.Cu")
		(remove_unused_layers yes)
		(keep_end_layers yes)
		(zone_layer_connections)
		(net 619)
	)
	(segment
		(start 163.52 146.76)
		(end 163.52 151.82)
		(width 0.1)
		(layer "In4.Cu")
		(net 619)
	)
	(segment
		(start 182 147.28)
		(end 181.72 147)
		(width 0.1)
		(layer "In4.Cu")
		(net 619)
	)
	(segment
		(start 163.52 151.82)
		(end 164.6505 152.9505)
		(width 0.1)
		(layer "In4.Cu")
		(net 619)
	)
	(segment
		(start 182.5 148.5)
		(end 182 148)
		(width 0.1)
		(layer "In4.Cu")
		(net 619)
	)
	(segment
		(start 165.28 145)
		(end 163.52 146.76)
		(width 0.1)
		(layer "In4.Cu")
		(net 619)
	)
	(segment
		(start 181.3 147)
		(end 180.99 146.69)
		(width 0.1)
		(layer "In4.Cu")
		(net 619)
	)
	(segment
		(start 180.99 146.69)
		(end 180.99 145.25)
		(width 0.1)
		(layer "In4.Cu")
		(net 619)
	)
	(segment
		(start 182 148)
		(end 182 147.28)
		(width 0.1)
		(layer "In4.Cu")
		(net 619)
	)
	(segment
		(start 180.74 145)
		(end 165.28 145)
		(width 0.1)
		(layer "In4.Cu")
		(net 619)
	)
	(segment
		(start 180.99 145.25)
		(end 180.74 145)
		(width 0.1)
		(layer "In4.Cu")
		(net 619)
	)
	(segment
		(start 181.72 147)
		(end 181.3 147)
		(width 0.1)
		(layer "In4.Cu")
		(net 619)
	)
	(segment
		(start 177.9995 149.9995)
		(end 177.5 149.5)
		(width 0.256)
		(layer "F.Cu")
		(net 620)
	)
	(segment
		(start 166.100001 151.5)
		(end 165.6 152)
		(width 0.256)
		(layer "F.Cu")
		(net 620)
	)
	(via
		(at 177.5 149.5)
		(size 0.45)
		(drill 0.1)
		(layers "F.Cu" "B.Cu")
		(remove_unused_layers yes)
		(keep_end_layers yes)
		(zone_layer_connections)
		(net 620)
	)
	(via
		(at 165.6 152)
		(size 0.45)
		(drill 0.1)
		(layers "F.Cu" "B.Cu")
		(remove_unused_layers yes)
		(keep_end_layers yes)
		(zone_layer_connections)
		(net 620)
	)
	(segment
		(start 167.36 150.47)
		(end 165.79 150.47)
		(width 0.1)
		(layer "In4.Cu")
		(net 620)
	)
	(segment
		(start 168.125 151.815)
		(end 167.58 151.27)
		(width 0.1)
		(layer "In4.Cu")
		(net 620)
	)
	(segment
		(start 168.125 152.425)
		(end 168.125 151.815)
		(width 0.1)
		(layer "In4.Cu")
		(net 620)
	)
	(segment
		(start 166.875 151.635)
		(end 166.85 151.635)
		(width 0.1)
		(layer "In4.Cu")
		(net 620)
	)
	(segment
		(start 173.1 147.71)
		(end 170.2 147.71)
		(width 0.1)
		(layer "In4.Cu")
		(net 620)
	)
	(segment
		(start 171.01 151.92)
		(end 170.372162 152.557838)
		(width 0.1)
		(layer "In4.Cu")
		(net 620)
	)
	(segment
		(start 168.26 152.56)
		(end 168.125 152.425)
		(width 0.1)
		(layer "In4.Cu")
		(net 620)
	)
	(segment
		(start 170.09 148.23)
		(end 171.01 149.15)
		(width 0.1)
		(layer "In4.Cu")
		(net 620)
	)
	(segment
		(start 170.09 147.82)
		(end 170.09 148.23)
		(width 0.1)
		(layer "In4.Cu")
		(net 620)
	)
	(segment
		(start 165.767642 151.087642)
		(end 166.929175 151.087642)
		(width 0.1)
		(layer "In4.Cu")
		(net 620)
	)
	(segment
		(start 165.6 151.91)
		(end 165.6 152)
		(width 0.1)
		(layer "In4.Cu")
		(net 620)
	)
	(segment
		(start 171.01 149.15)
		(end 171.01 151.92)
		(width 0.1)
		(layer "In4.Cu")
		(net 620)
	)
	(segment
		(start 177.5 149.85)
		(end 177.39 149.96)
		(width 0.1)
		(layer "In4.Cu")
		(net 620)
	)
	(segment
		(start 168.262162 152.557838)
		(end 168.26 152.56)
		(width 0.1)
		(layer "In4.Cu")
		(net 620)
	)
	(segment
		(start 177.5 149.5)
		(end 177.5 149.85)
		(width 0.1)
		(layer "In4.Cu")
		(net 620)
	)
	(segment
		(start 165.79 150.47)
		(end 165.68 150.58)
		(width 0.1)
		(layer "In4.Cu")
		(net 620)
	)
	(segment
		(start 170.2 147.71)
		(end 170.09 147.82)
		(width 0.1)
		(layer "In4.Cu")
		(net 620)
	)
	(segment
		(start 175.35 149.96)
		(end 173.1 147.71)
		(width 0.1)
		(layer "In4.Cu")
		(net 620)
	)
	(segment
		(start 167.58 150.69)
		(end 167.36 150.47)
		(width 0.1)
		(layer "In4.Cu")
		(net 620)
	)
	(segment
		(start 165.68 151)
		(end 165.767642 151.087642)
		(width 0.1)
		(layer "In4.Cu")
		(net 620)
	)
	(segment
		(start 165.68 150.58)
		(end 165.68 151)
		(width 0.1)
		(layer "In4.Cu")
		(net 620)
	)
	(segment
		(start 165.95 151.635)
		(end 165.875 151.635)
		(width 0.1)
		(layer "In4.Cu")
		(net 620)
	)
	(segment
		(start 170.372162 152.557838)
		(end 168.262162 152.557838)
		(width 0.1)
		(layer "In4.Cu")
		(net 620)
	)
	(segment
		(start 167.58 151.27)
		(end 167.58 150.69)
		(width 0.1)
		(layer "In4.Cu")
		(net 620)
	)
	(segment
		(start 177.39 149.96)
		(end 175.35 149.96)
		(width 0.1)
		(layer "In4.Cu")
		(net 620)
	)
	(arc
		(start 166.85 151.635)
		(mid 166.690901 151.700901)
		(end 166.625 151.86)
		(width 0.1)
		(layer "In4.Cu")
		(net 620)
	)
	(arc
		(start 166.625 151.86)
		(mid 166.559099 152.019099)
		(end 166.4 152.085)
		(width 0.1)
		(layer "In4.Cu")
		(net 620)
	)
	(arc
		(start 167.15 151.36)
		(mid 167.069454 151.554454)
		(end 166.875 151.635)
		(width 0.1)
		(layer "In4.Cu")
		(net 620)
	)
	(arc
		(start 165.875 151.635)
		(mid 165.680546 151.715546)
		(end 165.6 151.91)
		(width 0.1)
		(layer "In4.Cu")
		(net 620)
	)
	(arc
		(start 166.929175 151.087642)
		(mid 167.087578 151.185542)
		(end 167.15 151.36)
		(width 0.1)
		(layer "In4.Cu")
		(net 620)
	)
	(arc
		(start 166.4 152.085)
		(mid 166.240901 152.019099)
		(end 166.175 151.86)
		(width 0.1)
		(layer "In4.Cu")
		(net 620)
	)
	(arc
		(start 166.175 151.86)
		(mid 166.109099 151.700901)
		(end 165.95 151.635)
		(width 0.1)
		(layer "In4.Cu")
		(net 620)
	)
	(segment
		(start 166.1 154.5)
		(end 165.599 155.001)
		(width 0.256)
		(layer "F.Cu")
		(net 621)
	)
	(segment
		(start 181.9995 149.9995)
		(end 181.5 149.5)
		(width 0.256)
		(layer "F.Cu")
		(net 621)
	)
	(via
		(at 181.5 149.5)
		(size 0.45)
		(drill 0.1)
		(layers "F.Cu" "B.Cu")
		(remove_unused_layers yes)
		(keep_end_layers yes)
		(zone_layer_connections)
		(net 621)
	)
	(via
		(at 165.599 155.001)
		(size 0.45)
		(drill 0.1)
		(layers "F.Cu" "B.Cu")
		(remove_unused_layers yes)
		(keep_end_layers yes)
		(zone_layer_connections)
		(net 621)
	)
	(segment
		(start 175.875 152.732003)
		(end 175.875 152.855)
		(width 0.1)
		(layer "In4.Cu")
		(net 621)
	)
	(segment
		(start 182.03 149.87)
		(end 182.03 149.64)
		(width 0.1)
		(layer "In4.Cu")
		(net 621)
	)
	(segment
		(start 167.603603 154.513223)
		(end 167.727487 154.637107)
		(width 0.1)
		(layer "In4.Cu")
		(net 621)
	)
	(segment
		(start 180.76 151.97)
		(end 181 151.73)
		(width 0.1)
		(layer "In4.Cu")
		(net 621)
	)
	(segment
		(start 181 151.73)
		(end 181 150.21)
		(width 0.1)
		(layer "In4.Cu")
		(net 621)
	)
	(segment
		(start 175.28 153.03)
		(end 175.35 153.03)
		(width 0.1)
		(layer "In4.Cu")
		(net 621)
	)
	(segment
		(start 181 150.21)
		(end 181.19 150.02)
		(width 0.1)
		(layer "In4.Cu")
		(net 621)
	)
	(segment
		(start 166.91 155.92)
		(end 166.927157 155.92)
		(width 0.1)
		(layer "In4.Cu")
		(net 621)
	)
	(segment
		(start 168.434594 154.93)
		(end 172.4 154.93)
		(width 0.1)
		(layer "In4.Cu")
		(net 621)
	)
	(segment
		(start 181.19 150.02)
		(end 181.88 150.02)
		(width 0.1)
		(layer "In4.Cu")
		(net 621)
	)
	(segment
		(start 178.15 153.03)
		(end 179.27 153.03)
		(width 0.1)
		(layer "In4.Cu")
		(net 621)
	)
	(segment
		(start 179.793223 152.33)
		(end 179.793222 152.33)
		(width 0.1)
		(layer "In4.Cu")
		(net 621)
	)
	(segment
		(start 181.89 149.5)
		(end 181.5 149.5)
		(width 0.1)
		(layer "In4.Cu")
		(net 621)
	)
	(segment
		(start 165.158579 155.598579)
		(end 165.421422 155.861422)
		(width 0.1)
		(layer "In4.Cu")
		(net 621)
	)
	(segment
		(start 179.510379 152.436066)
		(end 179.616446 152.33)
		(width 0.1)
		(layer "In4.Cu")
		(net 621)
	)
	(segment
		(start 165.599 155.001)
		(end 165.381843 155.001)
		(width 0.1)
		(layer "In4.Cu")
		(net 621)
	)
	(segment
		(start 181.88 150.02)
		(end 182.03 149.87)
		(width 0.1)
		(layer "In4.Cu")
		(net 621)
	)
	(segment
		(start 165.562843 155.92)
		(end 165.81 155.92)
		(width 0.1)
		(layer "In4.Cu")
		(net 621)
	)
	(segment
		(start 176.575 152.732003)
		(end 176.575 152.855)
		(width 0.1)
		(layer "In4.Cu")
		(net 621)
	)
	(segment
		(start 167.143983 154.972842)
		(end 167.143983 154.972841)
		(width 0.1)
		(layer "In4.Cu")
		(net 621)
	)
	(segment
		(start 174.32 153.99)
		(end 175.28 153.03)
		(width 0.1)
		(layer "In4.Cu")
		(net 621)
	)
	(segment
		(start 182.03 149.64)
		(end 181.89 149.5)
		(width 0.1)
		(layer "In4.Cu")
		(net 621)
	)
	(segment
		(start 179.616446 152.33)
		(end 179.616446 152.329999)
		(width 0.1)
		(layer "In4.Cu")
		(net 621)
	)
	(segment
		(start 167.068579 155.861421)
		(end 167.320759 155.609238)
		(width 0.1)
		(layer "In4.Cu")
		(net 621)
	)
	(segment
		(start 165.240421 155.059579)
		(end 165.158578 155.141422)
		(width 0.1)
		(layer "In4.Cu")
		(net 621)
	)
	(segment
		(start 173.34 153.99)
		(end 174.32 153.99)
		(width 0.1)
		(layer "In4.Cu")
		(net 621)
	)
	(segment
		(start 172.4 154.93)
		(end 173.34 153.99)
		(width 0.1)
		(layer "In4.Cu")
		(net 621)
	)
	(segment
		(start 167.320759 155.149618)
		(end 167.143983 154.972842)
		(width 0.1)
		(layer "In4.Cu")
		(net 621)
	)
	(segment
		(start 165.1 155.282843)
		(end 165.1 155.457157)
		(width 0.1)
		(layer "In4.Cu")
		(net 621)
	)
	(segment
		(start 177.975 152.732003)
		(end 177.975 152.855)
		(width 0.1)
		(layer "In4.Cu")
		(net 621)
	)
	(segment
		(start 177.625 152.855)
		(end 177.625 152.732003)
		(width 0.1)
		(layer "In4.Cu")
		(net 621)
	)
	(segment
		(start 176.925 152.855)
		(end 176.925 152.732003)
		(width 0.1)
		(layer "In4.Cu")
		(net 621)
	)
	(segment
		(start 175.525 152.855)
		(end 175.525 152.732003)
		(width 0.1)
		(layer "In4.Cu")
		(net 621)
	)
	(segment
		(start 166.635 154.745)
		(end 166.635 155.645)
		(width 0.1)
		(layer "In4.Cu")
		(net 621)
	)
	(segment
		(start 176.225 152.855)
		(end 176.225 152.732003)
		(width 0.1)
		(layer "In4.Cu")
		(net 621)
	)
	(segment
		(start 166.085 155.645)
		(end 166.085 154.745)
		(width 0.1)
		(layer "In4.Cu")
		(net 621)
	)
	(segment
		(start 179.97 152.33)
		(end 180.33 151.97)
		(width 0.1)
		(layer "In4.Cu")
		(net 621)
	)
	(segment
		(start 177.275 152.732003)
		(end 177.275 152.855)
		(width 0.1)
		(layer "In4.Cu")
		(net 621)
	)
	(segment
		(start 179.510379 152.612842)
		(end 179.51038 152.612843)
		(width 0.1)
		(layer "In4.Cu")
		(net 621)
	)
	(segment
		(start 179.27 153.03)
		(end 179.510378 152.789619)
		(width 0.1)
		(layer "In4.Cu")
		(net 621)
	)
	(segment
		(start 180.33 151.97)
		(end 180.76 151.97)
		(width 0.1)
		(layer "In4.Cu")
		(net 621)
	)
	(arc
		(start 176.925 152.732003)
		(mid 176.976256 152.608259)
		(end 177.1 152.557003)
		(width 0.1)
		(layer "In4.Cu")
		(net 621)
	)
	(arc
		(start 176.05 153.03)
		(mid 176.173744 152.978744)
		(end 176.225 152.855)
		(width 0.1)
		(layer "In4.Cu")
		(net 621)
	)
	(arc
		(start 167.143983 154.513223)
		(mid 167.373793 154.418033)
		(end 167.603603 154.513223)
		(width 0.1)
		(layer "In4.Cu")
		(net 621)
	)
	(arc
		(start 179.51038 152.612843)
		(mid 179.473768 152.524455)
		(end 179.510379 152.436066)
		(width 0.1)
		(layer "In4.Cu")
		(net 621)
	)
	(arc
		(start 167.320759 155.609238)
		(mid 167.415949 155.379428)
		(end 167.320759 155.149618)
		(width 0.1)
		(layer "In4.Cu")
		(net 621)
	)
	(arc
		(start 177.8 152.557003)
		(mid 177.923744 152.608259)
		(end 177.975 152.732003)
		(width 0.1)
		(layer "In4.Cu")
		(net 621)
	)
	(arc
		(start 177.975 152.855)
		(mid 178.026256 152.978744)
		(end 178.15 153.03)
		(width 0.1)
		(layer "In4.Cu")
		(net 621)
	)
	(arc
		(start 166.085 154.745)
		(mid 166.165546 154.550546)
		(end 166.36 154.47)
		(width 0.1)
		(layer "In4.Cu")
		(net 621)
	)
	(arc
		(start 166.635 155.645)
		(mid 166.715546 155.839454)
		(end 166.91 155.92)
		(width 0.1)
		(layer "In4.Cu")
		(net 621)
	)
	(arc
		(start 165.421422 155.861422)
		(mid 165.486307 155.904776)
		(end 165.562843 155.92)
		(width 0.1)
		(layer "In4.Cu")
		(net 621)
	)
	(arc
		(start 166.36 154.47)
		(mid 166.554454 154.550546)
		(end 166.635 154.745)
		(width 0.1)
		(layer "In4.Cu")
		(net 621)
	)
	(arc
		(start 179.793222 152.33)
		(mid 179.881611 152.366612)
		(end 179.97 152.33)
		(width 0.1)
		(layer "In4.Cu")
		(net 621)
	)
	(arc
		(start 175.525 152.732003)
		(mid 175.576256 152.608259)
		(end 175.7 152.557003)
		(width 0.1)
		(layer "In4.Cu")
		(net 621)
	)
	(arc
		(start 165.381843 155.001)
		(mid 165.305306 155.016224)
		(end 165.240421 155.059579)
		(width 0.1)
		(layer "In4.Cu")
		(net 621)
	)
	(arc
		(start 177.45 153.03)
		(mid 177.573744 152.978744)
		(end 177.625 152.855)
		(width 0.1)
		(layer "In4.Cu")
		(net 621)
	)
	(arc
		(start 175.35 153.03)
		(mid 175.473744 152.978744)
		(end 175.525 152.855)
		(width 0.1)
		(layer "In4.Cu")
		(net 621)
	)
	(arc
		(start 166.927157 155.92)
		(mid 167.003694 155.904776)
		(end 167.068579 155.861421)
		(width 0.1)
		(layer "In4.Cu")
		(net 621)
	)
	(arc
		(start 175.7 152.557003)
		(mid 175.823744 152.608259)
		(end 175.875 152.732003)
		(width 0.1)
		(layer "In4.Cu")
		(net 621)
	)
	(arc
		(start 165.158578 155.141422)
		(mid 165.115224 155.206307)
		(end 165.1 155.282843)
		(width 0.1)
		(layer "In4.Cu")
		(net 621)
	)
	(arc
		(start 179.616446 152.329999)
		(mid 179.704835 152.293388)
		(end 179.793223 152.33)
		(width 0.1)
		(layer "In4.Cu")
		(net 621)
	)
	(arc
		(start 165.81 155.92)
		(mid 166.004454 155.839454)
		(end 166.085 155.645)
		(width 0.1)
		(layer "In4.Cu")
		(net 621)
	)
	(arc
		(start 176.75 153.03)
		(mid 176.873744 152.978744)
		(end 176.925 152.855)
		(width 0.1)
		(layer "In4.Cu")
		(net 621)
	)
	(arc
		(start 177.625 152.732003)
		(mid 177.676256 152.608259)
		(end 177.8 152.557003)
		(width 0.1)
		(layer "In4.Cu")
		(net 621)
	)
	(arc
		(start 176.575 152.855)
		(mid 176.626256 152.978744)
		(end 176.75 153.03)
		(width 0.1)
		(layer "In4.Cu")
		(net 621)
	)
	(arc
		(start 167.727487 154.637107)
		(mid 168.05191 154.85388)
		(end 168.434594 154.93)
		(width 0.1)
		(layer "In4.Cu")
		(net 621)
	)
	(arc
		(start 175.875 152.855)
		(mid 175.926256 152.978744)
		(end 176.05 153.03)
		(width 0.1)
		(layer "In4.Cu")
		(net 621)
	)
	(arc
		(start 176.225 152.732003)
		(mid 176.276256 152.608259)
		(end 176.4 152.557003)
		(width 0.1)
		(layer "In4.Cu")
		(net 621)
	)
	(arc
		(start 176.4 152.557003)
		(mid 176.523744 152.608259)
		(end 176.575 152.732003)
		(width 0.1)
		(layer "In4.Cu")
		(net 621)
	)
	(arc
		(start 177.275 152.855)
		(mid 177.326256 152.978744)
		(end 177.45 153.03)
		(width 0.1)
		(layer "In4.Cu")
		(net 621)
	)
	(arc
		(start 179.510378 152.789619)
		(mid 179.54699 152.701231)
		(end 179.510379 152.612842)
		(width 0.1)
		(layer "In4.Cu")
		(net 621)
	)
	(arc
		(start 165.1 155.457157)
		(mid 165.115224 155.533694)
		(end 165.158579 155.598579)
		(width 0.1)
		(layer "In4.Cu")
		(net 621)
	)
	(arc
		(start 177.1 152.557003)
		(mid 177.223744 152.608259)
		(end 177.275 152.732003)
		(width 0.1)
		(layer "In4.Cu")
		(net 621)
	)
	(arc
		(start 167.143983 154.972841)
		(mid 167.048793 154.743032)
		(end 167.143983 154.513223)
		(width 0.1)
		(layer "In4.Cu")
		(net 621)
	)
	(segment
		(start 182.9995 149.999499)
		(end 182.5 149.5)
		(width 0.256)
		(layer "F.Cu")
		(net 622)
	)
	(segment
		(start 166.1 152.5)
		(end 165.6 153)
		(width 0.256)
		(layer "F.Cu")
		(net 622)
	)
	(via
		(at 182.5 149.5)
		(size 0.45)
		(drill 0.1)
		(layers "F.Cu" "B.Cu")
		(remove_unused_layers yes)
		(keep_end_layers yes)
		(zone_layer_connections)
		(net 622)
	)
	(via
		(at 165.6 153)
		(size 0.45)
		(drill 0.1)
		(layers "F.Cu" "B.Cu")
		(remove_unused_layers yes)
		(keep_end_layers yes)
		(zone_layer_connections)
		(net 622)
	)
	(segment
		(start 180.69 154)
		(end 180.33 154)
		(width 0.1)
		(layer "In4.Cu")
		(net 622)
	)
	(segment
		(start 174.13 154.99)
		(end 173.26 155.86)
		(width 0.1)
		(layer "In4.Cu")
		(net 622)
	)
	(segment
		(start 181.05 153.23)
		(end 181.05 153.64)
		(width 0.1)
		(layer "In4.Cu")
		(net 622)
	)
	(segment
		(start 180 154.33)
		(end 180 154.725)
		(width 0.1)
		(layer "In4.Cu")
		(net 622)
	)
	(segment
		(start 180.33 154)
		(end 180 154.33)
		(width 0.1)
		(layer "In4.Cu")
		(net 622)
	)
	(segment
		(start 182.5 149.5)
		(end 183.02 150.02)
		(width 0.1)
		(layer "In4.Cu")
		(net 622)
	)
	(segment
		(start 164.96 156.96)
		(end 163.5 155.5)
		(width 0.1)
		(layer "In4.Cu")
		(net 622)
	)
	(segment
		(start 183.02 151.95)
		(end 181.97 153)
		(width 0.1)
		(layer "In4.Cu")
		(net 622)
	)
	(segment
		(start 164.76 153.5)
		(end 165.26 153)
		(width 0.1)
		(layer "In4.Cu")
		(net 622)
	)
	(segment
		(start 181.97 153)
		(end 181.28 153)
		(width 0.1)
		(layer "In4.Cu")
		(net 622)
	)
	(segment
		(start 163.5 155.5)
		(end 163.5 154.4)
		(width 0.1)
		(layer "In4.Cu")
		(net 622)
	)
	(segment
		(start 163.5 154.4)
		(end 164.4 153.5)
		(width 0.1)
		(layer "In4.Cu")
		(net 622)
	)
	(segment
		(start 167.55 156.96)
		(end 164.96 156.96)
		(width 0.1)
		(layer "In4.Cu")
		(net 622)
	)
	(segment
		(start 180 154.725)
		(end 179.735 154.99)
		(width 0.1)
		(layer "In4.Cu")
		(net 622)
	)
	(segment
		(start 181.05 153.64)
		(end 180.69 154)
		(width 0.1)
		(layer "In4.Cu")
		(net 622)
	)
	(segment
		(start 173.26 155.86)
		(end 168.65 155.86)
		(width 0.1)
		(layer "In4.Cu")
		(net 622)
	)
	(segment
		(start 164.4 153.5)
		(end 164.76 153.5)
		(width 0.1)
		(layer "In4.Cu")
		(net 622)
	)
	(segment
		(start 179.735 154.99)
		(end 174.13 154.99)
		(width 0.1)
		(layer "In4.Cu")
		(net 622)
	)
	(segment
		(start 165.26 153)
		(end 165.6 153)
		(width 0.1)
		(layer "In4.Cu")
		(net 622)
	)
	(segment
		(start 181.28 153)
		(end 181.05 153.23)
		(width 0.1)
		(layer "In4.Cu")
		(net 622)
	)
	(segment
		(start 183.02 150.02)
		(end 183.02 151.95)
		(width 0.1)
		(layer "In4.Cu")
		(net 622)
	)
	(segment
		(start 168.65 155.86)
		(end 167.55 156.96)
		(width 0.1)
		(layer "In4.Cu")
		(net 622)
	)
	(segment
		(start 180.9995 150.999501)
		(end 180.5 150.5)
		(width 0.256)
		(layer "F.Cu")
		(net 623)
	)
	(segment
		(start 169.099999 153.5)
		(end 168.6 153.999999)
		(width 0.256)
		(layer "F.Cu")
		(net 623)
	)
	(via
		(at 168.6 153.999999)
		(size 0.45)
		(drill 0.1)
		(layers "F.Cu" "B.Cu")
		(remove_unused_layers yes)
		(keep_end_layers yes)
		(zone_layer_connections)
		(net 623)
	)
	(via
		(at 180.5 150.5)
		(size 0.45)
		(drill 0.1)
		(layers "F.Cu" "B.Cu")
		(remove_unused_layers yes)
		(keep_end_layers yes)
		(zone_layer_connections)
		(net 623)
	)
	(segment
		(start 168.58 154.019999)
		(end 168.6 153.999999)
		(width 0.4)
		(layer "B.Cu")
		(net 623)
	)
	(segment
		(start 168.58 154.5)
		(end 168.58 154.019999)
		(width 0.4)
		(layer "B.Cu")
		(net 623)
	)
	(segment
		(start 170.480344 154.449656)
		(end 170.43 154.449656)
		(width 0.1)
		(layer "In4.Cu")
		(net 623)
	)
	(segment
		(start 172.241371 152.868626)
		(end 172.241371 152.868627)
		(width 0.1)
		(layer "In4.Cu")
		(net 623)
	)
	(segment
		(start 172.241373 152.868627)
		(end 172.241371 152.868626)
		(width 0.1)
		(layer "In4.Cu")
		(net 623)
	)
	(segment
		(start 174.675 152.73)
		(end 174.675 152.465)
		(width 0.1)
		(layer "In4.Cu")
		(net 623)
	)
	(segment
		(start 179.66 152.01)
		(end 178.29 152.01)
		(width 0.1)
		(layer "In4.Cu")
		(net 623)
	)
	(segment
		(start 171.675685 153.434312)
		(end 171.675685 153.434313)
		(width 0.1)
		(layer "In4.Cu")
		(net 623)
	)
	(segment
		(start 169.705172 154.224827)
		(end 169.705172 154.224828)
		(width 0.1)
		(layer "In4.Cu")
		(net 623)
	)
	(segment
		(start 180 150.595)
		(end 180 151.67)
		(width 0.1)
		(layer "In4.Cu")
		(net 623)
	)
	(segment
		(start 173.04 152.29)
		(end 172.82 152.29)
		(width 0.1)
		(layer "In4.Cu")
		(net 623)
	)
	(segment
		(start 170.705172 154.224827)
		(end 170.705172 154.224828)
		(width 0.1)
		(layer "In4.Cu")
		(net 623)
	)
	(segment
		(start 180.5 150.5)
		(end 180.095 150.5)
		(width 0.1)
		(layer "In4.Cu")
		(net 623)
	)
	(segment
		(start 172.82 152.29)
		(end 172.807057 152.302941)
		(width 0.1)
		(layer "In4.Cu")
		(net 623)
	)
	(segment
		(start 178.29 152.01)
		(end 178.01 152.29)
		(width 0.1)
		(layer "In4.Cu")
		(net 623)
	)
	(segment
		(start 172.807057 153.999998)
		(end 172.807056 153.999998)
		(width 0.1)
		(layer "In4.Cu")
		(net 623)
	)
	(segment
		(start 172.029239 154.070709)
		(end 172.029239 154.070708)
		(width 0.1)
		(layer "In4.Cu")
		(net 623)
	)
	(segment
		(start 172.807057 152.585783)
		(end 173.478809 153.257535)
		(width 0.1)
		(layer "In4.Cu")
		(net 623)
	)
	(segment
		(start 173.8 152.29)
		(end 173.74 152.29)
		(width 0.1)
		(layer "In4.Cu")
		(net 623)
	)
	(segment
		(start 171.675685 153.717155)
		(end 172.029239 154.070709)
		(width 0.1)
		(layer "In4.Cu")
		(net 623)
	)
	(segment
		(start 171.110001 153.999999)
		(end 170.93 153.999999)
		(width 0.1)
		(layer "In4.Cu")
		(net 623)
	)
	(segment
		(start 180.095 150.5)
		(end 180 150.595)
		(width 0.1)
		(layer "In4.Cu")
		(net 623)
	)
	(segment
		(start 173.725 152.96)
		(end 173.725 152.86)
		(width 0.1)
		(layer "In4.Cu")
		(net 623)
	)
	(segment
		(start 172.241371 153.151469)
		(end 172.807057 153.717155)
		(width 0.1)
		(layer "In4.Cu")
		(net 623)
	)
	(segment
		(start 171.746396 154.353552)
		(end 171.392843 153.999999)
		(width 0.1)
		(layer "In4.Cu")
		(net 623)
	)
	(segment
		(start 173.478809 153.257535)
		(end 173.478809 153.257534)
		(width 0.1)
		(layer "In4.Cu")
		(net 623)
	)
	(segment
		(start 174.325 152.465)
		(end 174.325 153.415)
		(width 0.1)
		(layer "In4.Cu")
		(net 623)
	)
	(segment
		(start 173.975 153.415)
		(end 173.975 153.21)
		(width 0.1)
		(layer "In4.Cu")
		(net 623)
	)
	(segment
		(start 172.524214 153.999998)
		(end 171.958529 153.434313)
		(width 0.1)
		(layer "In4.Cu")
		(net 623)
	)
	(segment
		(start 168.980344 153.999999)
		(end 168.6 153.999999)
		(width 0.1)
		(layer "In4.Cu")
		(net 623)
	)
	(segment
		(start 169.480344 154.449656)
		(end 169.43 154.449656)
		(width 0.1)
		(layer "In4.Cu")
		(net 623)
	)
	(segment
		(start 173.975 152.61)
		(end 173.975 152.465)
		(width 0.1)
		(layer "In4.Cu")
		(net 623)
	)
	(segment
		(start 173.195966 153.540378)
		(end 172.524215 152.868627)
		(width 0.1)
		(layer "In4.Cu")
		(net 623)
	)
	(segment
		(start 173.478809 153.540378)
		(end 173.478808 153.540378)
		(width 0.1)
		(layer "In4.Cu")
		(net 623)
	)
	(segment
		(start 170.205172 154.224828)
		(end 170.205172 154.224827)
		(width 0.1)
		(layer "In4.Cu")
		(net 623)
	)
	(segment
		(start 171.675687 153.434313)
		(end 171.675685 153.434312)
		(width 0.1)
		(layer "In4.Cu")
		(net 623)
	)
	(segment
		(start 180 151.67)
		(end 179.66 152.01)
		(width 0.1)
		(layer "In4.Cu")
		(net 623)
	)
	(segment
		(start 175.025 152.465)
		(end 175.025 152.73)
		(width 0.1)
		(layer "In4.Cu")
		(net 623)
	)
	(segment
		(start 172.807057 153.717155)
		(end 172.807057 153.717154)
		(width 0.1)
		(layer "In4.Cu")
		(net 623)
	)
	(segment
		(start 178.01 152.29)
		(end 175.2 152.29)
		(width 0.1)
		(layer "In4.Cu")
		(net 623)
	)
	(segment
		(start 169.205172 154.224828)
		(end 169.205172 154.224827)
		(width 0.1)
		(layer "In4.Cu")
		(net 623)
	)
	(segment
		(start 172.029239 154.353552)
		(end 172.029238 154.353552)
		(width 0.1)
		(layer "In4.Cu")
		(net 623)
	)
	(segment
		(start 169.980344 153.999999)
		(end 169.93 153.999999)
		(width 0.1)
		(layer "In4.Cu")
		(net 623)
	)
	(arc
		(start 173.215 152.465)
		(mid 173.163744 152.341256)
		(end 173.04 152.29)
		(width 0.1)
		(layer "In4.Cu")
		(net 623)
	)
	(arc
		(start 174.15 153.59)
		(mid 174.026256 153.538744)
		(end 173.975 153.415)
		(width 0.1)
		(layer "In4.Cu")
		(net 623)
	)
	(arc
		(start 171.392843 153.999999)
		(mid 171.251422 153.941421)
		(end 171.110001 153.999999)
		(width 0.1)
		(layer "In4.Cu")
		(net 623)
	)
	(arc
		(start 170.93 153.999999)
		(mid 170.771023 154.06585)
		(end 170.705172 154.224827)
		(width 0.1)
		(layer "In4.Cu")
		(net 623)
	)
	(arc
		(start 173.85 153.085)
		(mid 173.761612 153.048388)
		(end 173.725 152.96)
		(width 0.1)
		(layer "In4.Cu")
		(net 623)
	)
	(arc
		(start 174.5 152.29)
		(mid 174.376256 152.341256)
		(end 174.325 152.465)
		(width 0.1)
		(layer "In4.Cu")
		(net 623)
	)
	(arc
		(start 169.43 154.449656)
		(mid 169.271023 154.383805)
		(end 169.205172 154.224828)
		(width 0.1)
		(layer "In4.Cu")
		(net 623)
	)
	(arc
		(start 172.807057 153.717154)
		(mid 172.865636 153.858576)
		(end 172.807057 153.999998)
		(width 0.1)
		(layer "In4.Cu")
		(net 623)
	)
	(arc
		(start 173.725 152.86)
		(mid 173.761612 152.771612)
		(end 173.85 152.735)
		(width 0.1)
		(layer "In4.Cu")
		(net 623)
	)
	(arc
		(start 172.029238 154.353552)
		(mid 171.887817 154.41213)
		(end 171.746396 154.353552)
		(width 0.1)
		(layer "In4.Cu")
		(net 623)
	)
	(arc
		(start 169.93 153.999999)
		(mid 169.771023 154.06585)
		(end 169.705172 154.224827)
		(width 0.1)
		(layer "In4.Cu")
		(net 623)
	)
	(arc
		(start 172.029239 154.070708)
		(mid 172.087818 154.21213)
		(end 172.029239 154.353552)
		(width 0.1)
		(layer "In4.Cu")
		(net 623)
	)
	(arc
		(start 173.74 152.29)
		(mid 173.616256 152.341256)
		(end 173.565 152.465)
		(width 0.1)
		(layer "In4.Cu")
		(net 623)
	)
	(arc
		(start 170.205172 154.224827)
		(mid 170.139321 154.06585)
		(end 169.980344 153.999999)
		(width 0.1)
		(layer "In4.Cu")
		(net 623)
	)
	(arc
		(start 171.675685 153.434313)
		(mid 171.617107 153.575734)
		(end 171.675685 153.717155)
		(width 0.1)
		(layer "In4.Cu")
		(net 623)
	)
	(arc
		(start 169.205172 154.224827)
		(mid 169.139321 154.06585)
		(end 168.980344 153.999999)
		(width 0.1)
		(layer "In4.Cu")
		(net 623)
	)
	(arc
		(start 173.478808 153.540378)
		(mid 173.337387 153.598956)
		(end 173.195966 153.540378)
		(width 0.1)
		(layer "In4.Cu")
		(net 623)
	)
	(arc
		(start 174.85 152.905)
		(mid 174.726256 152.853744)
		(end 174.675 152.73)
		(width 0.1)
		(layer "In4.Cu")
		(net 623)
	)
	(arc
		(start 171.958529 153.434313)
		(mid 171.817108 153.375735)
		(end 171.675687 153.434313)
		(width 0.1)
		(layer "In4.Cu")
		(net 623)
	)
	(arc
		(start 175.025 152.73)
		(mid 174.973744 152.853744)
		(end 174.85 152.905)
		(width 0.1)
		(layer "In4.Cu")
		(net 623)
	)
	(arc
		(start 172.241371 152.868627)
		(mid 172.182793 153.010048)
		(end 172.241371 153.151469)
		(width 0.1)
		(layer "In4.Cu")
		(net 623)
	)
	(arc
		(start 174.325 153.415)
		(mid 174.273744 153.538744)
		(end 174.15 153.59)
		(width 0.1)
		(layer "In4.Cu")
		(net 623)
	)
	(arc
		(start 174.675 152.465)
		(mid 174.623744 152.341256)
		(end 174.5 152.29)
		(width 0.1)
		(layer "In4.Cu")
		(net 623)
	)
	(arc
		(start 173.478809 153.257534)
		(mid 173.537388 153.398956)
		(end 173.478809 153.540378)
		(width 0.1)
		(layer "In4.Cu")
		(net 623)
	)
	(arc
		(start 173.39 152.64)
		(mid 173.266256 152.588744)
		(end 173.215 152.465)
		(width 0.1)
		(layer "In4.Cu")
		(net 623)
	)
	(arc
		(start 169.705172 154.224828)
		(mid 169.639321 154.383805)
		(end 169.480344 154.449656)
		(width 0.1)
		(layer "In4.Cu")
		(net 623)
	)
	(arc
		(start 172.524215 152.868627)
		(mid 172.382794 152.810049)
		(end 172.241373 152.868627)
		(width 0.1)
		(layer "In4.Cu")
		(net 623)
	)
	(arc
		(start 173.85 152.735)
		(mid 173.938388 152.698388)
		(end 173.975 152.61)
		(width 0.1)
		(layer "In4.Cu")
		(net 623)
	)
	(arc
		(start 173.975 153.21)
		(mid 173.938388 153.121612)
		(end 173.85 153.085)
		(width 0.1)
		(layer "In4.Cu")
		(net 623)
	)
	(arc
		(start 172.807056 153.999998)
		(mid 172.665635 154.058576)
		(end 172.524214 153.999998)
		(width 0.1)
		(layer "In4.Cu")
		(net 623)
	)
	(arc
		(start 172.807057 152.302941)
		(mid 172.748479 152.444362)
		(end 172.807057 152.585783)
		(width 0.1)
		(layer "In4.Cu")
		(net 623)
	)
	(arc
		(start 173.565 152.465)
		(mid 173.513744 152.588744)
		(end 173.39 152.64)
		(width 0.1)
		(layer "In4.Cu")
		(net 623)
	)
	(arc
		(start 170.43 154.449656)
		(mid 170.271023 154.383805)
		(end 170.205172 154.224828)
		(width 0.1)
		(layer "In4.Cu")
		(net 623)
	)
	(arc
		(start 173.975 152.465)
		(mid 173.923744 152.341256)
		(end 173.8 152.29)
		(width 0.1)
		(layer "In4.Cu")
		(net 623)
	)
	(arc
		(start 170.705172 154.224828)
		(mid 170.639321 154.383805)
		(end 170.480344 154.449656)
		(width 0.1)
		(layer "In4.Cu")
		(net 623)
	)
	(arc
		(start 175.2 152.29)
		(mid 175.076256 152.341256)
		(end 175.025 152.465)
		(width 0.1)
		(layer "In4.Cu")
		(net 623)
	)
	(segment
		(start 181.9995 150.9995)
		(end 181.5 150.5)
		(width 0.256)
		(layer "F.Cu")
		(net 624)
	)
	(segment
		(start 167.1 152.5)
		(end 166.6 153)
		(width 0.256)
		(layer "F.Cu")
		(net 624)
	)
	(via
		(at 166.6 153)
		(size 0.45)
		(drill 0.1)
		(layers "F.Cu" "B.Cu")
		(remove_unused_layers yes)
		(keep_end_layers yes)
		(zone_layer_connections)
		(net 624)
	)
	(via
		(at 181.5 150.5)
		(size 0.45)
		(drill 0.1)
		(layers "F.Cu" "B.Cu")
		(remove_unused_layers yes)
		(keep_end_layers yes)
		(zone_layer_connections)
		(net 624)
	)
	(segment
		(start 168.28 155.38)
		(end 167.25 156.41)
		(width 0.1)
		(layer "In4.Cu")
		(net 624)
	)
	(segment
		(start 181.97 151.78)
		(end 181.68 152.07)
		(width 0.1)
		(layer "In4.Cu")
		(net 624)
	)
	(segment
		(start 165.23 156.41)
		(end 164.11 155.29)
		(width 0.1)
		(layer "In4.Cu")
		(net 624)
	)
	(segment
		(start 181.68 152.07)
		(end 181.21 152.07)
		(width 0.1)
		(layer "In4.Cu")
		(net 624)
	)
	(segment
		(start 165.1 153.75)
		(end 165.35 153.5)
		(width 0.1)
		(layer "In4.Cu")
		(net 624)
	)
	(segment
		(start 165.1 154.19)
		(end 165.1 153.75)
		(width 0.1)
		(layer "In4.Cu")
		(net 624)
	)
	(segment
		(start 164.4 154.49)
		(end 164.8 154.49)
		(width 0.1)
		(layer "In4.Cu")
		(net 624)
	)
	(segment
		(start 167.25 156.41)
		(end 165.23 156.41)
		(width 0.1)
		(layer "In4.Cu")
		(net 624)
	)
	(segment
		(start 164.11 154.78)
		(end 164.4 154.49)
		(width 0.1)
		(layer "In4.Cu")
		(net 624)
	)
	(segment
		(start 181.21 152.07)
		(end 180 153.28)
		(width 0.1)
		(layer "In4.Cu")
		(net 624)
	)
	(segment
		(start 166.3 153)
		(end 166.6 153)
		(width 0.1)
		(layer "In4.Cu")
		(net 624)
	)
	(segment
		(start 180 153.28)
		(end 180 153.71)
		(width 0.1)
		(layer "In4.Cu")
		(net 624)
	)
	(segment
		(start 181.5 150.8)
		(end 181.97 151.27)
		(width 0.1)
		(layer "In4.Cu")
		(net 624)
	)
	(segment
		(start 174.66 154.43)
		(end 173.62 154.43)
		(width 0.1)
		(layer "In4.Cu")
		(net 624)
	)
	(segment
		(start 175.1 153.99)
		(end 174.66 154.43)
		(width 0.1)
		(layer "In4.Cu")
		(net 624)
	)
	(segment
		(start 164.11 155.29)
		(end 164.11 154.78)
		(width 0.1)
		(layer "In4.Cu")
		(net 624)
	)
	(segment
		(start 180 153.71)
		(end 179.72 153.99)
		(width 0.1)
		(layer "In4.Cu")
		(net 624)
	)
	(segment
		(start 164.8 154.49)
		(end 165.1 154.19)
		(width 0.1)
		(layer "In4.Cu")
		(net 624)
	)
	(segment
		(start 165.8 153.5)
		(end 166.3 153)
		(width 0.1)
		(layer "In4.Cu")
		(net 624)
	)
	(segment
		(start 179.72 153.99)
		(end 175.1 153.99)
		(width 0.1)
		(layer "In4.Cu")
		(net 624)
	)
	(segment
		(start 173.62 154.43)
		(end 172.67 155.38)
		(width 0.1)
		(layer "In4.Cu")
		(net 624)
	)
	(segment
		(start 165.35 153.5)
		(end 165.8 153.5)
		(width 0.1)
		(layer "In4.Cu")
		(net 624)
	)
	(segment
		(start 181.97 151.27)
		(end 181.97 151.78)
		(width 0.1)
		(layer "In4.Cu")
		(net 624)
	)
	(segment
		(start 172.67 155.38)
		(end 168.28 155.38)
		(width 0.1)
		(layer "In4.Cu")
		(net 624)
	)
	(segment
		(start 181.5 150.5)
		(end 181.5 150.8)
		(width 0.1)
		(layer "In4.Cu")
		(net 624)
	)
	(segment
		(start 251.324499 137.899)
		(end 251.474499 138.049)
		(width 0.15)
		(layer "F.Cu")
		(net 625)
	)
	(segment
		(start 256.564998 138.889499)
		(end 256.564998 139.35)
		(width 0.15)
		(layer "F.Cu")
		(net 625)
	)
	(segment
		(start 251.474499 138.049)
		(end 255.724499 138.049)
		(width 0.15)
		(layer "F.Cu")
		(net 625)
	)
	(segment
		(start 256.561998 139.353)
		(end 255.239499 139.353)
		(width 0.256)
		(layer "F.Cu")
		(net 625)
	)
	(segment
		(start 255.724499 138.049)
		(end 256.564998 138.889499)
		(width 0.15)
		(layer "F.Cu")
		(net 625)
	)
	(segment
		(start 256.564998 139.35)
		(end 256.561998 139.353)
		(width 0.256)
		(layer "F.Cu")
		(net 625)
	)
	(via
		(at 256.564998 139.35)
		(size 0.45)
		(drill 0.1)
		(layers "F.Cu" "B.Cu")
		(remove_unused_layers yes)
		(keep_end_layers yes)
		(zone_layer_connections)
		(net 625)
	)
	(segment
		(start 256.564998 139.35)
		(end 255.873499 139.35)
		(width 0.256)
		(layer "B.Cu")
		(net 625)
	)
	(segment
		(start 255.773499 138.254)
		(end 255.769499 138.25)
		(width 0.256)
		(layer "B.Cu")
		(net 625)
	)
	(segment
		(start 255.873499 139.35)
		(end 255.773499 139.25)
		(width 0.256)
		(layer "B.Cu")
		(net 625)
	)
	(segment
		(start 255.773499 139.25)
		(end 255.773499 138.254)
		(width 0.256)
		(layer "B.Cu")
		(net 625)
	)
	(segment
		(start 200.0005 150.9995)
		(end 200.5 150.5)
		(width 0.256)
		(layer "F.Cu")
		(net 626)
	)
	(segment
		(start 241.001 143.1)
		(end 240 143.1)
		(width 0.256)
		(layer "F.Cu")
		(net 626)
	)
	(via
		(at 200.5 150.5)
		(size 0.45)
		(drill 0.1)
		(layers "F.Cu" "B.Cu")
		(remove_unused_layers yes)
		(keep_end_layers yes)
		(zone_layer_connections)
		(net 626)
	)
	(via
		(at 240 143.1)
		(size 0.45)
		(drill 0.1)
		(layers "F.Cu" "B.Cu")
		(remove_unused_layers yes)
		(keep_end_layers yes)
		(zone_layer_connections)
		(net 626)
	)
	(segment
		(start 239.257999 143.09)
		(end 239.99 143.09)
		(width 0.15)
		(layer "B.Cu")
		(net 626)
	)
	(segment
		(start 239.99 143.09)
		(end 240 143.1)
		(width 0.1)
		(layer "B.Cu")
		(net 626)
	)
	(segment
		(start 219.68 147.61)
		(end 235.49 147.61)
		(width 0.1)
		(layer "In6.Cu")
		(net 626)
	)
	(segment
		(start 201.81 149.97)
		(end 204.6 147.18)
		(width 0.1)
		(layer "In6.Cu")
		(net 626)
	)
	(segment
		(start 235.49 147.61)
		(end 240 143.1)
		(width 0.1)
		(layer "In6.Cu")
		(net 626)
	)
	(segment
		(start 200.5 150.5)
		(end 201.03 149.97)
		(width 0.1)
		(layer "In6.Cu")
		(net 626)
	)
	(segment
		(start 219.25 147.18)
		(end 219.68 147.61)
		(width 0.1)
		(layer "In6.Cu")
		(net 626)
	)
	(segment
		(start 201.03 149.97)
		(end 201.81 149.97)
		(width 0.1)
		(layer "In6.Cu")
		(net 626)
	)
	(segment
		(start 204.6 147.18)
		(end 219.25 147.18)
		(width 0.1)
		(layer "In6.Cu")
		(net 626)
	)
	(segment
		(start 183.5005 162.4995)
		(end 184 162)
		(width 0.256)
		(layer "F.Cu")
		(net 627)
	)
	(via
		(at 183.5005 162.4995)
		(size 0.45)
		(drill 0.1)
		(layers "F.Cu" "B.Cu")
		(remove_unused_layers yes)
		(keep_end_layers yes)
		(zone_layer_connections)
		(net 627)
	)
	(segment
		(start 183.5005 162.28021)
		(end 183.5005 162.4995)
		(width 0.1)
		(layer "B.Cu")
		(net 627)
	)
	(segment
		(start 183.384996 166.144618)
		(end 183.384996 166.129114)
		(width 0.1)
		(layer "B.Cu")
		(net 627)
	)
	(segment
		(start 183.4905 166.9695)
		(end 183.4905 166.957)
		(width 0.1)
		(layer "B.Cu")
		(net 627)
	)
	(segment
		(start 183.321211 162.1095)
		(end 183.329789 162.1095)
		(width 0.1)
		(layer "B.Cu")
		(net 627)
	)
	(segment
		(start 183.481661 166.935661)
		(end 183.189161 166.643161)
		(width 0.1)
		(layer "B.Cu")
		(net 627)
	)
	(segment
		(start 183.171211 162.180211)
		(end 183.185856 162.165565)
		(width 0.1)
		(layer "B.Cu")
		(net 627)
	)
	(segment
		(start 183.1005 165.829114)
		(end 183.1005 162.350922)
		(width 0.1)
		(layer "B.Cu")
		(net 627)
	)
	(segment
		(start 183.1005 165.844618)
		(end 183.1005 165.829114)
		(width 0.1)
		(layer "B.Cu")
		(net 627)
	)
	(arc
		(start 183.185856 162.165565)
		(mid 183.247957 162.12407)
		(end 183.321211 162.1095)
		(width 0.1)
		(layer "B.Cu")
		(net 627)
	)
	(arc
		(start 183.4905 166.957)
		(mid 183.488202 166.945451)
		(end 183.481661 166.935661)
		(width 0.1)
		(layer "B.Cu")
		(net 627)
	)
	(arc
		(start 183.1005 162.350922)
		(mid 183.118877 162.258533)
		(end 183.171211 162.180211)
		(width 0.1)
		(layer "B.Cu")
		(net 627)
	)
	(arc
		(start 183.329789 162.1095)
		(mid 183.395117 162.122494)
		(end 183.4505 162.1595)
		(width 0.1)
		(layer "B.Cu")
		(net 627)
	)
	(arc
		(start 183.189161 166.643161)
		(mid 183.123542 166.544955)
		(end 183.1005 166.429114)
		(width 0.1)
		(layer "B.Cu")
		(net 627)
	)
	(arc
		(start 183.4505 162.1595)
		(mid 183.487505 162.214882)
		(end 183.5005 162.28021)
		(width 0.1)
		(layer "B.Cu")
		(net 627)
	)
	(arc
		(start 183.1005 166.429114)
		(mid 183.142163 166.328529)
		(end 183.242748 166.286866)
		(width 0.1)
		(layer "B.Cu")
		(net 627)
	)
	(arc
		(start 183.384996 166.129114)
		(mid 183.343333 166.028529)
		(end 183.242748 165.986866)
		(width 0.1)
		(layer "B.Cu")
		(net 627)
	)
	(arc
		(start 183.242748 165.986866)
		(mid 183.142163 165.945203)
		(end 183.1005 165.844618)
		(width 0.1)
		(layer "B.Cu")
		(net 627)
	)
	(arc
		(start 183.242748 166.286866)
		(mid 183.343333 166.245203)
		(end 183.384996 166.144618)
		(width 0.1)
		(layer "B.Cu")
		(net 627)
	)
	(segment
		(start 183.5005 161.4995)
		(end 184 161)
		(width 0.256)
		(layer "F.Cu")
		(net 628)
	)
	(via
		(at 183.5005 161.4995)
		(size 0.45)
		(drill 0.1)
		(layers "F.Cu" "B.Cu")
		(remove_unused_layers yes)
		(keep_end_layers yes)
		(zone_layer_connections)
		(net 628)
	)
	(segment
		(start 183.5005 161.738789)
		(end 183.5005 161.4995)
		(width 0.1)
		(layer "B.Cu")
		(net 628)
	)
	(segment
		(start 182.519339 166.935661)
		(end 182.7055 166.749499)
		(width 0.1)
		(layer "B.Cu")
		(net 628)
	)
	(segment
		(start 183.279789 161.9095)
		(end 183.329789 161.9095)
		(width 0.1)
		(layer "B.Cu")
		(net 628)
	)
	(segment
		(start 182.9005 165.628728)
		(end 182.9005 162.35092)
		(width 0.1)
		(layer "B.Cu")
		(net 628)
	)
	(segment
		(start 182.9005 166.278728)
		(end 182.9005 165.628728)
		(width 0.1)
		(layer "B.Cu")
		(net 628)
	)
	(segment
		(start 182.510501 166.9695)
		(end 182.510501 166.957)
		(width 0.1)
		(layer "B.Cu")
		(net 628)
	)
	(segment
		(start 183.029788 162.038788)
		(end 183.073722 161.994855)
		(width 0.1)
		(layer "B.Cu")
		(net 628)
	)
	(arc
		(start 183.4505 161.8595)
		(mid 183.487505 161.804117)
		(end 183.5005 161.738789)
		(width 0.1)
		(layer "B.Cu")
		(net 628)
	)
	(arc
		(start 182.9005 162.35092)
		(mid 182.9341 162.181995)
		(end 183.029788 162.038788)
		(width 0.1)
		(layer "B.Cu")
		(net 628)
	)
	(arc
		(start 182.7055 166.749499)
		(mid 182.849821 166.533507)
		(end 182.9005 166.278728)
		(width 0.1)
		(layer "B.Cu")
		(net 628)
	)
	(arc
		(start 182.510501 166.957)
		(mid 182.512797 166.945451)
		(end 182.519339 166.935661)
		(width 0.1)
		(layer "B.Cu")
		(net 628)
	)
	(arc
		(start 183.329789 161.9095)
		(mid 183.395117 161.896505)
		(end 183.4505 161.8595)
		(width 0.1)
		(layer "B.Cu")
		(net 628)
	)
	(arc
		(start 183.073722 161.994855)
		(mid 183.168266 161.931683)
		(end 183.279789 161.9095)
		(width 0.1)
		(layer "B.Cu")
		(net 628)
	)
	(segment
		(start 185.5 162.5)
		(end 185.9995 162.0005)
		(width 0.256)
		(layer "F.Cu")
		(net 629)
	)
	(via
		(at 185.5 162.5)
		(size 0.45)
		(drill 0.1)
		(layers "F.Cu" "B.Cu")
		(remove_unused_layers yes)
		(keep_end_layers yes)
		(zone_layer_connections)
		(net 629)
	)
	(segment
		(start 185.481161 166.936161)
		(end 185.188661 166.643661)
		(width 0.1)
		(layer "B.Cu")
		(net 629)
	)
	(segment
		(start 185.1 165.845118)
		(end 185.1 165.829614)
		(width 0.1)
		(layer "B.Cu")
		(net 629)
	)
	(segment
		(start 185.384496 166.145118)
		(end 185.384496 166.129614)
		(width 0.1)
		(layer "B.Cu")
		(net 629)
	)
	(segment
		(start 185.5 162.28071)
		(end 185.5 162.5)
		(width 0.1)
		(layer "B.Cu")
		(net 629)
	)
	(segment
		(start 185.1 165.829614)
		(end 185.1 162.351422)
		(width 0.1)
		(layer "B.Cu")
		(net 629)
	)
	(segment
		(start 185.49 166.97)
		(end 185.49 166.9575)
		(width 0.1)
		(layer "B.Cu")
		(net 629)
	)
	(segment
		(start 185.320711 162.11)
		(end 185.329289 162.11)
		(width 0.1)
		(layer "B.Cu")
		(net 629)
	)
	(segment
		(start 185.170711 162.180711)
		(end 185.185356 162.166065)
		(width 0.1)
		(layer "B.Cu")
		(net 629)
	)
	(arc
		(start 185.49 166.9575)
		(mid 185.487702 166.945951)
		(end 185.481161 166.936161)
		(width 0.1)
		(layer "B.Cu")
		(net 629)
	)
	(arc
		(start 185.1 162.351422)
		(mid 185.118377 162.259033)
		(end 185.170711 162.180711)
		(width 0.1)
		(layer "B.Cu")
		(net 629)
	)
	(arc
		(start 185.384496 166.129614)
		(mid 185.342833 166.029029)
		(end 185.242248 165.987366)
		(width 0.1)
		(layer "B.Cu")
		(net 629)
	)
	(arc
		(start 185.45 162.16)
		(mid 185.487005 162.215382)
		(end 185.5 162.28071)
		(width 0.1)
		(layer "B.Cu")
		(net 629)
	)
	(arc
		(start 185.242248 165.987366)
		(mid 185.141663 165.945703)
		(end 185.1 165.845118)
		(width 0.1)
		(layer "B.Cu")
		(net 629)
	)
	(arc
		(start 185.1 166.429614)
		(mid 185.141663 166.329029)
		(end 185.242248 166.287366)
		(width 0.1)
		(layer "B.Cu")
		(net 629)
	)
	(arc
		(start 185.188661 166.643661)
		(mid 185.123042 166.545455)
		(end 185.1 166.429614)
		(width 0.1)
		(layer "B.Cu")
		(net 629)
	)
	(arc
		(start 185.242248 166.287366)
		(mid 185.342833 166.245703)
		(end 185.384496 166.145118)
		(width 0.1)
		(layer "B.Cu")
		(net 629)
	)
	(arc
		(start 185.185356 162.166065)
		(mid 185.247457 162.12457)
		(end 185.320711 162.11)
		(width 0.1)
		(layer "B.Cu")
		(net 629)
	)
	(arc
		(start 185.329289 162.11)
		(mid 185.394617 162.122994)
		(end 185.45 162.16)
		(width 0.1)
		(layer "B.Cu")
		(net 629)
	)
	(segment
		(start 185.5 161.5)
		(end 185.9995 161.0005)
		(width 0.256)
		(layer "F.Cu")
		(net 630)
	)
	(via
		(at 185.5 161.5)
		(size 0.45)
		(drill 0.1)
		(layers "F.Cu" "B.Cu")
		(remove_unused_layers yes)
		(keep_end_layers yes)
		(zone_layer_connections)
		(net 630)
	)
	(segment
		(start 184.510001 166.97)
		(end 184.510001 166.9575)
		(width 0.1)
		(layer "B.Cu")
		(net 630)
	)
	(segment
		(start 185.5 161.739289)
		(end 185.5 161.5)
		(width 0.1)
		(layer "B.Cu")
		(net 630)
	)
	(segment
		(start 184.9 166.279228)
		(end 184.9 165.629228)
		(width 0.1)
		(layer "B.Cu")
		(net 630)
	)
	(segment
		(start 184.518839 166.936161)
		(end 184.705 166.749999)
		(width 0.1)
		(layer "B.Cu")
		(net 630)
	)
	(segment
		(start 184.9 165.629228)
		(end 184.9 162.35142)
		(width 0.1)
		(layer "B.Cu")
		(net 630)
	)
	(segment
		(start 185.029288 162.039288)
		(end 185.073222 161.995355)
		(width 0.1)
		(layer "B.Cu")
		(net 630)
	)
	(segment
		(start 185.279289 161.91)
		(end 185.329289 161.91)
		(width 0.1)
		(layer "B.Cu")
		(net 630)
	)
	(arc
		(start 184.9 162.35142)
		(mid 184.9336 162.182495)
		(end 185.029288 162.039288)
		(width 0.1)
		(layer "B.Cu")
		(net 630)
	)
	(arc
		(start 184.705 166.749999)
		(mid 184.849321 166.534007)
		(end 184.9 166.279228)
		(width 0.1)
		(layer "B.Cu")
		(net 630)
	)
	(arc
		(start 185.45 161.86)
		(mid 185.487005 161.804617)
		(end 185.5 161.739289)
		(width 0.1)
		(layer "B.Cu")
		(net 630)
	)
	(arc
		(start 185.073222 161.995355)
		(mid 185.167766 161.932183)
		(end 185.279289 161.91)
		(width 0.1)
		(layer "B.Cu")
		(net 630)
	)
	(arc
		(start 185.329289 161.91)
		(mid 185.394617 161.897005)
		(end 185.45 161.86)
		(width 0.1)
		(layer "B.Cu")
		(net 630)
	)
	(arc
		(start 184.510001 166.9575)
		(mid 184.512297 166.945951)
		(end 184.518839 166.936161)
		(width 0.1)
		(layer "B.Cu")
		(net 630)
	)
	(segment
		(start 187.5005 162.4995)
		(end 188 162)
		(width 0.256)
		(layer "F.Cu")
		(net 631)
	)
	(via
		(at 187.5005 162.4995)
		(size 0.45)
		(drill 0.1)
		(layers "F.Cu" "B.Cu")
		(remove_unused_layers yes)
		(keep_end_layers yes)
		(zone_layer_connections)
		(net 631)
	)
	(segment
		(start 187.1005 165.844618)
		(end 187.1005 165.829114)
		(width 0.1)
		(layer "B.Cu")
		(net 631)
	)
	(segment
		(start 187.171211 162.180211)
		(end 187.185856 162.165565)
		(width 0.1)
		(layer "B.Cu")
		(net 631)
	)
	(segment
		(start 187.321211 162.1095)
		(end 187.329789 162.1095)
		(width 0.1)
		(layer "B.Cu")
		(net 631)
	)
	(segment
		(start 187.5005 162.28021)
		(end 187.5005 162.4995)
		(width 0.1)
		(layer "B.Cu")
		(net 631)
	)
	(segment
		(start 187.1005 165.829114)
		(end 187.1005 162.350922)
		(width 0.1)
		(layer "B.Cu")
		(net 631)
	)
	(segment
		(start 187.4905 166.9695)
		(end 187.4905 166.957)
		(width 0.1)
		(layer "B.Cu")
		(net 631)
	)
	(segment
		(start 187.481661 166.935661)
		(end 187.189161 166.643161)
		(width 0.1)
		(layer "B.Cu")
		(net 631)
	)
	(segment
		(start 187.384996 166.144618)
		(end 187.384996 166.129114)
		(width 0.1)
		(layer "B.Cu")
		(net 631)
	)
	(arc
		(start 187.384996 166.129114)
		(mid 187.343333 166.028529)
		(end 187.242748 165.986866)
		(width 0.1)
		(layer "B.Cu")
		(net 631)
	)
	(arc
		(start 187.242748 166.286866)
		(mid 187.343333 166.245203)
		(end 187.384996 166.144618)
		(width 0.1)
		(layer "B.Cu")
		(net 631)
	)
	(arc
		(start 187.1005 166.429114)
		(mid 187.142163 166.328529)
		(end 187.242748 166.286866)
		(width 0.1)
		(layer "B.Cu")
		(net 631)
	)
	(arc
		(start 187.4505 162.1595)
		(mid 187.487505 162.214882)
		(end 187.5005 162.28021)
		(width 0.1)
		(layer "B.Cu")
		(net 631)
	)
	(arc
		(start 187.189161 166.643161)
		(mid 187.123542 166.544955)
		(end 187.1005 166.429114)
		(width 0.1)
		(layer "B.Cu")
		(net 631)
	)
	(arc
		(start 187.1005 162.350922)
		(mid 187.118877 162.258533)
		(end 187.171211 162.180211)
		(width 0.1)
		(layer "B.Cu")
		(net 631)
	)
	(arc
		(start 187.185856 162.165565)
		(mid 187.247957 162.12407)
		(end 187.321211 162.1095)
		(width 0.1)
		(layer "B.Cu")
		(net 631)
	)
	(arc
		(start 187.329789 162.1095)
		(mid 187.395117 162.122494)
		(end 187.4505 162.1595)
		(width 0.1)
		(layer "B.Cu")
		(net 631)
	)
	(arc
		(start 187.4905 166.957)
		(mid 187.488202 166.945451)
		(end 187.481661 166.935661)
		(width 0.1)
		(layer "B.Cu")
		(net 631)
	)
	(arc
		(start 187.242748 165.986866)
		(mid 187.142163 165.945203)
		(end 187.1005 165.844618)
		(width 0.1)
		(layer "B.Cu")
		(net 631)
	)
	(segment
		(start 187.5005 161.4995)
		(end 188 161)
		(width 0.256)
		(layer "F.Cu")
		(net 632)
	)
	(via
		(at 187.5005 161.4995)
		(size 0.45)
		(drill 0.1)
		(layers "F.Cu" "B.Cu")
		(remove_unused_layers yes)
		(keep_end_layers yes)
		(zone_layer_connections)
		(net 632)
	)
	(segment
		(start 187.029788 162.038788)
		(end 187.073722 161.994855)
		(width 0.1)
		(layer "B.Cu")
		(net 632)
	)
	(segment
		(start 186.519339 166.935661)
		(end 186.7055 166.749499)
		(width 0.1)
		(layer "B.Cu")
		(net 632)
	)
	(segment
		(start 186.9005 165.628728)
		(end 186.9005 162.35092)
		(width 0.1)
		(layer "B.Cu")
		(net 632)
	)
	(segment
		(start 187.5005 161.738789)
		(end 187.5005 161.4995)
		(width 0.1)
		(layer "B.Cu")
		(net 632)
	)
	(segment
		(start 186.9005 166.278728)
		(end 186.9005 165.628728)
		(width 0.1)
		(layer "B.Cu")
		(net 632)
	)
	(segment
		(start 187.279789 161.9095)
		(end 187.329789 161.9095)
		(width 0.1)
		(layer "B.Cu")
		(net 632)
	)
	(segment
		(start 186.510501 166.9695)
		(end 186.510501 166.957)
		(width 0.1)
		(layer "B.Cu")
		(net 632)
	)
	(arc
		(start 187.4505 161.8595)
		(mid 187.487505 161.804117)
		(end 187.5005 161.738789)
		(width 0.1)
		(layer "B.Cu")
		(net 632)
	)
	(arc
		(start 186.7055 166.749499)
		(mid 186.849821 166.533507)
		(end 186.9005 166.278728)
		(width 0.1)
		(layer "B.Cu")
		(net 632)
	)
	(arc
		(start 187.329789 161.9095)
		(mid 187.395117 161.896505)
		(end 187.4505 161.8595)
		(width 0.1)
		(layer "B.Cu")
		(net 632)
	)
	(arc
		(start 187.073722 161.994855)
		(mid 187.168266 161.931683)
		(end 187.279789 161.9095)
		(width 0.1)
		(layer "B.Cu")
		(net 632)
	)
	(arc
		(start 186.9005 162.35092)
		(mid 186.9341 162.181995)
		(end 187.029788 162.038788)
		(width 0.1)
		(layer "B.Cu")
		(net 632)
	)
	(arc
		(start 186.510501 166.957)
		(mid 186.512797 166.945451)
		(end 186.519339 166.935661)
		(width 0.1)
		(layer "B.Cu")
		(net 632)
	)
	(segment
		(start 194.0005 139.9995)
		(end 194.5 139.5)
		(width 0.256)
		(layer "F.Cu")
		(net 633)
	)
	(segment
		(start 189.6 110.598)
		(end 189.6 111.75)
		(width 0.38)
		(layer "F.Cu")
		(net 633)
	)
	(via
		(at 189.6 111.75)
		(size 0.45)
		(drill 0.1)
		(layers "F.Cu" "B.Cu")
		(remove_unused_layers yes)
		(keep_end_layers yes)
		(zone_layer_connections)
		(net 633)
	)
	(via
		(at 194.5 139.5)
		(size 0.45)
		(drill 0.1)
		(layers "F.Cu" "B.Cu")
		(remove_unused_layers yes)
		(keep_end_layers yes)
		(zone_layer_connections)
		(net 633)
	)
	(segment
		(start 182.425 125.898222)
		(end 182.701778 126.175)
		(width 0.1)
		(layer "In9.Cu")
		(net 633)
	)
	(segment
		(start 185.675 119.101778)
		(end 183.225 121.551778)
		(width 0.1)
		(layer "In9.Cu")
		(net 633)
	)
	(segment
		(start 194.120252 128.143474)
		(end 194.120252 137.9)
		(width 0.1)
		(layer "In9.Cu")
		(net 633)
	)
	(segment
		(start 194.370252 138.75)
		(end 194.370252 138.8)
		(width 0.1)
		(layer "In9.Cu")
		(net 633)
	)
	(segment
		(start 182.701778 126.175)
		(end 183.85 126.175)
		(width 0.1)
		(layer "In9.Cu")
		(net 633)
	)
	(segment
		(start 194.370252 138.15)
		(end 194.370252 138.2)
		(width 0.1)
		(layer "In9.Cu")
		(net 633)
	)
	(segment
		(start 194.120252 139.175)
		(end 194.097726 139.197526)
		(width 0.1)
		(layer "In9.Cu")
		(net 633)
	)
	(segment
		(start 183.225 121.551778)
		(end 183.225 124.301778)
		(width 0.1)
		(layer "In9.Cu")
		(net 633)
	)
	(segment
		(start 194.097726 139.759831)
		(end 194.237895 139.9)
		(width 0.1)
		(layer "In9.Cu")
		(net 633)
	)
	(segment
		(start 194.5 139.85)
		(end 194.5 139.5)
		(width 0.1)
		(layer "In9.Cu")
		(net 633)
	)
	(segment
		(start 189.9 111.45)
		(end 189.9 111.126778)
		(width 0.1)
		(layer "In9.Cu")
		(net 633)
	)
	(segment
		(start 189.698222 110.925)
		(end 189.6 110.925)
		(width 0.1)
		(layer "In9.Cu")
		(net 633)
	)
	(segment
		(start 194.237895 139.9)
		(end 194.45 139.9)
		(width 0.1)
		(layer "In9.Cu")
		(net 633)
	)
	(segment
		(start 185.675 114.051778)
		(end 185.675 119.101778)
		(width 0.1)
		(layer "In9.Cu")
		(net 633)
	)
	(segment
		(start 188.9 110.925)
		(end 188.801778 110.925)
		(width 0.1)
		(layer "In9.Cu")
		(net 633)
	)
	(segment
		(start 184.375 125.65)
		(end 184.375 121.775)
		(width 0.1)
		(layer "In9.Cu")
		(net 633)
	)
	(segment
		(start 192.151778 126.175)
		(end 194.120252 128.143474)
		(width 0.1)
		(layer "In9.Cu")
		(net 633)
	)
	(segment
		(start 189.9 111.126778)
		(end 189.698222 110.925)
		(width 0.1)
		(layer "In9.Cu")
		(net 633)
	)
	(segment
		(start 187.175987 125.125)
		(end 186.25 125.125)
		(width 0.1)
		(layer "In9.Cu")
		(net 633)
	)
	(segment
		(start 194.120252 138.45)
		(end 194.120252 138.5)
		(width 0.1)
		(layer "In9.Cu")
		(net 633)
	)
	(segment
		(start 188.801778 110.925)
		(end 185.675 114.051778)
		(width 0.1)
		(layer "In9.Cu")
		(net 633)
	)
	(segment
		(start 189.425 111.1)
		(end 189.425 111.195751)
		(width 0.1)
		(layer "In9.Cu")
		(net 633)
	)
	(segment
		(start 186.25 123.975)
		(end 187.175987 123.975)
		(width 0.1)
		(layer "In9.Cu")
		(net 633)
	)
	(segment
		(start 187.67867 126.175)
		(end 192.151778 126.175)
		(width 0.1)
		(layer "In9.Cu")
		(net 633)
	)
	(segment
		(start 189.075 111.195751)
		(end 189.075 111.1)
		(width 0.1)
		(layer "In9.Cu")
		(net 633)
	)
	(segment
		(start 185.925 125.45)
		(end 185.925 125.65)
		(width 0.1)
		(layer "In9.Cu")
		(net 633)
	)
	(segment
		(start 189.6 111.75)
		(end 189.9 111.45)
		(width 0.1)
		(layer "In9.Cu")
		(net 633)
	)
	(segment
		(start 187.175987 123.325)
		(end 186.25 123.325)
		(width 0.1)
		(layer "In9.Cu")
		(net 633)
	)
	(segment
		(start 194.097726 139.197526)
		(end 194.097726 139.759831)
		(width 0.1)
		(layer "In9.Cu")
		(net 633)
	)
	(segment
		(start 185.925 121.775)
		(end 185.925 121.85)
		(width 0.1)
		(layer "In9.Cu")
		(net 633)
	)
	(segment
		(start 186.45 126.175)
		(end 187.67867 126.175)
		(width 0.1)
		(layer "In9.Cu")
		(net 633)
	)
	(segment
		(start 194.45 139.9)
		(end 194.5 139.85)
		(width 0.1)
		(layer "In9.Cu")
		(net 633)
	)
	(segment
		(start 183.225 124.301778)
		(end 182.425 125.101778)
		(width 0.1)
		(layer "In9.Cu")
		(net 633)
	)
	(segment
		(start 182.425 125.101778)
		(end 182.425 125.898222)
		(width 0.1)
		(layer "In9.Cu")
		(net 633)
	)
	(segment
		(start 194.120252 139.05)
		(end 194.120252 139.175)
		(width 0.1)
		(layer "In9.Cu")
		(net 633)
	)
	(segment
		(start 186.25 122.175)
		(end 187.175987 122.175)
		(width 0.1)
		(layer "In9.Cu")
		(net 633)
	)
	(arc
		(start 194.245252 138.925)
		(mid 194.156864 138.961612)
		(end 194.120252 139.05)
		(width 0.1)
		(layer "In9.Cu")
		(net 633)
	)
	(arc
		(start 185.15 121)
		(mid 185.698008 121.226992)
		(end 185.925 121.775)
		(width 0.1)
		(layer "In9.Cu")
		(net 633)
	)
	(arc
		(start 194.120252 138.5)
		(mid 194.156864 138.588388)
		(end 194.245252 138.625)
		(width 0.1)
		(layer "In9.Cu")
		(net 633)
	)
	(arc
		(start 194.370252 138.8)
		(mid 194.33364 138.888388)
		(end 194.245252 138.925)
		(width 0.1)
		(layer "In9.Cu")
		(net 633)
	)
	(arc
		(start 187.175987 122.175)
		(mid 187.582573 122.343414)
		(end 187.750987 122.75)
		(width 0.1)
		(layer "In9.Cu")
		(net 633)
	)
	(arc
		(start 189.075 111.1)
		(mid 189.023744 110.976256)
		(end 188.9 110.925)
		(width 0.1)
		(layer "In9.Cu")
		(net 633)
	)
	(arc
		(start 194.370252 138.2)
		(mid 194.33364 138.288388)
		(end 194.245252 138.325)
		(width 0.1)
		(layer "In9.Cu")
		(net 633)
	)
	(arc
		(start 194.120252 137.9)
		(mid 194.156864 137.988388)
		(end 194.245252 138.025)
		(width 0.1)
		(layer "In9.Cu")
		(net 633)
	)
	(arc
		(start 194.245252 138.325)
		(mid 194.156864 138.361612)
		(end 194.120252 138.45)
		(width 0.1)
		(layer "In9.Cu")
		(net 633)
	)
	(arc
		(start 184.375 121.775)
		(mid 184.601992 121.226992)
		(end 185.15 121)
		(width 0.1)
		(layer "In9.Cu")
		(net 633)
	)
	(arc
		(start 183.85 126.175)
		(mid 184.221231 126.021231)
		(end 184.375 125.65)
		(width 0.1)
		(layer "In9.Cu")
		(net 633)
	)
	(arc
		(start 187.750987 122.75)
		(mid 187.582573 123.156586)
		(end 187.175987 123.325)
		(width 0.1)
		(layer "In9.Cu")
		(net 633)
	)
	(arc
		(start 189.6 110.925)
		(mid 189.476256 110.976256)
		(end 189.425 111.1)
		(width 0.1)
		(layer "In9.Cu")
		(net 633)
	)
	(arc
		(start 187.175987 123.975)
		(mid 187.582573 124.143414)
		(end 187.750987 124.55)
		(width 0.1)
		(layer "In9.Cu")
		(net 633)
	)
	(arc
		(start 185.925 123.65)
		(mid 186.02019 123.87981)
		(end 186.25 123.975)
		(width 0.1)
		(layer "In9.Cu")
		(net 633)
	)
	(arc
		(start 194.245252 138.625)
		(mid 194.33364 138.661612)
		(end 194.370252 138.75)
		(width 0.1)
		(layer "In9.Cu")
		(net 633)
	)
	(arc
		(start 186.25 123.325)
		(mid 186.02019 123.42019)
		(end 185.925 123.65)
		(width 0.1)
		(layer "In9.Cu")
		(net 633)
	)
	(arc
		(start 187.750987 124.55)
		(mid 187.582573 124.956586)
		(end 187.175987 125.125)
		(width 0.1)
		(layer "In9.Cu")
		(net 633)
	)
	(arc
		(start 185.925 125.65)
		(mid 186.078769 126.021231)
		(end 186.45 126.175)
		(width 0.1)
		(layer "In9.Cu")
		(net 633)
	)
	(arc
		(start 185.925 121.85)
		(mid 186.02019 122.07981)
		(end 186.25 122.175)
		(width 0.1)
		(layer "In9.Cu")
		(net 633)
	)
	(arc
		(start 186.25 125.125)
		(mid 186.02019 125.22019)
		(end 185.925 125.45)
		(width 0.1)
		(layer "In9.Cu")
		(net 633)
	)
	(arc
		(start 189.25 111.370751)
		(mid 189.126256 111.319495)
		(end 189.075 111.195751)
		(width 0.1)
		(layer "In9.Cu")
		(net 633)
	)
	(arc
		(start 194.245252 138.025)
		(mid 194.33364 138.061612)
		(end 194.370252 138.15)
		(width 0.1)
		(layer "In9.Cu")
		(net 633)
	)
	(arc
		(start 189.425 111.195751)
		(mid 189.373744 111.319495)
		(end 189.25 111.370751)
		(width 0.1)
		(layer "In9.Cu")
		(net 633)
	)
	(segment
		(start 190.45 110.598)
		(end 190.45 111.75)
		(width 0.38)
		(layer "F.Cu")
		(net 634)
	)
	(segment
		(start 194.0005 140.9995)
		(end 194.5 140.5)
		(width 0.256)
		(layer "F.Cu")
		(net 634)
	)
	(via
		(at 190.45 111.75)
		(size 0.45)
		(drill 0.1)
		(layers "F.Cu" "B.Cu")
		(remove_unused_layers yes)
		(keep_end_layers yes)
		(zone_layer_connections)
		(net 634)
	)
	(via
		(at 194.5 140.5)
		(size 0.45)
		(drill 0.1)
		(layers "F.Cu" "B.Cu")
		(remove_unused_layers yes)
		(keep_end_layers yes)
		(zone_layer_connections)
		(net 634)
	)
	(segment
		(start 182.598222 126.425)
		(end 183.85 126.425)
		(width 0.1)
		(layer "In9.Cu")
		(net 634)
	)
	(segment
		(start 185.425 113.948222)
		(end 185.425 118.998222)
		(width 0.1)
		(layer "In9.Cu")
		(net 634)
	)
	(segment
		(start 185.425 118.998222)
		(end 182.975 121.448222)
		(width 0.1)
		(layer "In9.Cu")
		(net 634)
	)
	(segment
		(start 186.25 124.225)
		(end 187.175987 124.225)
		(width 0.1)
		(layer "In9.Cu")
		(net 634)
	)
	(segment
		(start 184.625 125.65)
		(end 184.625 121.775)
		(width 0.1)
		(layer "In9.Cu")
		(net 634)
	)
	(segment
		(start 192.048222 126.425)
		(end 193.870252 128.24703)
		(width 0.1)
		(layer "In9.Cu")
		(net 634)
	)
	(segment
		(start 185.675 121.775)
		(end 185.675 121.85)
		(width 0.1)
		(layer "In9.Cu")
		(net 634)
	)
	(segment
		(start 186.25 122.425)
		(end 187.175987 122.425)
		(width 0.1)
		(layer "In9.Cu")
		(net 634)
	)
	(segment
		(start 194.155051 140.1)
		(end 194.45 140.1)
		(width 0.1)
		(layer "In9.Cu")
		(net 634)
	)
	(segment
		(start 194.5 140.15)
		(end 194.5 140.5)
		(width 0.1)
		(layer "In9.Cu")
		(net 634)
	)
	(segment
		(start 182.975 124.198222)
		(end 182.175 124.998222)
		(width 0.1)
		(layer "In9.Cu")
		(net 634)
	)
	(segment
		(start 193.897726 139.842675)
		(end 194.155051 140.1)
		(width 0.1)
		(layer "In9.Cu")
		(net 634)
	)
	(segment
		(start 193.870252 139.175)
		(end 193.897726 139.202474)
		(width 0.1)
		(layer "In9.Cu")
		(net 634)
	)
	(segment
		(start 190.15 111.45)
		(end 190.15 111.023222)
		(width 0.1)
		(layer "In9.Cu")
		(net 634)
	)
	(segment
		(start 182.975 121.448222)
		(end 182.975 124.198222)
		(width 0.1)
		(layer "In9.Cu")
		(net 634)
	)
	(segment
		(start 193.870252 128.24703)
		(end 193.870252 139.175)
		(width 0.1)
		(layer "In9.Cu")
		(net 634)
	)
	(segment
		(start 187.175987 123.075)
		(end 186.25 123.075)
		(width 0.1)
		(layer "In9.Cu")
		(net 634)
	)
	(segment
		(start 182.175 124.998222)
		(end 182.175 126.001778)
		(width 0.1)
		(layer "In9.Cu")
		(net 634)
	)
	(segment
		(start 194.45 140.1)
		(end 194.5 140.15)
		(width 0.1)
		(layer "In9.Cu")
		(net 634)
	)
	(segment
		(start 190.45 111.75)
		(end 190.15 111.45)
		(width 0.1)
		(layer "In9.Cu")
		(net 634)
	)
	(segment
		(start 188.698222 110.675)
		(end 185.425 113.948222)
		(width 0.1)
		(layer "In9.Cu")
		(net 634)
	)
	(segment
		(start 189.801778 110.675)
		(end 188.698222 110.675)
		(width 0.1)
		(layer "In9.Cu")
		(net 634)
	)
	(segment
		(start 182.175 126.001778)
		(end 182.598222 126.425)
		(width 0.1)
		(layer "In9.Cu")
		(net 634)
	)
	(segment
		(start 186.45 126.425)
		(end 187.67867 126.425)
		(width 0.1)
		(layer "In9.Cu")
		(net 634)
	)
	(segment
		(start 187.67867 126.425)
		(end 192.048222 126.425)
		(width 0.1)
		(layer "In9.Cu")
		(net 634)
	)
	(segment
		(start 193.897726 139.202474)
		(end 193.897726 139.842675)
		(width 0.1)
		(layer "In9.Cu")
		(net 634)
	)
	(segment
		(start 185.675 125.45)
		(end 185.675 125.65)
		(width 0.1)
		(layer "In9.Cu")
		(net 634)
	)
	(segment
		(start 190.15 111.023222)
		(end 189.801778 110.675)
		(width 0.1)
		(layer "In9.Cu")
		(net 634)
	)
	(segment
		(start 187.175987 124.875)
		(end 186.25 124.875)
		(width 0.1)
		(layer "In9.Cu")
		(net 634)
	)
	(arc
		(start 187.500987 124.55)
		(mid 187.405797 124.77981)
		(end 187.175987 124.875)
		(width 0.1)
		(layer "In9.Cu")
		(net 634)
	)
	(arc
		(start 185.675 125.65)
		(mid 185.901992 126.198008)
		(end 186.45 126.425)
		(width 0.1)
		(layer "In9.Cu")
		(net 634)
	)
	(arc
		(start 187.500987 122.75)
		(mid 187.405797 122.97981)
		(end 187.175987 123.075)
		(width 0.1)
		(layer "In9.Cu")
		(net 634)
	)
	(arc
		(start 187.175987 124.225)
		(mid 187.405797 124.32019)
		(end 187.500987 124.55)
		(width 0.1)
		(layer "In9.Cu")
		(net 634)
	)
	(arc
		(start 185.15 121.25)
		(mid 185.521231 121.403769)
		(end 185.675 121.775)
		(width 0.1)
		(layer "In9.Cu")
		(net 634)
	)
	(arc
		(start 184.625 121.775)
		(mid 184.778769 121.403769)
		(end 185.15 121.25)
		(width 0.1)
		(layer "In9.Cu")
		(net 634)
	)
	(arc
		(start 185.675 121.85)
		(mid 185.843414 122.256586)
		(end 186.25 122.425)
		(width 0.1)
		(layer "In9.Cu")
		(net 634)
	)
	(arc
		(start 186.25 124.875)
		(mid 185.843414 125.043414)
		(end 185.675 125.45)
		(width 0.1)
		(layer "In9.Cu")
		(net 634)
	)
	(arc
		(start 183.85 126.425)
		(mid 184.398008 126.198008)
		(end 184.625 125.65)
		(width 0.1)
		(layer "In9.Cu")
		(net 634)
	)
	(arc
		(start 185.675 123.65)
		(mid 185.843414 124.056586)
		(end 186.25 124.225)
		(width 0.1)
		(layer "In9.Cu")
		(net 634)
	)
	(arc
		(start 187.175987 122.425)
		(mid 187.405797 122.52019)
		(end 187.500987 122.75)
		(width 0.1)
		(layer "In9.Cu")
		(net 634)
	)
	(arc
		(start 186.25 123.075)
		(mid 185.843414 123.243414)
		(end 185.675 123.65)
		(width 0.1)
		(layer "In9.Cu")
		(net 634)
	)
	(segment
		(start 118.005176 154.755176)
		(end 118.005176 155.264824)
		(width 0.256)
		(layer "F.Cu")
		(net 635)
	)
	(segment
		(start 116.235 153.65)
		(end 116.35 153.535)
		(width 0.256)
		(layer "F.Cu")
		(net 635)
	)
	(segment
		(start 179.9995 145.9995)
		(end 179.499999 145.5)
		(width 0.256)
		(layer "F.Cu")
		(net 635)
	)
	(segment
		(start 116.964501 153.714501)
		(end 118.005176 154.755176)
		(width 0.256)
		(layer "F.Cu")
		(net 635)
	)
	(segment
		(start 118.005176 155.264824)
		(end 117.62 155.65)
		(width 0.256)
		(layer "F.Cu")
		(net 635)
	)
	(segment
		(start 116.23 153.714501)
		(end 116.964501 153.714501)
		(width 0.256)
		(layer "F.Cu")
		(net 635)
	)
	(segment
		(start 116.35 152.601)
		(end 116.451 152.5)
		(width 0.256)
		(layer "F.Cu")
		(net 635)
	)
	(segment
		(start 116.35 153.535)
		(end 116.35 152.601)
		(width 0.256)
		(layer "F.Cu")
		(net 635)
	)
	(via
		(at 118.005176 155.047412)
		(size 0.45)
		(drill 0.1)
		(layers "F.Cu" "B.Cu")
		(remove_unused_layers yes)
		(keep_end_layers yes)
		(zone_layer_connections)
		(net 635)
	)
	(via
		(at 179.499999 145.5)
		(size 0.45)
		(drill 0.1)
		(layers "F.Cu" "B.Cu")
		(remove_unused_layers yes)
		(keep_end_layers yes)
		(zone_layer_connections)
		(net 635)
	)
	(segment
		(start 147.22 150.7)
		(end 150.055 147.865)
		(width 0.1)
		(layer "In2.Cu")
		(net 635)
	)
	(segment
		(start 178.999999 146)
		(end 179.499999 145.5)
		(width 0.1)
		(layer "In2.Cu")
		(net 635)
	)
	(segment
		(start 123.07 156.72)
		(end 123.07 157.27)
		(width 0.1)
		(layer "In2.Cu")
		(net 635)
	)
	(segment
		(start 129.3 154.89)
		(end 129.3 152.55)
		(width 0.1)
		(layer "In2.Cu")
		(net 635)
	)
	(segment
		(start 161.92 145.78)
		(end 174.67 145.78)
		(width 0.1)
		(layer "In2.Cu")
		(net 635)
	)
	(segment
		(start 129.3 152.55)
		(end 130.83 151.02)
		(width 0.1)
		(layer "In2.Cu")
		(net 635)
	)
	(segment
		(start 118.406764 155.449)
		(end 121.799 155.449)
		(width 0.1)
		(layer "In2.Cu")
		(net 635)
	)
	(segment
		(start 121.799 155.449)
		(end 123.07 156.72)
		(width 0.1)
		(layer "In2.Cu")
		(net 635)
	)
	(segment
		(start 123.07 157.27)
		(end 122.15 158.19)
		(width 0.1)
		(layer "In2.Cu")
		(net 635)
	)
	(segment
		(start 126.82 157.37)
		(end 129.3 154.89)
		(width 0.1)
		(layer "In2.Cu")
		(net 635)
	)
	(segment
		(start 122.15 159.025)
		(end 122.505339 159.380339)
		(width 0.1)
		(layer "In2.Cu")
		(net 635)
	)
	(segment
		(start 174.67 145.78)
		(end 174.89 146)
		(width 0.1)
		(layer "In2.Cu")
		(net 635)
	)
	(segment
		(start 124.02 159.380339)
		(end 126.030339 157.37)
		(width 0.1)
		(layer "In2.Cu")
		(net 635)
	)
	(segment
		(start 126.030339 157.37)
		(end 126.82 157.37)
		(width 0.1)
		(layer "In2.Cu")
		(net 635)
	)
	(segment
		(start 136.08 151.02)
		(end 136.4 150.7)
		(width 0.1)
		(layer "In2.Cu")
		(net 635)
	)
	(segment
		(start 118.005176 155.047412)
		(end 118.406764 155.449)
		(width 0.1)
		(layer "In2.Cu")
		(net 635)
	)
	(segment
		(start 122.505339 159.380339)
		(end 124.02 159.380339)
		(width 0.1)
		(layer "In2.Cu")
		(net 635)
	)
	(segment
		(start 150.055 147.865)
		(end 159.835 147.865)
		(width 0.1)
		(layer "In2.Cu")
		(net 635)
	)
	(segment
		(start 174.89 146)
		(end 178.999999 146)
		(width 0.1)
		(layer "In2.Cu")
		(net 635)
	)
	(segment
		(start 136.4 150.7)
		(end 147.22 150.7)
		(width 0.1)
		(layer "In2.Cu")
		(net 635)
	)
	(segment
		(start 159.835 147.865)
		(end 161.92 145.78)
		(width 0.1)
		(layer "In2.Cu")
		(net 635)
	)
	(segment
		(start 122.15 158.19)
		(end 122.15 159.025)
		(width 0.1)
		(layer "In2.Cu")
		(net 635)
	)
	(segment
		(start 130.83 151.02)
		(end 136.08 151.02)
		(width 0.1)
		(layer "In2.Cu")
		(net 635)
	)
	(segment
		(start 120.725 157.725)
		(end 121.67 157.725)
		(width 0.256)
		(layer "F.Cu")
		(net 636)
	)
	(segment
		(start 122.596669 157.125)
		(end 121.996669 157.725)
		(width 0.256)
		(layer "F.Cu")
		(net 636)
	)
	(segment
		(start 121.996669 157.725)
		(end 121.67 157.725)
		(width 0.256)
		(layer "F.Cu")
		(net 636)
	)
	(segment
		(start 120.423 158.223)
		(end 120.423 158.027)
		(width 0.256)
		(layer "F.Cu")
		(net 636)
	)
	(segment
		(start 180.9995 147.9995)
		(end 180.5 147.5)
		(width 0.256)
		(layer "F.Cu")
		(net 636)
	)
	(segment
		(start 120.423 158.027)
		(end 120.725 157.725)
		(width 0.256)
		(layer "F.Cu")
		(net 636)
	)
	(via
		(at 122.596669 157.125)
		(size 0.45)
		(drill 0.1)
		(layers "F.Cu" "B.Cu")
		(remove_unused_layers yes)
		(keep_end_layers yes)
		(zone_layer_connections)
		(net 636)
	)
	(via
		(at 180.5 147.5)
		(size 0.45)
		(drill 0.1)
		(layers "F.Cu" "B.Cu")
		(remove_unused_layers yes)
		(keep_end_layers yes)
		(zone_layer_connections)
		(net 636)
	)
	(segment
		(start 122.4275 160.8875)
		(end 121.62 160.08)
		(width 0.1)
		(layer "In2.Cu")
		(net 636)
	)
	(segment
		(start 163.13 148.09)
		(end 160.815 150.405)
		(width 0.1)
		(layer "In2.Cu")
		(net 636)
	)
	(segment
		(start 149.08 153.5)
		(end 135.76 153.5)
		(width 0.1)
		(layer "In2.Cu")
		(net 636)
	)
	(segment
		(start 180.5 147.8)
		(end 180 148.3)
		(width 0.1)
		(layer "In2.Cu")
		(net 636)
	)
	(segment
		(start 122.255 157.125)
		(end 122.596669 157.125)
		(width 0.1)
		(layer "In2.Cu")
		(net 636)
	)
	(segment
		(start 121.62 157.76)
		(end 122.255 157.125)
		(width 0.1)
		(layer "In2.Cu")
		(net 636)
	)
	(segment
		(start 160.815 150.405)
		(end 152.175 150.405)
		(width 0.1)
		(layer "In2.Cu")
		(net 636)
	)
	(segment
		(start 173.49 149)
		(end 172.58 148.09)
		(width 0.1)
		(layer "In2.Cu")
		(net 636)
	)
	(segment
		(start 180.5 147.5)
		(end 180.5 147.8)
		(width 0.1)
		(layer "In2.Cu")
		(net 636)
	)
	(segment
		(start 172.58 148.09)
		(end 163.13 148.09)
		(width 0.1)
		(layer "In2.Cu")
		(net 636)
	)
	(segment
		(start 129.65 159.61)
		(end 126.8975 159.61)
		(width 0.1)
		(layer "In2.Cu")
		(net 636)
	)
	(segment
		(start 125.62 160.8875)
		(end 122.4275 160.8875)
		(width 0.1)
		(layer "In2.Cu")
		(net 636)
	)
	(segment
		(start 152.175 150.405)
		(end 149.08 153.5)
		(width 0.1)
		(layer "In2.Cu")
		(net 636)
	)
	(segment
		(start 135.76 153.5)
		(end 129.65 159.61)
		(width 0.1)
		(layer "In2.Cu")
		(net 636)
	)
	(segment
		(start 180 148.7)
		(end 179.7 149)
		(width 0.1)
		(layer "In2.Cu")
		(net 636)
	)
	(segment
		(start 180 148.3)
		(end 180 148.7)
		(width 0.1)
		(layer "In2.Cu")
		(net 636)
	)
	(segment
		(start 179.7 149)
		(end 173.49 149)
		(width 0.1)
		(layer "In2.Cu")
		(net 636)
	)
	(segment
		(start 121.62 160.08)
		(end 121.62 157.76)
		(width 0.1)
		(layer "In2.Cu")
		(net 636)
	)
	(segment
		(start 126.8975 159.61)
		(end 125.62 160.8875)
		(width 0.1)
		(layer "In2.Cu")
		(net 636)
	)
	(segment
		(start 120.423 160.574)
		(end 120.423 160.748)
		(width 0.256)
		(layer "F.Cu")
		(net 637)
	)
	(segment
		(start 122.1 160.975)
		(end 121.5 160.975)
		(width 0.256)
		(layer "F.Cu")
		(net 637)
	)
	(segment
		(start 122.625 161.5)
		(end 122.1 160.975)
		(width 0.256)
		(layer "F.Cu")
		(net 637)
	)
	(segment
		(start 120.65 160.975)
		(end 121.67 160.975)
		(width 0.256)
		(layer "F.Cu")
		(net 637)
	)
	(segment
		(start 182.9995 146.9995)
		(end 182.5 146.5)
		(width 0.256)
		(layer "F.Cu")
		(net 637)
	)
	(segment
		(start 120.423 160.748)
		(end 120.65 160.975)
		(width 0.256)
		(layer "F.Cu")
		(net 637)
	)
	(via
		(at 122.625 161.5)
		(size 0.45)
		(drill 0.1)
		(layers "F.Cu" "B.Cu")
		(remove_unused_layers yes)
		(keep_end_layers yes)
		(zone_layer_connections)
		(net 637)
	)
	(via
		(at 182.5 146.5)
		(size 0.45)
		(drill 0.1)
		(layers "F.Cu" "B.Cu")
		(remove_unused_layers yes)
		(keep_end_layers yes)
		(zone_layer_connections)
		(net 637)
	)
	(segment
		(start 131.323133 159.11687)
		(end 131.314513 159.125488)
		(width 0.1)
		(layer "In2.Cu")
		(net 637)
	)
	(segment
		(start 134.708628 156.28835)
		(end 134.708627 156.28835)
		(width 0.1)
		(layer "In2.Cu")
		(net 637)
	)
	(segment
		(start 182.01 146.99)
		(end 181.26 146.99)
		(width 0.1)
		(layer "In2.Cu")
		(net 637)
	)
	(segment
		(start 135.968843 154.471157)
		(end 135.84 154.6)
		(width 0.1)
		(layer "In2.Cu")
		(net 637)
	)
	(segment
		(start 173.08 150)
		(end 171.78 148.7)
		(width 0.1)
		(layer "In2.Cu")
		(net 637)
	)
	(segment
		(start 181 149.71)
		(end 180.71 150)
		(width 0.1)
		(layer "In2.Cu")
		(net 637)
	)
	(segment
		(start 181 147.25)
		(end 181 149.71)
		(width 0.1)
		(layer "In2.Cu")
		(net 637)
	)
	(segment
		(start 152.651157 151.34)
		(end 149.52 154.471157)
		(width 0.1)
		(layer "In2.Cu")
		(net 637)
	)
	(segment
		(start 160.96 151.34)
		(end 152.651157 151.34)
		(width 0.1)
		(layer "In2.Cu")
		(net 637)
	)
	(segment
		(start 134.708629 156.845327)
		(end 134.69992 156.854037)
		(width 0.1)
		(layer "In2.Cu")
		(net 637)
	)
	(segment
		(start 132.445885 157.994116)
		(end 132.445884 157.994116)
		(width 0.1)
		(layer "In2.Cu")
		(net 637)
	)
	(segment
		(start 132.445884 158.551182)
		(end 132.445885 158.551183)
		(width 0.1)
		(layer "In2.Cu")
		(net 637)
	)
	(segment
		(start 182.5 146.5)
		(end 182.01 146.99)
		(width 0.1)
		(layer "In2.Cu")
		(net 637)
	)
	(segment
		(start 134.142943 156.854038)
		(end 134.142944 156.854036)
		(width 0.1)
		(layer "In2.Cu")
		(net 637)
	)
	(segment
		(start 133.577256 157.41968)
		(end 133.577257 157.419681)
		(width 0.1)
		(layer "In2.Cu")
		(net 637)
	)
	(segment
		(start 130.183141 160.25686)
		(end 129.99 160.45)
		(width 0.1)
		(layer "In2.Cu")
		(net 637)
	)
	(segment
		(start 180.71 150)
		(end 173.08 150)
		(width 0.1)
		(layer "In2.Cu")
		(net 637)
	)
	(segment
		(start 171.78 148.7)
		(end 163.6 148.7)
		(width 0.1)
		(layer "In2.Cu")
		(net 637)
	)
	(segment
		(start 132.454635 157.985368)
		(end 132.445885 157.994116)
		(width 0.1)
		(layer "In2.Cu")
		(net 637)
	)
	(segment
		(start 135.84 155.156922)
		(end 135.839999 155.156922)
		(width 0.1)
		(layer "In2.Cu")
		(net 637)
	)
	(segment
		(start 129.99 160.45)
		(end 127.28 160.45)
		(width 0.1)
		(layer "In2.Cu")
		(net 637)
	)
	(segment
		(start 181.26 146.99)
		(end 181 147.25)
		(width 0.1)
		(layer "In2.Cu")
		(net 637)
	)
	(segment
		(start 149.52 154.471157)
		(end 135.968843 154.471157)
		(width 0.1)
		(layer "In2.Cu")
		(net 637)
	)
	(segment
		(start 133.577257 157.976617)
		(end 133.568507 157.985368)
		(width 0.1)
		(layer "In2.Cu")
		(net 637)
	)
	(segment
		(start 134.717396 155.722608)
		(end 134.708629 155.731372)
		(width 0.1)
		(layer "In2.Cu")
		(net 637)
	)
	(segment
		(start 131.314513 159.125488)
		(end 131.314512 159.125488)
		(width 0.1)
		(layer "In2.Cu")
		(net 637)
	)
	(segment
		(start 131.314513 160.239525)
		(end 131.305845 160.248194)
		(width 0.1)
		(layer "In2.Cu")
		(net 637)
	)
	(segment
		(start 133.585966 156.854037)
		(end 133.577256 156.862744)
		(width 0.1)
		(layer "In2.Cu")
		(net 637)
	)
	(segment
		(start 127.28 160.45)
		(end 126.23 161.5)
		(width 0.1)
		(layer "In2.Cu")
		(net 637)
	)
	(segment
		(start 134.708629 155.731372)
		(end 134.708628 155.731372)
		(width 0.1)
		(layer "In2.Cu")
		(net 637)
	)
	(segment
		(start 130.191809 160.248194)
		(end 130.183141 160.25686)
		(width 0.1)
		(layer "In2.Cu")
		(net 637)
	)
	(segment
		(start 135.839999 155.156922)
		(end 135.84 155.156923)
		(width 0.1)
		(layer "In2.Cu")
		(net 637)
	)
	(segment
		(start 135.84 155.713843)
		(end 135.831236 155.722608)
		(width 0.1)
		(layer "In2.Cu")
		(net 637)
	)
	(segment
		(start 134.708627 156.28835)
		(end 134.708628 156.288351)
		(width 0.1)
		(layer "In2.Cu")
		(net 637)
	)
	(segment
		(start 132.445885 159.108249)
		(end 132.437265 159.11687)
		(width 0.1)
		(layer "In2.Cu")
		(net 637)
	)
	(segment
		(start 126.23 161.5)
		(end 122.625 161.5)
		(width 0.1)
		(layer "In2.Cu")
		(net 637)
	)
	(segment
		(start 134.708629 156.845328)
		(end 134.708629 156.845327)
		(width 0.1)
		(layer "In2.Cu")
		(net 637)
	)
	(segment
		(start 133.585967 156.854035)
		(end 133.585966 156.854037)
		(width 0.1)
		(layer "In2.Cu")
		(net 637)
	)
	(segment
		(start 131.314512 159.682506)
		(end 131.314513 159.682507)
		(width 0.1)
		(layer "In2.Cu")
		(net 637)
	)
	(segment
		(start 163.6 148.7)
		(end 160.96 151.34)
		(width 0.1)
		(layer "In2.Cu")
		(net 637)
	)
	(arc
		(start 133.568507 157.985368)
		(mid 133.29004 158.100712)
		(end 133.011571 157.985368)
		(width 0.1)
		(layer "In2.Cu")
		(net 637)
	)
	(arc
		(start 133.577257 157.419681)
		(mid 133.692601 157.69815)
		(end 133.577257 157.976617)
		(width 0.1)
		(layer "In2.Cu")
		(net 637)
	)
	(arc
		(start 132.437265 159.11687)
		(mid 132.158733 159.232241)
		(end 131.880199 159.11687)
		(width 0.1)
		(layer "In2.Cu")
		(net 637)
	)
	(arc
		(start 134.708628 155.731372)
		(mid 134.593273 156.009862)
		(end 134.708628 156.28835)
		(width 0.1)
		(layer "In2.Cu")
		(net 637)
	)
	(arc
		(start 133.011571 157.985368)
		(mid 132.733104 157.870022)
		(end 132.454635 157.985368)
		(width 0.1)
		(layer "In2.Cu")
		(net 637)
	)
	(arc
		(start 135.84 154.6)
		(mid 135.724657 154.878462)
		(end 135.84 155.156922)
		(width 0.1)
		(layer "In2.Cu")
		(net 637)
	)
	(arc
		(start 130.748827 160.248194)
		(mid 130.470319 160.132831)
		(end 130.191809 160.248194)
		(width 0.1)
		(layer "In2.Cu")
		(net 637)
	)
	(arc
		(start 131.314512 159.125488)
		(mid 131.199149 159.403998)
		(end 131.314512 159.682506)
		(width 0.1)
		(layer "In2.Cu")
		(net 637)
	)
	(arc
		(start 134.69992 156.854037)
		(mid 134.421432 156.969391)
		(end 134.142943 156.854038)
		(width 0.1)
		(layer "In2.Cu")
		(net 637)
	)
	(arc
		(start 135.274316 155.722608)
		(mid 134.995856 155.607266)
		(end 134.717396 155.722608)
		(width 0.1)
		(layer "In2.Cu")
		(net 637)
	)
	(arc
		(start 134.708628 156.288351)
		(mid 134.823982 156.566839)
		(end 134.708629 156.845328)
		(width 0.1)
		(layer "In2.Cu")
		(net 637)
	)
	(arc
		(start 131.314513 159.682507)
		(mid 131.429874 159.961017)
		(end 131.314513 160.239525)
		(width 0.1)
		(layer "In2.Cu")
		(net 637)
	)
	(arc
		(start 131.305845 160.248194)
		(mid 131.027337 160.363555)
		(end 130.748827 160.248194)
		(width 0.1)
		(layer "In2.Cu")
		(net 637)
	)
	(arc
		(start 135.831236 155.722608)
		(mid 135.552776 155.83795)
		(end 135.274316 155.722608)
		(width 0.1)
		(layer "In2.Cu")
		(net 637)
	)
	(arc
		(start 132.445884 157.994116)
		(mid 132.330511 158.27265)
		(end 132.445884 158.551182)
		(width 0.1)
		(layer "In2.Cu")
		(net 637)
	)
	(arc
		(start 131.880199 159.11687)
		(mid 131.601667 159.001497)
		(end 131.323133 159.11687)
		(width 0.1)
		(layer "In2.Cu")
		(net 637)
	)
	(arc
		(start 133.577256 156.862744)
		(mid 133.46191 157.141213)
		(end 133.577256 157.41968)
		(width 0.1)
		(layer "In2.Cu")
		(net 637)
	)
	(arc
		(start 135.84 155.156923)
		(mid 135.955342 155.435383)
		(end 135.84 155.713843)
		(width 0.1)
		(layer "In2.Cu")
		(net 637)
	)
	(arc
		(start 132.445885 158.551183)
		(mid 132.561256 158.829717)
		(end 132.445885 159.108249)
		(width 0.1)
		(layer "In2.Cu")
		(net 637)
	)
	(arc
		(start 134.142944 156.854036)
		(mid 133.864456 156.738682)
		(end 133.585967 156.854035)
		(width 0.1)
		(layer "In2.Cu")
		(net 637)
	)
	(segment
		(start 181.9995 145.9995)
		(end 181.5 145.5)
		(width 0.256)
		(layer "F.Cu")
		(net 638)
	)
	(segment
		(start 122.805 158.97)
		(end 122.85 158.925)
		(width 0.256)
		(layer "F.Cu")
		(net 638)
	)
	(segment
		(start 121.192 159.198)
		(end 121.42 158.97)
		(width 0.256)
		(layer "F.Cu")
		(net 638)
	)
	(segment
		(start 121.42 158.97)
		(end 122.805 158.97)
		(width 0.256)
		(layer "F.Cu")
		(net 638)
	)
	(segment
		(start 120.448 159.198)
		(end 121.192 159.198)
		(width 0.256)
		(layer "F.Cu")
		(net 638)
	)
	(via
		(at 181.5 145.5)
		(size 0.45)
		(drill 0.1)
		(layers "F.Cu" "B.Cu")
		(remove_unused_layers yes)
		(keep_end_layers yes)
		(zone_layer_connections)
		(net 638)
	)
	(via
		(at 122.85 158.925)
		(size 0.45)
		(drill 0.1)
		(layers "F.Cu" "B.Cu")
		(remove_unused_layers yes)
		(keep_end_layers yes)
		(zone_layer_connections)
		(net 638)
	)
	(segment
		(start 159.19 147.21)
		(end 161.35 145.05)
		(width 0.1)
		(layer "In2.Cu")
		(net 638)
	)
	(segment
		(start 129.65 149.9)
		(end 130.25 149.9)
		(width 0.1)
		(layer "In2.Cu")
		(net 638)
	)
	(segment
		(start 128.716651 153.74835)
		(end 128.716651 153.64)
		(width 0.1)
		(layer "In2.Cu")
		(net 638)
	)
	(segment
		(start 141.43 149.9)
		(end 141.58 150.05)
		(width 0.1)
		(layer "In2.Cu")
		(net 638)
	)
	(segment
		(start 128.470826 153.394175)
		(end 128.470825 153.394175)
		(width 0.1)
		(layer "In2.Cu")
		(net 638)
	)
	(segment
		(start 129.173333 151.078737)
		(end 129.173333 151.078738)
		(width 0.1)
		(layer "In2.Cu")
		(net 638)
	)
	(segment
		(start 128.663198 151.205)
		(end 128.855135 151.396937)
		(width 0.1)
		(layer "In2.Cu")
		(net 638)
	)
	(segment
		(start 128.225 153.14835)
		(end 128.225 153.04)
		(width 0.1)
		(layer "In2.Cu")
		(net 638)
	)
	(segment
		(start 128.981395 150.568602)
		(end 128.981396 150.568603)
		(width 0.1)
		(layer "In2.Cu")
		(net 638)
	)
	(segment
		(start 131.625 150.175)
		(end 131.625 150.225)
		(width 0.1)
		(layer "In2.Cu")
		(net 638)
	)
	(segment
		(start 132.175 150.225)
		(end 132.175 150.175)
		(width 0.1)
		(layer "In2.Cu")
		(net 638)
	)
	(segment
		(start 149.08 147.21)
		(end 159.19 147.21)
		(width 0.1)
		(layer "In2.Cu")
		(net 638)
	)
	(segment
		(start 135.75 149.9)
		(end 141.43 149.9)
		(width 0.1)
		(layer "In2.Cu")
		(net 638)
	)
	(segment
		(start 135.475 150.225)
		(end 135.475 150.175)
		(width 0.1)
		(layer "In2.Cu")
		(net 638)
	)
	(segment
		(start 141.58 150.05)
		(end 146.24 150.05)
		(width 0.1)
		(layer "In2.Cu")
		(net 638)
	)
	(segment
		(start 129.80973 150.44234)
		(end 129.80973 150.442341)
		(width 0.1)
		(layer "In2.Cu")
		(net 638)
	)
	(segment
		(start 128.470825 153.994175)
		(end 128.470826 153.994175)
		(width 0.1)
		(layer "In2.Cu")
		(net 638)
	)
	(segment
		(start 130.525 150.175)
		(end 130.525 150.225)
		(width 0.1)
		(layer "In2.Cu")
		(net 638)
	)
	(segment
		(start 181.05 145.05)
		(end 181.5 145.5)
		(width 0.1)
		(layer "In2.Cu")
		(net 638)
	)
	(segment
		(start 129.173333 151.078738)
		(end 128.981395 150.8868)
		(width 0.1)
		(layer "In2.Cu")
		(net 638)
	)
	(segment
		(start 128.470875 152.794125)
		(end 128.470876 152.794125)
		(width 0.1)
		(layer "In2.Cu")
		(net 638)
	)
	(segment
		(start 129.617793 149.932206)
		(end 129.65 149.9)
		(width 0.1)
		(layer "In2.Cu")
		(net 638)
	)
	(segment
		(start 146.24 150.05)
		(end 149.08 147.21)
		(width 0.1)
		(layer "In2.Cu")
		(net 638)
	)
	(segment
		(start 129.80973 150.442341)
		(end 129.617792 150.250403)
		(width 0.1)
		(layer "In2.Cu")
		(net 638)
	)
	(segment
		(start 134.925 150.175)
		(end 134.925 150.225)
		(width 0.1)
		(layer "In2.Cu")
		(net 638)
	)
	(segment
		(start 128.981396 150.568603)
		(end 128.981397 150.568603)
		(width 0.1)
		(layer "In2.Cu")
		(net 638)
	)
	(segment
		(start 128.716751 152.54825)
		(end 128.716751 152.44)
		(width 0.1)
		(layer "In2.Cu")
		(net 638)
	)
	(segment
		(start 126.34 156.55)
		(end 128.225 154.665)
		(width 0.1)
		(layer "In2.Cu")
		(net 638)
	)
	(segment
		(start 123.455 158.925)
		(end 125.83 156.55)
		(width 0.1)
		(layer "In2.Cu")
		(net 638)
	)
	(segment
		(start 128.225 151.94825)
		(end 128.225 151.325)
		(width 0.1)
		(layer "In2.Cu")
		(net 638)
	)
	(segment
		(start 133.275 150.225)
		(end 133.275 150.175)
		(width 0.1)
		(layer "In2.Cu")
		(net 638)
	)
	(segment
		(start 125.83 156.55)
		(end 126.34 156.55)
		(width 0.1)
		(layer "In2.Cu")
		(net 638)
	)
	(segment
		(start 129.617792 149.932205)
		(end 129.617793 149.932206)
		(width 0.1)
		(layer "In2.Cu")
		(net 638)
	)
	(segment
		(start 132.725 150.175)
		(end 132.725 150.225)
		(width 0.1)
		(layer "In2.Cu")
		(net 638)
	)
	(segment
		(start 133.825 150.175)
		(end 133.825 150.225)
		(width 0.1)
		(layer "In2.Cu")
		(net 638)
	)
	(segment
		(start 128.225 154.665)
		(end 128.225 154.24)
		(width 0.1)
		(layer "In2.Cu")
		(net 638)
	)
	(segment
		(start 131.075 150.225)
		(end 131.075 150.175)
		(width 0.1)
		(layer "In2.Cu")
		(net 638)
	)
	(segment
		(start 128.470876 152.194125)
		(end 128.470875 152.194125)
		(width 0.1)
		(layer "In2.Cu")
		(net 638)
	)
	(segment
		(start 128.225 151.325)
		(end 128.345 151.205)
		(width 0.1)
		(layer "In2.Cu")
		(net 638)
	)
	(segment
		(start 134.375 150.225)
		(end 134.375 150.175)
		(width 0.1)
		(layer "In2.Cu")
		(net 638)
	)
	(segment
		(start 129.299595 150.568603)
		(end 129.491532 150.76054)
		(width 0.1)
		(layer "In2.Cu")
		(net 638)
	)
	(segment
		(start 122.85 158.925)
		(end 123.455 158.925)
		(width 0.1)
		(layer "In2.Cu")
		(net 638)
	)
	(segment
		(start 161.35 145.05)
		(end 181.05 145.05)
		(width 0.1)
		(layer "In2.Cu")
		(net 638)
	)
	(arc
		(start 128.470875 152.194125)
		(mid 128.297015 152.12211)
		(end 128.225 151.94825)
		(width 0.1)
		(layer "In2.Cu")
		(net 638)
	)
	(arc
		(start 128.345 151.205)
		(mid 128.504099 151.139099)
		(end 128.663198 151.205)
		(width 0.1)
		(layer "In2.Cu")
		(net 638)
	)
	(arc
		(start 128.716651 153.64)
		(mid 128.644651 153.466175)
		(end 128.470826 153.394175)
		(width 0.1)
		(layer "In2.Cu")
		(net 638)
	)
	(arc
		(start 132.175 150.175)
		(mid 132.255546 149.980546)
		(end 132.45 149.9)
		(width 0.1)
		(layer "In2.Cu")
		(net 638)
	)
	(arc
		(start 133.275 150.175)
		(mid 133.355546 149.980546)
		(end 133.55 149.9)
		(width 0.1)
		(layer "In2.Cu")
		(net 638)
	)
	(arc
		(start 129.617792 150.250403)
		(mid 129.551891 150.091304)
		(end 129.617792 149.932205)
		(width 0.1)
		(layer "In2.Cu")
		(net 638)
	)
	(arc
		(start 131.075 150.175)
		(mid 131.155546 149.980546)
		(end 131.35 149.9)
		(width 0.1)
		(layer "In2.Cu")
		(net 638)
	)
	(arc
		(start 134.65 149.9)
		(mid 134.844454 149.980546)
		(end 134.925 150.175)
		(width 0.1)
		(layer "In2.Cu")
		(net 638)
	)
	(arc
		(start 133 150.5)
		(mid 133.194454 150.419454)
		(end 133.275 150.225)
		(width 0.1)
		(layer "In2.Cu")
		(net 638)
	)
	(arc
		(start 133.825 150.225)
		(mid 133.905546 150.419454)
		(end 134.1 150.5)
		(width 0.1)
		(layer "In2.Cu")
		(net 638)
	)
	(arc
		(start 132.725 150.225)
		(mid 132.805546 150.419454)
		(end 133 150.5)
		(width 0.1)
		(layer "In2.Cu")
		(net 638)
	)
	(arc
		(start 128.855135 151.396937)
		(mid 129.014234 151.462838)
		(end 129.173333 151.396937)
		(width 0.1)
		(layer "In2.Cu")
		(net 638)
	)
	(arc
		(start 131.9 150.5)
		(mid 132.094454 150.419454)
		(end 132.175 150.225)
		(width 0.1)
		(layer "In2.Cu")
		(net 638)
	)
	(arc
		(start 131.625 150.225)
		(mid 131.705546 150.419454)
		(end 131.9 150.5)
		(width 0.1)
		(layer "In2.Cu")
		(net 638)
	)
	(arc
		(start 135.475 150.175)
		(mid 135.555546 149.980546)
		(end 135.75 149.9)
		(width 0.1)
		(layer "In2.Cu")
		(net 638)
	)
	(arc
		(start 128.981397 150.568603)
		(mid 129.140496 150.502702)
		(end 129.299595 150.568603)
		(width 0.1)
		(layer "In2.Cu")
		(net 638)
	)
	(arc
		(start 130.25 149.9)
		(mid 130.444454 149.980546)
		(end 130.525 150.175)
		(width 0.1)
		(layer "In2.Cu")
		(net 638)
	)
	(arc
		(start 134.925 150.225)
		(mid 135.005546 150.419454)
		(end 135.2 150.5)
		(width 0.1)
		(layer "In2.Cu")
		(net 638)
	)
	(arc
		(start 128.716751 152.44)
		(mid 128.644736 152.26614)
		(end 128.470876 152.194125)
		(width 0.1)
		(layer "In2.Cu")
		(net 638)
	)
	(arc
		(start 130.525 150.225)
		(mid 130.605546 150.419454)
		(end 130.8 150.5)
		(width 0.1)
		(layer "In2.Cu")
		(net 638)
	)
	(arc
		(start 132.45 149.9)
		(mid 132.644454 149.980546)
		(end 132.725 150.175)
		(width 0.1)
		(layer "In2.Cu")
		(net 638)
	)
	(arc
		(start 128.470825 153.394175)
		(mid 128.297 153.322175)
		(end 128.225 153.14835)
		(width 0.1)
		(layer "In2.Cu")
		(net 638)
	)
	(arc
		(start 131.35 149.9)
		(mid 131.544454 149.980546)
		(end 131.625 150.175)
		(width 0.1)
		(layer "In2.Cu")
		(net 638)
	)
	(arc
		(start 133.55 149.9)
		(mid 133.744454 149.980546)
		(end 133.825 150.175)
		(width 0.1)
		(layer "In2.Cu")
		(net 638)
	)
	(arc
		(start 128.470876 152.794125)
		(mid 128.644736 152.72211)
		(end 128.716751 152.54825)
		(width 0.1)
		(layer "In2.Cu")
		(net 638)
	)
	(arc
		(start 135.2 150.5)
		(mid 135.394454 150.419454)
		(end 135.475 150.225)
		(width 0.1)
		(layer "In2.Cu")
		(net 638)
	)
	(arc
		(start 130.8 150.5)
		(mid 130.994454 150.419454)
		(end 131.075 150.225)
		(width 0.1)
		(layer "In2.Cu")
		(net 638)
	)
	(arc
		(start 129.491532 150.76054)
		(mid 129.650631 150.826441)
		(end 129.80973 150.76054)
		(width 0.1)
		(layer "In2.Cu")
		(net 638)
	)
	(arc
		(start 134.375 150.175)
		(mid 134.455546 149.980546)
		(end 134.65 149.9)
		(width 0.1)
		(layer "In2.Cu")
		(net 638)
	)
	(arc
		(start 128.470826 153.994175)
		(mid 128.644651 153.922175)
		(end 128.716651 153.74835)
		(width 0.1)
		(layer "In2.Cu")
		(net 638)
	)
	(arc
		(start 134.1 150.5)
		(mid 134.294454 150.419454)
		(end 134.375 150.225)
		(width 0.1)
		(layer "In2.Cu")
		(net 638)
	)
	(arc
		(start 128.981395 150.8868)
		(mid 128.915494 150.727701)
		(end 128.981395 150.568602)
		(width 0.1)
		(layer "In2.Cu")
		(net 638)
	)
	(arc
		(start 128.225 154.24)
		(mid 128.297 154.066175)
		(end 128.470825 153.994175)
		(width 0.1)
		(layer "In2.Cu")
		(net 638)
	)
	(arc
		(start 129.173333 151.396937)
		(mid 129.239234 151.237837)
		(end 129.173333 151.078737)
		(width 0.1)
		(layer "In2.Cu")
		(net 638)
	)
	(arc
		(start 128.225 153.04)
		(mid 128.297015 152.86614)
		(end 128.470875 152.794125)
		(width 0.1)
		(layer "In2.Cu")
		(net 638)
	)
	(arc
		(start 129.80973 150.76054)
		(mid 129.875631 150.60144)
		(end 129.80973 150.44234)
		(width 0.1)
		(layer "In2.Cu")
		(net 638)
	)
	(segment
		(start 121.24 158.4)
		(end 122.627 158.4)
		(width 0.256)
		(layer "F.Cu")
		(net 639)
	)
	(segment
		(start 120.84 158.8)
		(end 121.24 158.4)
		(width 0.256)
		(layer "F.Cu")
		(net 639)
	)
	(segment
		(start 181.9995 144.9995)
		(end 181.5 144.5)
		(width 0.256)
		(layer "F.Cu")
		(net 639)
	)
	(segment
		(start 120.448 158.8)
		(end 120.84 158.8)
		(width 0.256)
		(layer "F.Cu")
		(net 639)
	)
	(via
		(at 181.5 144.5)
		(size 0.45)
		(drill 0.1)
		(layers "F.Cu" "B.Cu")
		(remove_unused_layers yes)
		(keep_end_layers yes)
		(zone_layer_connections)
		(net 639)
	)
	(via
		(at 122.627 158.4)
		(size 0.45)
		(drill 0.1)
		(layers "F.Cu" "B.Cu")
		(remove_unused_layers yes)
		(keep_end_layers yes)
		(zone_layer_connections)
		(net 639)
	)
	(segment
		(start 141.72 149.17)
		(end 127.89 149.17)
		(width 0.1)
		(layer "In2.Cu")
		(net 639)
	)
	(segment
		(start 127.300192 154.295)
		(end 126.955 154.295)
		(width 0.1)
		(layer "In2.Cu")
		(net 639)
	)
	(segment
		(start 126.955 152.345)
		(end 127.30022 152.345)
		(width 0.1)
		(layer "In2.Cu")
		(net 639)
	)
	(segment
		(start 145.16 149.5)
		(end 142.05 149.5)
		(width 0.1)
		(layer "In2.Cu")
		(net 639)
	)
	(segment
		(start 126.955 153.645)
		(end 127.300192 153.645)
		(width 0.1)
		(layer "In2.Cu")
		(net 639)
	)
	(segment
		(start 127.89 149.17)
		(end 127.759237 149.300759)
		(width 0.1)
		(layer "In2.Cu")
		(net 639)
	)
	(segment
		(start 126.84 150.22)
		(end 126.63 150.43)
		(width 0.1)
		(layer "In2.Cu")
		(net 639)
	)
	(segment
		(start 181.5 144.5)
		(end 181 144)
		(width 0.1)
		(layer "In2.Cu")
		(net 639)
	)
	(segment
		(start 158.83 146.28)
		(end 148.38 146.28)
		(width 0.1)
		(layer "In2.Cu")
		(net 639)
	)
	(segment
		(start 126.17 155.66)
		(end 125.367 155.66)
		(width 0.1)
		(layer "In2.Cu")
		(net 639)
	)
	(segment
		(start 174.745 144.28)
		(end 160.83 144.28)
		(width 0.1)
		(layer "In2.Cu")
		(net 639)
	)
	(segment
		(start 126.955 151.045)
		(end 127.30022 151.045)
		(width 0.1)
		(layer "In2.Cu")
		(net 639)
	)
	(segment
		(start 126.63 155.2)
		(end 126.17 155.66)
		(width 0.1)
		(layer "In2.Cu")
		(net 639)
	)
	(segment
		(start 142.05 149.5)
		(end 141.72 149.17)
		(width 0.1)
		(layer "In2.Cu")
		(net 639)
	)
	(segment
		(start 127.30022 152.995)
		(end 126.955 152.995)
		(width 0.1)
		(layer "In2.Cu")
		(net 639)
	)
	(segment
		(start 160.83 144.28)
		(end 158.83 146.28)
		(width 0.1)
		(layer "In2.Cu")
		(net 639)
	)
	(segment
		(start 125.367 155.66)
		(end 122.627 158.4)
		(width 0.1)
		(layer "In2.Cu")
		(net 639)
	)
	(segment
		(start 126.63 154.999082)
		(end 126.63 155.2)
		(width 0.1)
		(layer "In2.Cu")
		(net 639)
	)
	(segment
		(start 148.38 146.28)
		(end 145.16 149.5)
		(width 0.1)
		(layer "In2.Cu")
		(net 639)
	)
	(segment
		(start 127.928359 150.389121)
		(end 127.92836 150.389121)
		(width 0.1)
		(layer "In2.Cu")
		(net 639)
	)
	(segment
		(start 127.46874 150.389121)
		(end 127.299619 150.22)
		(width 0.1)
		(layer "In2.Cu")
		(net 639)
	)
	(segment
		(start 175.025 144)
		(end 174.745 144.28)
		(width 0.1)
		(layer "In2.Cu")
		(net 639)
	)
	(segment
		(start 127.30022 151.695)
		(end 126.955 151.695)
		(width 0.1)
		(layer "In2.Cu")
		(net 639)
	)
	(segment
		(start 126.63 154.62)
		(end 126.63 154.999082)
		(width 0.1)
		(layer "In2.Cu")
		(net 639)
	)
	(segment
		(start 181 144)
		(end 175.025 144)
		(width 0.1)
		(layer "In2.Cu")
		(net 639)
	)
	(segment
		(start 127.759237 149.760379)
		(end 127.928359 149.929501)
		(width 0.1)
		(layer "In2.Cu")
		(net 639)
	)
	(segment
		(start 126.63 150.43)
		(end 126.63 150.72)
		(width 0.1)
		(layer "In2.Cu")
		(net 639)
	)
	(segment
		(start 127.299619 150.22)
		(end 127.299618 150.22)
		(width 0.1)
		(layer "In2.Cu")
		(net 639)
	)
	(arc
		(start 127.92836 150.389121)
		(mid 127.69855 150.484311)
		(end 127.46874 150.389121)
		(width 0.1)
		(layer "In2.Cu")
		(net 639)
	)
	(arc
		(start 127.625192 153.97)
		(mid 127.530002 154.19981)
		(end 127.300192 154.295)
		(width 0.1)
		(layer "In2.Cu")
		(net 639)
	)
	(arc
		(start 126.63 153.32)
		(mid 126.72519 153.54981)
		(end 126.955 153.645)
		(width 0.1)
		(layer "In2.Cu")
		(net 639)
	)
	(arc
		(start 126.955 151.695)
		(mid 126.72519 151.79019)
		(end 126.63 152.02)
		(width 0.1)
		(layer "In2.Cu")
		(net 639)
	)
	(arc
		(start 127.30022 151.045)
		(mid 127.53003 151.14019)
		(end 127.62522 151.37)
		(width 0.1)
		(layer "In2.Cu")
		(net 639)
	)
	(arc
		(start 127.62522 152.67)
		(mid 127.53003 152.89981)
		(end 127.30022 152.995)
		(width 0.1)
		(layer "In2.Cu")
		(net 639)
	)
	(arc
		(start 127.299618 150.22)
		(mid 127.069809 150.12481)
		(end 126.84 150.22)
		(width 0.1)
		(layer "In2.Cu")
		(net 639)
	)
	(arc
		(start 127.759237 149.300759)
		(mid 127.664047 149.530569)
		(end 127.759237 149.760379)
		(width 0.1)
		(layer "In2.Cu")
		(net 639)
	)
	(arc
		(start 127.62522 151.37)
		(mid 127.53003 151.59981)
		(end 127.30022 151.695)
		(width 0.1)
		(layer "In2.Cu")
		(net 639)
	)
	(arc
		(start 126.955 152.995)
		(mid 126.72519 153.09019)
		(end 126.63 153.32)
		(width 0.1)
		(layer "In2.Cu")
		(net 639)
	)
	(arc
		(start 126.63 150.72)
		(mid 126.72519 150.94981)
		(end 126.955 151.045)
		(width 0.1)
		(layer "In2.Cu")
		(net 639)
	)
	(arc
		(start 126.63 152.02)
		(mid 126.72519 152.24981)
		(end 126.955 152.345)
		(width 0.1)
		(layer "In2.Cu")
		(net 639)
	)
	(arc
		(start 126.955 154.295)
		(mid 126.72519 154.39019)
		(end 126.63 154.62)
		(width 0.1)
		(layer "In2.Cu")
		(net 639)
	)
	(arc
		(start 127.300192 153.645)
		(mid 127.530002 153.74019)
		(end 127.625192 153.97)
		(width 0.1)
		(layer "In2.Cu")
		(net 639)
	)
	(arc
		(start 127.928359 149.929501)
		(mid 128.023549 150.159311)
		(end 127.928359 150.389121)
		(width 0.1)
		(layer "In2.Cu")
		(net 639)
	)
	(arc
		(start 127.30022 152.345)
		(mid 127.53003 152.44019)
		(end 127.62522 152.67)
		(width 0.1)
		(layer "In2.Cu")
		(net 639)
	)
	(segment
		(start 180.9995 146.999501)
		(end 180.5 146.5)
		(width 0.256)
		(layer "F.Cu")
		(net 640)
	)
	(segment
		(start 120.768 159.998)
		(end 121.07 160.3)
		(width 0.256)
		(layer "F.Cu")
		(net 640)
	)
	(segment
		(start 120.423 159.998)
		(end 120.768 159.998)
		(width 0.256)
		(layer "F.Cu")
		(net 640)
	)
	(segment
		(start 121.07 160.3)
		(end 122.627 160.3)
		(width 0.256)
		(layer "F.Cu")
		(net 640)
	)
	(via
		(at 122.627 160.3)
		(size 0.45)
		(drill 0.1)
		(layers "F.Cu" "B.Cu")
		(remove_unused_layers yes)
		(keep_end_layers yes)
		(zone_layer_connections)
		(net 640)
	)
	(via
		(at 180.5 146.5)
		(size 0.45)
		(drill 0.1)
		(layers "F.Cu" "B.Cu")
		(remove_unused_layers yes)
		(keep_end_layers yes)
		(zone_layer_connections)
		(net 640)
	)
	(segment
		(start 126.49 158.87)
		(end 128.52 158.87)
		(width 0.1)
		(layer "In2.Cu")
		(net 640)
	)
	(segment
		(start 129.907017 156.978918)
		(end 130.411099 157.483)
		(width 0.1)
		(layer "In2.Cu")
		(net 640)
	)
	(segment
		(start 122.627 160.3)
		(end 125.06 160.3)
		(width 0.1)
		(layer "In2.Cu")
		(net 640)
	)
	(segment
		(start 160.55 149.53)
		(end 162.77 147.31)
		(width 0.1)
		(layer "In2.Cu")
		(net 640)
	)
	(segment
		(start 129.951467 157.942604)
		(end 129.447397 157.438536)
		(width 0.1)
		(layer "In2.Cu")
		(net 640)
	)
	(segment
		(start 130.826241 156.059665)
		(end 130.826242 156.059667)
		(width 0.1)
		(layer "In2.Cu")
		(net 640)
	)
	(segment
		(start 130.870718 157.02338)
		(end 130.870717 157.02338)
		(width 0.1)
		(layer "In2.Cu")
		(net 640)
	)
	(segment
		(start 129.907016 156.978916)
		(end 129.907017 156.978918)
		(width 0.1)
		(layer "In2.Cu")
		(net 640)
	)
	(segment
		(start 180 147.7)
		(end 180 147.3)
		(width 0.1)
		(layer "In2.Cu")
		(net 640)
	)
	(segment
		(start 131.78993 156.104116)
		(end 131.285847 155.600034)
		(width 0.1)
		(layer "In2.Cu")
		(net 640)
	)
	(segment
		(start 129.469622 158.38)
		(end 129.469623 158.379999)
		(width 0.1)
		(layer "In2.Cu")
		(net 640)
	)
	(segment
		(start 129.951468 157.942604)
		(end 129.951467 157.942604)
		(width 0.1)
		(layer "In2.Cu")
		(net 640)
	)
	(segment
		(start 173.13 147.31)
		(end 173.82 148)
		(width 0.1)
		(layer "In2.Cu")
		(net 640)
	)
	(segment
		(start 129.01 158.38)
		(end 129.010004 158.38)
		(width 0.1)
		(layer "In2.Cu")
		(net 640)
	)
	(segment
		(start 130.870717 157.02338)
		(end 130.366622 156.519285)
		(width 0.1)
		(layer "In2.Cu")
		(net 640)
	)
	(segment
		(start 162.77 147.31)
		(end 173.13 147.31)
		(width 0.1)
		(layer "In2.Cu")
		(net 640)
	)
	(segment
		(start 129.469623 158.379999)
		(end 129.491848 158.402224)
		(width 0.1)
		(layer "In2.Cu")
		(net 640)
	)
	(segment
		(start 179.7 148)
		(end 180 147.7)
		(width 0.1)
		(layer "In2.Cu")
		(net 640)
	)
	(segment
		(start 137.61 152.65)
		(end 148.06 152.65)
		(width 0.1)
		(layer "In2.Cu")
		(net 640)
	)
	(segment
		(start 131.789931 156.104116)
		(end 131.78993 156.104116)
		(width 0.1)
		(layer "In2.Cu")
		(net 640)
	)
	(segment
		(start 132.227339 155.162668)
		(end 135.04 152.35)
		(width 0.1)
		(layer "In2.Cu")
		(net 640)
	)
	(segment
		(start 129.951467 158.402225)
		(end 129.951468 158.402224)
		(width 0.1)
		(layer "In2.Cu")
		(net 640)
	)
	(segment
		(start 131.745467 155.140414)
		(end 131.745466 155.140414)
		(width 0.1)
		(layer "In2.Cu")
		(net 640)
	)
	(segment
		(start 135.04 152.35)
		(end 137.31 152.35)
		(width 0.1)
		(layer "In2.Cu")
		(net 640)
	)
	(segment
		(start 151.18 149.53)
		(end 160.55 149.53)
		(width 0.1)
		(layer "In2.Cu")
		(net 640)
	)
	(segment
		(start 180.5 146.8)
		(end 180.5 146.5)
		(width 0.1)
		(layer "In2.Cu")
		(net 640)
	)
	(segment
		(start 130.870718 157.482999)
		(end 130.870718 157.483)
		(width 0.1)
		(layer "In2.Cu")
		(net 640)
	)
	(segment
		(start 180 147.3)
		(end 180.5 146.8)
		(width 0.1)
		(layer "In2.Cu")
		(net 640)
	)
	(segment
		(start 148.06 152.65)
		(end 151.18 149.53)
		(width 0.1)
		(layer "In2.Cu")
		(net 640)
	)
	(segment
		(start 125.06 160.3)
		(end 126.49 158.87)
		(width 0.1)
		(layer "In2.Cu")
		(net 640)
	)
	(segment
		(start 130.826242 156.059667)
		(end 131.330311 156.563736)
		(width 0.1)
		(layer "In2.Cu")
		(net 640)
	)
	(segment
		(start 131.745466 155.140414)
		(end 131.767718 155.162666)
		(width 0.1)
		(layer "In2.Cu")
		(net 640)
	)
	(segment
		(start 132.227337 155.162667)
		(end 132.227339 155.162668)
		(width 0.1)
		(layer "In2.Cu")
		(net 640)
	)
	(segment
		(start 137.31 152.35)
		(end 137.61 152.65)
		(width 0.1)
		(layer "In2.Cu")
		(net 640)
	)
	(segment
		(start 128.52 158.87)
		(end 129.01 158.38)
		(width 0.1)
		(layer "In2.Cu")
		(net 640)
	)
	(segment
		(start 129.447397 156.978916)
		(end 129.447396 156.978918)
		(width 0.1)
		(layer "In2.Cu")
		(net 640)
	)
	(segment
		(start 130.366623 156.059666)
		(end 130.366621 156.059667)
		(width 0.1)
		(layer "In2.Cu")
		(net 640)
	)
	(segment
		(start 173.82 148)
		(end 179.7 148)
		(width 0.1)
		(layer "In2.Cu")
		(net 640)
	)
	(arc
		(start 129.447397 157.438536)
		(mid 129.352207 157.208726)
		(end 129.447397 156.978916)
		(width 0.1)
		(layer "In2.Cu")
		(net 640)
	)
	(arc
		(start 131.789931 156.563736)
		(mid 131.885121 156.333926)
		(end 131.789931 156.104116)
		(width 0.1)
		(layer "In2.Cu")
		(net 640)
	)
	(arc
		(start 129.447396 156.978918)
		(mid 129.677206 156.883728)
		(end 129.907016 156.978916)
		(width 0.1)
		(layer "In2.Cu")
		(net 640)
	)
	(arc
		(start 130.366621 156.059667)
		(mid 130.596431 155.964477)
		(end 130.826241 156.059665)
		(width 0.1)
		(layer "In2.Cu")
		(net 640)
	)
	(arc
		(start 129.010004 158.38)
		(mid 129.239813 158.28481)
		(end 129.469622 158.38)
		(width 0.1)
		(layer "In2.Cu")
		(net 640)
	)
	(arc
		(start 130.366622 156.519285)
		(mid 130.271432 156.289475)
		(end 130.366623 156.059666)
		(width 0.1)
		(layer "In2.Cu")
		(net 640)
	)
	(arc
		(start 129.491848 158.402224)
		(mid 129.721657 158.497415)
		(end 129.951467 158.402225)
		(width 0.1)
		(layer "In2.Cu")
		(net 640)
	)
	(arc
		(start 129.951468 158.402224)
		(mid 130.046658 158.172414)
		(end 129.951468 157.942604)
		(width 0.1)
		(layer "In2.Cu")
		(net 640)
	)
	(arc
		(start 131.285847 155.600034)
		(mid 131.190657 155.370224)
		(end 131.285847 155.140414)
		(width 0.1)
		(layer "In2.Cu")
		(net 640)
	)
	(arc
		(start 131.330311 156.563736)
		(mid 131.560121 156.658926)
		(end 131.789931 156.563736)
		(width 0.1)
		(layer "In2.Cu")
		(net 640)
	)
	(arc
		(start 131.285847 155.140414)
		(mid 131.515657 155.045224)
		(end 131.745467 155.140414)
		(width 0.1)
		(layer "In2.Cu")
		(net 640)
	)
	(arc
		(start 131.767718 155.162666)
		(mid 131.997527 155.257857)
		(end 132.227337 155.162667)
		(width 0.1)
		(layer "In2.Cu")
		(net 640)
	)
	(arc
		(start 130.870718 157.483)
		(mid 130.965908 157.25319)
		(end 130.870718 157.02338)
		(width 0.1)
		(layer "In2.Cu")
		(net 640)
	)
	(arc
		(start 130.411099 157.483)
		(mid 130.640909 157.57819)
		(end 130.870718 157.482999)
		(width 0.1)
		(layer "In2.Cu")
		(net 640)
	)
	(segment
		(start 180.9995 145.9995)
		(end 180.5 145.5)
		(width 0.256)
		(layer "F.Cu")
		(net 641)
	)
	(segment
		(start 121.2 159.6)
		(end 121.33 159.73)
		(width 0.256)
		(layer "F.Cu")
		(net 641)
	)
	(segment
		(start 121.33 159.73)
		(end 122.799103 159.73)
		(width 0.256)
		(layer "F.Cu")
		(net 641)
	)
	(segment
		(start 120.448 159.6)
		(end 121.2 159.6)
		(width 0.256)
		(layer "F.Cu")
		(net 641)
	)
	(segment
		(start 122.799103 159.73)
		(end 122.881553 159.81245)
		(width 0.256)
		(layer "F.Cu")
		(net 641)
	)
	(via
		(at 180.5 145.5)
		(size 0.45)
		(drill 0.1)
		(layers "F.Cu" "B.Cu")
		(remove_unused_layers yes)
		(keep_end_layers yes)
		(zone_layer_connections)
		(net 641)
	)
	(via
		(at 122.881553 159.81245)
		(size 0.45)
		(drill 0.1)
		(layers "F.Cu" "B.Cu")
		(remove_unused_layers yes)
		(keep_end_layers yes)
		(zone_layer_connections)
		(net 641)
	)
	(segment
		(start 180 146)
		(end 180.5 145.5)
		(width 0.1)
		(layer "In2.Cu")
		(net 641)
	)
	(segment
		(start 147.43 151.8)
		(end 150.53 148.7)
		(width 0.1)
		(layer "In2.Cu")
		(net 641)
	)
	(segment
		(start 124.64 159.8)
		(end 126.32 158.12)
		(width 0.1)
		(layer "In2.Cu")
		(net 641)
	)
	(segment
		(start 160.26 148.7)
		(end 162.46 146.5)
		(width 0.1)
		(layer "In2.Cu")
		(net 641)
	)
	(segment
		(start 131.123276 152.078729)
		(end 131.123274 152.07873)
		(width 0.1)
		(layer "In2.Cu")
		(net 641)
	)
	(segment
		(start 132.46 151.8)
		(end 147.43 151.8)
		(width 0.1)
		(layer "In2.Cu")
		(net 641)
	)
	(segment
		(start 180 146.7)
		(end 180 146)
		(width 0.1)
		(layer "In2.Cu")
		(net 641)
	)
	(segment
		(start 133.02981 153.207446)
		(end 133.029809 153.207446)
		(width 0.1)
		(layer "In2.Cu")
		(net 641)
	)
	(segment
		(start 132.235634 152.024363)
		(end 132.46 151.8)
		(width 0.1)
		(layer "In2.Cu")
		(net 641)
	)
	(segment
		(start 132.252021 154.374205)
		(end 132.252022 154.374205)
		(width 0.1)
		(layer "In2.Cu")
		(net 641)
	)
	(segment
		(start 130.53 155.04)
		(end 130.53 153.73)
		(width 0.1)
		(layer "In2.Cu")
		(net 641)
	)
	(segment
		(start 130.734365 152.078731)
		(end 130.734366 152.078729)
		(width 0.1)
		(layer "In2.Cu")
		(net 641)
	)
	(segment
		(start 122.881553 159.81245)
		(end 122.894003 159.8)
		(width 0.1)
		(layer "In2.Cu")
		(net 641)
	)
	(segment
		(start 132.235635 152.024362)
		(end 132.235634 152.024363)
		(width 0.1)
		(layer "In2.Cu")
		(net 641)
	)
	(segment
		(start 132.235635 152.024362)
		(end 132.225329 152.034669)
		(width 0.1)
		(layer "In2.Cu")
		(net 641)
	)
	(segment
		(start 174.15 147)
		(end 179.7 147)
		(width 0.1)
		(layer "In2.Cu")
		(net 641)
	)
	(segment
		(start 122.894003 159.8)
		(end 124.64 159.8)
		(width 0.1)
		(layer "In2.Cu")
		(net 641)
	)
	(segment
		(start 126.32 158.12)
		(end 127.45 158.12)
		(width 0.1)
		(layer "In2.Cu")
		(net 641)
	)
	(segment
		(start 127.45 158.12)
		(end 130.53 155.04)
		(width 0.1)
		(layer "In2.Cu")
		(net 641)
	)
	(segment
		(start 133.029808 153.596356)
		(end 133.029809 153.596355)
		(width 0.1)
		(layer "In2.Cu")
		(net 641)
	)
	(segment
		(start 150.53 148.7)
		(end 160.26 148.7)
		(width 0.1)
		(layer "In2.Cu")
		(net 641)
	)
	(segment
		(start 162.46 146.5)
		(end 173.65 146.5)
		(width 0.1)
		(layer "In2.Cu")
		(net 641)
	)
	(segment
		(start 179.7 147)
		(end 180 146.7)
		(width 0.1)
		(layer "In2.Cu")
		(net 641)
	)
	(segment
		(start 130.53 153.73)
		(end 130.68 153.58)
		(width 0.1)
		(layer "In2.Cu")
		(net 641)
	)
	(segment
		(start 131.123274 152.07873)
		(end 132.6409 153.596356)
		(width 0.1)
		(layer "In2.Cu")
		(net 641)
	)
	(segment
		(start 133.029809 153.207446)
		(end 132.225343 152.40298)
		(width 0.1)
		(layer "In2.Cu")
		(net 641)
	)
	(segment
		(start 173.65 146.5)
		(end 174.15 147)
		(width 0.1)
		(layer "In2.Cu")
		(net 641)
	)
	(segment
		(start 131.068908 153.58)
		(end 131.863113 154.374205)
		(width 0.1)
		(layer "In2.Cu")
		(net 641)
	)
	(segment
		(start 132.252022 153.985295)
		(end 132.252022 153.985296)
		(width 0.1)
		(layer "In2.Cu")
		(net 641)
	)
	(segment
		(start 132.252022 153.985296)
		(end 130.734365 152.467639)
		(width 0.1)
		(layer "In2.Cu")
		(net 641)
	)
	(arc
		(start 133.029809 153.596355)
		(mid 133.110355 153.401901)
		(end 133.02981 153.207446)
		(width 0.1)
		(layer "In2.Cu")
		(net 641)
	)
	(arc
		(start 132.252022 154.374205)
		(mid 132.332568 154.17975)
		(end 132.252022 153.985295)
		(width 0.1)
		(layer "In2.Cu")
		(net 641)
	)
	(arc
		(start 131.863113 154.374205)
		(mid 132.057567 154.45475)
		(end 132.252021 154.374205)
		(width 0.1)
		(layer "In2.Cu")
		(net 641)
	)
	(arc
		(start 130.734366 152.078729)
		(mid 130.92882 151.998184)
		(end 131.123276 152.078729)
		(width 0.1)
		(layer "In2.Cu")
		(net 641)
	)
	(arc
		(start 130.68 153.58)
		(mid 130.874454 153.499455)
		(end 131.068908 153.58)
		(width 0.1)
		(layer "In2.Cu")
		(net 641)
	)
	(arc
		(start 132.6409 153.596356)
		(mid 132.835354 153.676901)
		(end 133.029808 153.596356)
		(width 0.1)
		(layer "In2.Cu")
		(net 641)
	)
	(arc
		(start 132.225343 152.40298)
		(mid 132.149061 152.218828)
		(end 132.225329 152.034669)
		(width 0.1)
		(layer "In2.Cu")
		(net 641)
	)
	(arc
		(start 130.734365 152.467639)
		(mid 130.653821 152.273184)
		(end 130.734365 152.078731)
		(width 0.1)
		(layer "In2.Cu")
		(net 641)
	)
	(segment
		(start 178.9995 147.9995)
		(end 178.5 147.5)
		(width 0.256)
		(layer "F.Cu")
		(net 643)
	)
	(via
		(at 178.5 147.5)
		(size 0.45)
		(drill 0.1)
		(layers "F.Cu" "B.Cu")
		(remove_unused_layers yes)
		(keep_end_layers yes)
		(zone_layer_connections)
		(net 643)
	)
	(segment
		(start 183.9995 153.0005)
		(end 183.5 153.499999)
		(width 0.256)
		(layer "F.Cu")
		(net 644)
	)
	(segment
		(start 126.576 184.778)
		(end 126.576 187.012)
		(width 0.201)
		(layer "F.Cu")
		(net 644)
	)
	(segment
		(start 126.576 187.012)
		(end 127.106 187.542)
		(width 0.201)
		(layer "F.Cu")
		(net 644)
	)
	(via
		(at 183.5 153.499999)
		(size 0.45)
		(drill 0.1)
		(layers "F.Cu" "B.Cu")
		(remove_unused_layers yes)
		(keep_end_layers yes)
		(zone_layer_connections)
		(net 644)
	)
	(via
		(at 127.106 187.542)
		(size 0.45)
		(drill 0.1)
		(layers "F.Cu" "B.Cu")
		(remove_unused_layers yes)
		(keep_end_layers yes)
		(zone_layer_connections)
		(net 644)
	)
	(segment
		(start 127.106 187.542)
		(end 127.002 187.542)
		(width 0.201)
		(layer "B.Cu")
		(net 644)
	)
	(segment
		(start 127.002 187.542)
		(end 126.4 186.94)
		(width 0.201)
		(layer "B.Cu")
		(net 644)
	)
	(segment
		(start 182.95 155.75)
		(end 182.95 155.35)
		(width 0.1)
		(layer "In9.Cu")
		(net 644)
	)
	(segment
		(start 183.7 155)
		(end 183.9 154.8)
		(width 0.1)
		(layer "In9.Cu")
		(net 644)
	)
	(segment
		(start 174.5 162)
		(end 179.6 162)
		(width 0.1)
		(layer "In9.Cu")
		(net 644)
	)
	(segment
		(start 183.3 155)
		(end 183.7 155)
		(width 0.1)
		(layer "In9.Cu")
		(net 644)
	)
	(segment
		(start 183.9 154.8)
		(end 183.9 154.25)
		(width 0.1)
		(layer "In9.Cu")
		(net 644)
	)
	(segment
		(start 127.106 187.4435)
		(end 130.0565 187.4435)
		(width 0.1)
		(layer "In9.Cu")
		(net 644)
	)
	(segment
		(start 165 168.5)
		(end 168 168.5)
		(width 0.1)
		(layer "In9.Cu")
		(net 644)
	)
	(segment
		(start 183.5 153.85)
		(end 183.5 153.499999)
		(width 0.1)
		(layer "In9.Cu")
		(net 644)
	)
	(segment
		(start 179.6 162)
		(end 180 161.6)
		(width 0.1)
		(layer "In9.Cu")
		(net 644)
	)
	(segment
		(start 180 161.6)
		(end 180 156.469669)
		(width 0.1)
		(layer "In9.Cu")
		(net 644)
	)
	(segment
		(start 182.81 155.89)
		(end 182.95 155.75)
		(width 0.1)
		(layer "In9.Cu")
		(net 644)
	)
	(segment
		(start 182.95 155.35)
		(end 183.3 155)
		(width 0.1)
		(layer "In9.Cu")
		(net 644)
	)
	(segment
		(start 140.5 176.5)
		(end 157 176.5)
		(width 0.1)
		(layer "In9.Cu")
		(net 644)
	)
	(segment
		(start 168 168.5)
		(end 174.5 162)
		(width 0.1)
		(layer "In9.Cu")
		(net 644)
	)
	(segment
		(start 157 176.5)
		(end 165 168.5)
		(width 0.1)
		(layer "In9.Cu")
		(net 644)
	)
	(segment
		(start 180 156.469669)
		(end 180.579669 155.89)
		(width 0.1)
		(layer "In9.Cu")
		(net 644)
	)
	(segment
		(start 183.9 154.25)
		(end 183.5 153.85)
		(width 0.1)
		(layer "In9.Cu")
		(net 644)
	)
	(segment
		(start 139.2 178.3)
		(end 139.2 177.8)
		(width 0.1)
		(layer "In9.Cu")
		(net 644)
	)
	(segment
		(start 180.579669 155.89)
		(end 182.81 155.89)
		(width 0.1)
		(layer "In9.Cu")
		(net 644)
	)
	(segment
		(start 130.0565 187.4435)
		(end 139.2 178.3)
		(width 0.1)
		(layer "In9.Cu")
		(net 644)
	)
	(segment
		(start 139.2 177.8)
		(end 140.5 176.5)
		(width 0.1)
		(layer "In9.Cu")
		(net 644)
	)
	(segment
		(start 179.9995 147.9995)
		(end 179.5 147.5)
		(width 0.256)
		(layer "F.Cu")
		(net 646)
	)
	(via
		(at 179.5 147.5)
		(size 0.45)
		(drill 0.1)
		(layers "F.Cu" "B.Cu")
		(remove_unused_layers yes)
		(keep_end_layers yes)
		(zone_layer_connections)
		(net 646)
	)
	(via
		(at 119.65 162)
		(size 0.45)
		(drill 0.1)
		(layers "F.Cu" "B.Cu")
		(remove_unused_layers yes)
		(keep_end_layers yes)
		(zone_layer_connections)
		(net 647)
	)
	(segment
		(start 119.65 160.505)
		(end 119.075 159.93)
		(width 0.177)
		(layer "B.Cu")
		(net 647)
	)
	(segment
		(start 119.65 162)
		(end 119.65 160.505)
		(width 0.177)
		(layer "B.Cu")
		(net 647)
	)
	(segment
		(start 182.5005 165.4995)
		(end 183 165)
		(width 0.256)
		(layer "F.Cu")
		(net 648)
	)
	(via
		(at 182.5005 165.4995)
		(size 0.45)
		(drill 0.1)
		(layers "F.Cu" "B.Cu")
		(remove_unused_layers yes)
		(keep_end_layers yes)
		(zone_layer_connections)
		(net 648)
	)
	(via
		(at 125.01 148.41)
		(size 0.45)
		(drill 0.1)
		(layers "F.Cu" "B.Cu")
		(remove_unused_layers yes)
		(keep_end_layers yes)
		(zone_layer_connections)
		(net 648)
	)
	(segment
		(start 124.01895 148.265001)
		(end 124.65995 148.265001)
		(width 0.16)
		(layer "B.Cu")
		(net 648)
	)
	(segment
		(start 123.602499 148.4375)
		(end 123.43 148.61)
		(width 0.16)
		(layer "B.Cu")
		(net 648)
	)
	(arc
		(start 125.01 148.41)
		(mid 124.849392 148.302683)
		(end 124.65995 148.265001)
		(width 0.16)
		(layer "B.Cu")
		(net 648)
	)
	(arc
		(start 124.01895 148.265001)
		(mid 123.793568 148.309832)
		(end 123.602499 148.4375)
		(width 0.16)
		(layer "B.Cu")
		(net 648)
	)
	(segment
		(start 153.343233 154.27001)
		(end 153.343235 154.270012)
		(width 0.1)
		(layer "In4.Cu")
		(net 648)
	)
	(segment
		(start 156.02918 155.402441)
		(end 156.029181 155.402441)
		(width 0.1)
		(layer "In4.Cu")
		(net 648)
	)
	(segment
		(start 154.296711 154.129706)
		(end 154.156406 154.27001)
		(width 0.1)
		(layer "In4.Cu")
		(net 648)
	)
	(segment
		(start 153.483583 152.856872)
		(end 153.483582 152.856871)
		(width 0.1)
		(layer "In4.Cu")
		(net 648)
	)
	(segment
		(start 151.751186 151.584063)
		(end 151.751185 151.584064)
		(width 0.1)
		(layer "In4.Cu")
		(net 648)
	)
	(segment
		(start 156.842339 156.675246)
		(end 156.842338 156.675247)
		(width 0.1)
		(layer "In4.Cu")
		(net 648)
	)
	(segment
		(start 125.437487 148.235)
		(end 125.432484 148.235)
		(width 0.1)
		(layer "In4.Cu")
		(net 648)
	)
	(segment
		(start 179.200347 168.265)
		(end 174.860009 168.265)
		(width 0.1)
		(layer "In4.Cu")
		(net 648)
	)
	(segment
		(start 152.070443 152.184046)
		(end 152.070443 152.184047)
		(width 0.1)
		(layer "In4.Cu")
		(net 648)
	)
	(segment
		(start 154.756332 154.129707)
		(end 154.756331 154.129706)
		(width 0.1)
		(layer "In4.Cu")
		(net 648)
	)
	(segment
		(start 152.070441 152.997219)
		(end 152.070441 152.997218)
		(width 0.1)
		(layer "In4.Cu")
		(net 648)
	)
	(segment
		(start 172.518222 167.295)
		(end 172.443547 167.220325)
		(width 0.1)
		(layer "In4.Cu")
		(net 648)
	)
	(segment
		(start 182.5005 165.4995)
		(end 182.5005 165.211208)
		(width 0.1)
		(layer "In4.Cu")
		(net 648)
	)
	(segment
		(start 156.842338 156.675247)
		(end 156.70199 156.815594)
		(width 0.1)
		(layer "In4.Cu")
		(net 648)
	)
	(segment
		(start 154.616027 154.72963)
		(end 154.616027 154.729631)
		(width 0.1)
		(layer "In4.Cu")
		(net 648)
	)
	(segment
		(start 155.888819 156.002423)
		(end 156.029181 155.86206)
		(width 0.1)
		(layer "In4.Cu")
		(net 648)
	)
	(segment
		(start 155.569561 155.402441)
		(end 155.429198 155.542803)
		(width 0.1)
		(layer "In4.Cu")
		(net 648)
	)
	(segment
		(start 153.343235 153.456838)
		(end 153.343235 153.456839)
		(width 0.1)
		(layer "In4.Cu")
		(net 648)
	)
	(segment
		(start 170.282056 166.325)
		(end 167.652185 166.325)
		(width 0.1)
		(layer "In4.Cu")
		(net 648)
	)
	(segment
		(start 155.569562 155.40244)
		(end 155.569561 155.402441)
		(width 0.1)
		(layer "In4.Cu")
		(net 648)
	)
	(segment
		(start 157.301959 156.675248)
		(end 157.301958 156.675247)
		(width 0.1)
		(layer "In4.Cu")
		(net 648)
	)
	(segment
		(start 152.070443 152.184047)
		(end 152.210805 152.043684)
		(width 0.1)
		(layer "In4.Cu")
		(net 648)
	)
	(segment
		(start 150.797649 151.724427)
		(end 150.797649 151.724426)
		(width 0.1)
		(layer "In4.Cu")
		(net 648)
	)
	(segment
		(start 152.210806 151.584065)
		(end 152.210805 151.584064)
		(width 0.1)
		(layer "In4.Cu")
		(net 648)
	)
	(segment
		(start 126.541635 149.218413)
		(end 125.643594 148.320372)
		(width 0.1)
		(layer "In4.Cu")
		(net 648)
	)
	(segment
		(start 154.616026 155.542803)
		(end 154.616027 155.542804)
		(width 0.1)
		(layer "In4.Cu")
		(net 648)
	)
	(segment
		(start 153.343233 154.270011)
		(end 153.343233 154.27001)
		(width 0.1)
		(layer "In4.Cu")
		(net 648)
	)
	(segment
		(start 181.699289 166.977488)
		(end 181.268388 167.408388)
		(width 0.1)
		(layer "In4.Cu")
		(net 648)
	)
	(segment
		(start 146.562458 149.625)
		(end 127.523222 149.625)
		(width 0.1)
		(layer "In4.Cu")
		(net 648)
	)
	(segment
		(start 152.070441 152.997218)
		(end 152.070443 152.99722)
		(width 0.1)
		(layer "In4.Cu")
		(net 648)
	)
	(segment
		(start 153.023963 152.85687)
		(end 153.023962 152.856871)
		(width 0.1)
		(layer "In4.Cu")
		(net 648)
	)
	(segment
		(start 157.161611 157.275214)
		(end 157.161611 157.275215)
		(width 0.1)
		(layer "In4.Cu")
		(net 648)
	)
	(segment
		(start 151.751185 151.584064)
		(end 151.610822 151.724426)
		(width 0.1)
		(layer "In4.Cu")
		(net 648)
	)
	(segment
		(start 154.616025 155.542802)
		(end 154.616026 155.542803)
		(width 0.1)
		(layer "In4.Cu")
		(net 648)
	)
	(segment
		(start 154.296712 154.129705)
		(end 154.296711 154.129706)
		(width 0.1)
		(layer "In4.Cu")
		(net 648)
	)
	(segment
		(start 157.161611 157.275215)
		(end 157.301958 157.134867)
		(width 0.1)
		(layer "In4.Cu")
		(net 648)
	)
	(segment
		(start 153.023962 152.856871)
		(end 152.883614 152.997218)
		(width 0.1)
		(layer "In4.Cu")
		(net 648)
	)
	(segment
		(start 182.414291 165.125)
		(end 182.398844 165.125)
		(width 0.1)
		(layer "In4.Cu")
		(net 648)
	)
	(segment
		(start 155.888819 156.002422)
		(end 155.888819 156.002423)
		(width 0.1)
		(layer "In4.Cu")
		(net 648)
	)
	(segment
		(start 150.797649 151.724426)
		(end 150.208435 151.135213)
		(width 0.1)
		(layer "In4.Cu")
		(net 648)
	)
	(segment
		(start 155.888817 156.815594)
		(end 155.888819 156.815596)
		(width 0.1)
		(layer "In4.Cu")
		(net 648)
	)
	(segment
		(start 155.888817 156.815595)
		(end 155.888817 156.815594)
		(width 0.1)
		(layer "In4.Cu")
		(net 648)
	)
	(segment
		(start 157.161611 158.088389)
		(end 157.161611 158.088388)
		(width 0.1)
		(layer "In4.Cu")
		(net 648)
	)
	(segment
		(start 153.343235 153.456839)
		(end 153.483582 153.316491)
		(width 0.1)
		(layer "In4.Cu")
		(net 648)
	)
	(segment
		(start 182.125 165.505152)
		(end 182.125 165.949733)
		(width 0.1)
		(layer "In4.Cu")
		(net 648)
	)
	(segment
		(start 163.804429 164.731207)
		(end 157.161611 158.088389)
		(width 0.1)
		(layer "In4.Cu")
		(net 648)
	)
	(segment
		(start 154.616027 154.729631)
		(end 154.756331 154.589326)
		(width 0.1)
		(layer "In4.Cu")
		(net 648)
	)
	(segment
		(start 182.311515 165.161172)
		(end 182.236343 165.236343)
		(width 0.1)
		(layer "In4.Cu")
		(net 648)
	)
	(arc
		(start 125.432484 148.235)
		(mid 125.203839 148.28048)
		(end 125.01 148.41)
		(width 0.1)
		(layer "In4.Cu")
		(net 648)
	)
	(arc
		(start 155.888819 156.815596)
		(mid 155.720405 156.409009)
		(end 155.888819 156.002422)
		(width 0.1)
		(layer "In4.Cu")
		(net 648)
	)
	(arc
		(start 172.443547 167.220325)
		(mid 171.451848 166.557688)
		(end 170.282056 166.325)
		(width 0.1)
		(layer "In4.Cu")
		(net 648)
	)
	(arc
		(start 156.029181 155.402441)
		(mid 155.799372 155.30725)
		(end 155.569562 155.40244)
		(width 0.1)
		(layer "In4.Cu")
		(net 648)
	)
	(arc
		(start 181.268388 167.408388)
		(mid 180.319563 168.042373)
		(end 179.200347 168.265)
		(width 0.1)
		(layer "In4.Cu")
		(net 648)
	)
	(arc
		(start 152.883614 152.997218)
		(mid 152.477028 153.165632)
		(end 152.070441 152.997219)
		(width 0.1)
		(layer "In4.Cu")
		(net 648)
	)
	(arc
		(start 154.616027 155.542804)
		(mid 154.447613 155.136217)
		(end 154.616027 154.72963)
		(width 0.1)
		(layer "In4.Cu")
		(net 648)
	)
	(arc
		(start 154.756331 154.129706)
		(mid 154.526522 154.034515)
		(end 154.296712 154.129705)
		(width 0.1)
		(layer "In4.Cu")
		(net 648)
	)
	(arc
		(start 127.523222 149.625)
		(mid 126.991991 149.519331)
		(end 126.541635 149.218413)
		(width 0.1)
		(layer "In4.Cu")
		(net 648)
	)
	(arc
		(start 182.47525 165.15025)
		(mid 182.447281 165.131562)
		(end 182.414291 165.125)
		(width 0.1)
		(layer "In4.Cu")
		(net 648)
	)
	(arc
		(start 167.652185 166.325)
		(mid 165.569794 165.910786)
		(end 163.804429 164.731207)
		(width 0.1)
		(layer "In4.Cu")
		(net 648)
	)
	(arc
		(start 153.483582 153.316491)
		(mid 153.578773 153.086682)
		(end 153.483583 152.856872)
		(width 0.1)
		(layer "In4.Cu")
		(net 648)
	)
	(arc
		(start 157.301958 157.134867)
		(mid 157.397149 156.905058)
		(end 157.301959 156.675248)
		(width 0.1)
		(layer "In4.Cu")
		(net 648)
	)
	(arc
		(start 152.210805 151.584064)
		(mid 151.980996 151.488873)
		(end 151.751186 151.584063)
		(width 0.1)
		(layer "In4.Cu")
		(net 648)
	)
	(arc
		(start 182.125 165.949733)
		(mid 182.014361 166.50595)
		(end 181.699289 166.977488)
		(width 0.1)
		(layer "In4.Cu")
		(net 648)
	)
	(arc
		(start 153.343235 154.270012)
		(mid 153.174821 153.863425)
		(end 153.343235 153.456838)
		(width 0.1)
		(layer "In4.Cu")
		(net 648)
	)
	(arc
		(start 155.429198 155.542803)
		(mid 155.022611 155.711216)
		(end 154.616025 155.542802)
		(width 0.1)
		(layer "In4.Cu")
		(net 648)
	)
	(arc
		(start 153.483582 152.856871)
		(mid 153.253773 152.76168)
		(end 153.023963 152.85687)
		(width 0.1)
		(layer "In4.Cu")
		(net 648)
	)
	(arc
		(start 182.398844 165.125)
		(mid 182.351581 165.1344)
		(end 182.311515 165.161172)
		(width 0.1)
		(layer "In4.Cu")
		(net 648)
	)
	(arc
		(start 174.860009 168.265)
		(mid 173.592643 168.012905)
		(end 172.518222 167.295)
		(width 0.1)
		(layer "In4.Cu")
		(net 648)
	)
	(arc
		(start 182.5005 165.211208)
		(mid 182.493937 165.178217)
		(end 182.47525 165.15025)
		(width 0.1)
		(layer "In4.Cu")
		(net 648)
	)
	(arc
		(start 152.070443 152.99722)
		(mid 151.902029 152.590633)
		(end 152.070443 152.184046)
		(width 0.1)
		(layer "In4.Cu")
		(net 648)
	)
	(arc
		(start 125.643594 148.320372)
		(mid 125.549031 148.257188)
		(end 125.437487 148.235)
		(width 0.1)
		(layer "In4.Cu")
		(net 648)
	)
	(arc
		(start 156.70199 156.815594)
		(mid 156.295404 156.984008)
		(end 155.888817 156.815595)
		(width 0.1)
		(layer "In4.Cu")
		(net 648)
	)
	(arc
		(start 156.029181 155.86206)
		(mid 156.124371 155.63225)
		(end 156.02918 155.402441)
		(width 0.1)
		(layer "In4.Cu")
		(net 648)
	)
	(arc
		(start 154.756331 154.589326)
		(mid 154.851522 154.359517)
		(end 154.756332 154.129707)
		(width 0.1)
		(layer "In4.Cu")
		(net 648)
	)
	(arc
		(start 152.210805 152.043684)
		(mid 152.305996 151.813875)
		(end 152.210806 151.584065)
		(width 0.1)
		(layer "In4.Cu")
		(net 648)
	)
	(arc
		(start 157.301958 156.675247)
		(mid 157.072149 156.580056)
		(end 156.842339 156.675246)
		(width 0.1)
		(layer "In4.Cu")
		(net 648)
	)
	(arc
		(start 182.236343 165.236343)
		(mid 182.153937 165.359673)
		(end 182.125 165.505152)
		(width 0.1)
		(layer "In4.Cu")
		(net 648)
	)
	(arc
		(start 151.610822 151.724426)
		(mid 151.204236 151.89284)
		(end 150.797649 151.724427)
		(width 0.1)
		(layer "In4.Cu")
		(net 648)
	)
	(arc
		(start 150.208435 151.135213)
		(mid 148.535646 150.017492)
		(end 146.562458 149.625)
		(width 0.1)
		(layer "In4.Cu")
		(net 648)
	)
	(arc
		(start 154.156406 154.27001)
		(mid 153.74982 154.438424)
		(end 153.343233 154.270011)
		(width 0.1)
		(layer "In4.Cu")
		(net 648)
	)
	(arc
		(start 157.161611 158.088388)
		(mid 156.993197 157.681801)
		(end 157.161611 157.275214)
		(width 0.1)
		(layer "In4.Cu")
		(net 648)
	)
	(segment
		(start 182.5005 164.4995)
		(end 183 164)
		(width 0.256)
		(layer "F.Cu")
		(net 649)
	)
	(via
		(at 182.5005 164.4995)
		(size 0.45)
		(drill 0.1)
		(layers "F.Cu" "B.Cu")
		(remove_unused_layers yes)
		(keep_end_layers yes)
		(zone_layer_connections)
		(net 649)
	)
	(via
		(at 125.01 147.81)
		(size 0.45)
		(drill 0.1)
		(layers "F.Cu" "B.Cu")
		(remove_unused_layers yes)
		(keep_end_layers yes)
		(zone_layer_connections)
		(net 649)
	)
	(segment
		(start 123.602499 147.782499)
		(end 123.43 147.61)
		(width 0.16)
		(layer "B.Cu")
		(net 649)
	)
	(segment
		(start 124.659953 147.954999)
		(end 124.01895 147.954999)
		(width 0.16)
		(layer "B.Cu")
		(net 649)
	)
	(arc
		(start 125.01 147.81)
		(mid 124.849392 147.917318)
		(end 124.659953 147.954999)
		(width 0.16)
		(layer "B.Cu")
		(net 649)
	)
	(arc
		(start 123.602499 147.782499)
		(mid 123.793568 147.910167)
		(end 124.01895 147.954999)
		(width 0.16)
		(layer "B.Cu")
		(net 649)
	)
	(segment
		(start 153.520012 153.633616)
		(end 153.660359 153.493268)
		(width 0.1)
		(layer "In4.Cu")
		(net 649)
	)
	(segment
		(start 155.392785 155.225664)
		(end 155.392785 155.225665)
		(width 0.1)
		(layer "In4.Cu")
		(net 649)
	)
	(segment
		(start 156.065596 156.1792)
		(end 156.205958 156.038837)
		(width 0.1)
		(layer "In4.Cu")
		(net 649)
	)
	(segment
		(start 182.5005 164.4995)
		(end 182.500333 164.499667)
		(width 0.1)
		(layer "In4.Cu")
		(net 649)
	)
	(segment
		(start 156.665562 156.498471)
		(end 156.525214 156.638818)
		(width 0.1)
		(layer "In4.Cu")
		(net 649)
	)
	(segment
		(start 156.665562 156.49847)
		(end 156.665562 156.498471)
		(width 0.1)
		(layer "In4.Cu")
		(net 649)
	)
	(segment
		(start 181.875 165.505147)
		(end 181.875 165.959237)
		(width 0.1)
		(layer "In4.Cu")
		(net 649)
	)
	(segment
		(start 172.69234 167.115563)
		(end 172.621778 167.045)
		(width 0.1)
		(layer "In4.Cu")
		(net 649)
	)
	(segment
		(start 157.338388 157.451991)
		(end 157.338388 157.451992)
		(width 0.1)
		(layer "In4.Cu")
		(net 649)
	)
	(segment
		(start 156.205957 155.225664)
		(end 156.205958 155.225665)
		(width 0.1)
		(layer "In4.Cu")
		(net 649)
	)
	(segment
		(start 156.065595 156.638819)
		(end 156.065594 156.638818)
		(width 0.1)
		(layer "In4.Cu")
		(net 649)
	)
	(segment
		(start 153.52001 154.093234)
		(end 153.520012 154.093235)
		(width 0.1)
		(layer "In4.Cu")
		(net 649)
	)
	(segment
		(start 126.718838 149.04206)
		(end 125.830344 148.153566)
		(width 0.1)
		(layer "In4.Cu")
		(net 649)
	)
	(segment
		(start 179.200342 168.015)
		(end 174.863757 168.015)
		(width 0.1)
		(layer "In4.Cu")
		(net 649)
	)
	(segment
		(start 157.338388 157.451992)
		(end 157.478735 157.311644)
		(width 0.1)
		(layer "In4.Cu")
		(net 649)
	)
	(segment
		(start 157.478736 156.498471)
		(end 157.478735 156.498471)
		(width 0.1)
		(layer "In4.Cu")
		(net 649)
	)
	(segment
		(start 154.792804 154.906408)
		(end 154.933108 154.766103)
		(width 0.1)
		(layer "In4.Cu")
		(net 649)
	)
	(segment
		(start 181.529237 166.793984)
		(end 181.091611 167.231611)
		(width 0.1)
		(layer "In4.Cu")
		(net 649)
	)
	(segment
		(start 154.119935 153.952929)
		(end 154.119935 153.95293)
		(width 0.1)
		(layer "In4.Cu")
		(net 649)
	)
	(segment
		(start 152.387583 151.407288)
		(end 152.387582 151.407288)
		(width 0.1)
		(layer "In4.Cu")
		(net 649)
	)
	(segment
		(start 152.247219 152.820443)
		(end 152.247218 152.820442)
		(width 0.1)
		(layer "In4.Cu")
		(net 649)
	)
	(segment
		(start 150.974426 151.54765)
		(end 150.39557 150.968792)
		(width 0.1)
		(layer "In4.Cu")
		(net 649)
	)
	(segment
		(start 151.574409 151.407287)
		(end 151.574409 151.407288)
		(width 0.1)
		(layer "In4.Cu")
		(net 649)
	)
	(segment
		(start 151.574409 151.407288)
		(end 151.434046 151.54765)
		(width 0.1)
		(layer "In4.Cu")
		(net 649)
	)
	(segment
		(start 153.66036 152.680095)
		(end 153.660359 152.680095)
		(width 0.1)
		(layer "In4.Cu")
		(net 649)
	)
	(segment
		(start 182.171346 164.947785)
		(end 182.059566 165.059566)
		(width 0.1)
		(layer "In4.Cu")
		(net 649)
	)
	(segment
		(start 153.520012 153.633615)
		(end 153.520012 153.633616)
		(width 0.1)
		(layer "In4.Cu")
		(net 649)
	)
	(segment
		(start 170.27999 166.075)
		(end 167.660893 166.075)
		(width 0.1)
		(layer "In4.Cu")
		(net 649)
	)
	(segment
		(start 152.847186 152.680095)
		(end 152.706838 152.820442)
		(width 0.1)
		(layer "In4.Cu")
		(net 649)
	)
	(segment
		(start 163.975053 164.548275)
		(end 157.338389 157.911611)
		(width 0.1)
		(layer "In4.Cu")
		(net 649)
	)
	(segment
		(start 155.392785 155.225665)
		(end 155.252422 155.366027)
		(width 0.1)
		(layer "In4.Cu")
		(net 649)
	)
	(segment
		(start 154.119935 153.95293)
		(end 153.97963 154.093234)
		(width 0.1)
		(layer "In4.Cu")
		(net 649)
	)
	(segment
		(start 157.338389 157.911611)
		(end 157.338388 157.911611)
		(width 0.1)
		(layer "In4.Cu")
		(net 649)
	)
	(segment
		(start 154.933109 153.95293)
		(end 154.933108 153.95293)
		(width 0.1)
		(layer "In4.Cu")
		(net 649)
	)
	(segment
		(start 156.065594 156.638818)
		(end 156.065596 156.638819)
		(width 0.1)
		(layer "In4.Cu")
		(net 649)
	)
	(segment
		(start 154.792803 155.366027)
		(end 154.792804 155.366027)
		(width 0.1)
		(layer "In4.Cu")
		(net 649)
	)
	(segment
		(start 153.520011 154.093235)
		(end 153.52001 154.093234)
		(width 0.1)
		(layer "In4.Cu")
		(net 649)
	)
	(segment
		(start 125.016429 147.816429)
		(end 125.01 147.81)
		(width 0.1)
		(layer "In4.Cu")
		(net 649)
	)
	(segment
		(start 182.500333 164.499667)
		(end 182.500333 164.805906)
		(width 0.1)
		(layer "In4.Cu")
		(net 649)
	)
	(segment
		(start 152.24722 152.360823)
		(end 152.24722 152.360824)
		(width 0.1)
		(layer "In4.Cu")
		(net 649)
	)
	(segment
		(start 152.847186 152.680094)
		(end 152.847186 152.680095)
		(width 0.1)
		(layer "In4.Cu")
		(net 649)
	)
	(segment
		(start 152.24722 152.360824)
		(end 152.387582 152.220461)
		(width 0.1)
		(layer "In4.Cu")
		(net 649)
	)
	(segment
		(start 152.247218 152.820442)
		(end 152.24722 152.820443)
		(width 0.1)
		(layer "In4.Cu")
		(net 649)
	)
	(segment
		(start 146.547814 149.375)
		(end 127.522627 149.375)
		(width 0.1)
		(layer "In4.Cu")
		(net 649)
	)
	(segment
		(start 150.974427 151.547651)
		(end 150.974426 151.54765)
		(width 0.1)
		(layer "In4.Cu")
		(net 649)
	)
	(segment
		(start 182.414291 164.875)
		(end 182.347066 164.875)
		(width 0.1)
		(layer "In4.Cu")
		(net 649)
	)
	(segment
		(start 154.792803 155.366026)
		(end 154.792803 155.366027)
		(width 0.1)
		(layer "In4.Cu")
		(net 649)
	)
	(segment
		(start 154.792804 154.906407)
		(end 154.792804 154.906408)
		(width 0.1)
		(layer "In4.Cu")
		(net 649)
	)
	(segment
		(start 156.065596 156.179199)
		(end 156.065596 156.1792)
		(width 0.1)
		(layer "In4.Cu")
		(net 649)
	)
	(arc
		(start 174.863757 168.015)
		(mid 173.688593 167.781244)
		(end 172.69234 167.115563)
		(width 0.1)
		(layer "In4.Cu")
		(net 649)
	)
	(arc
		(start 167.660893 166.075)
		(mid 165.666131 165.678217)
		(end 163.975053 164.548275)
		(width 0.1)
		(layer "In4.Cu")
		(net 649)
	)
	(arc
		(start 156.065596 156.638819)
		(mid 155.970406 156.409009)
		(end 156.065596 156.179199)
		(width 0.1)
		(layer "In4.Cu")
		(net 649)
	)
	(arc
		(start 127.522627 149.375)
		(mid 127.08762 149.288472)
		(end 126.718838 149.04206)
		(width 0.1)
		(layer "In4.Cu")
		(net 649)
	)
	(arc
		(start 182.47525 164.84975)
		(mid 182.447281 164.868437)
		(end 182.414291 164.875)
		(width 0.1)
		(layer "In4.Cu")
		(net 649)
	)
	(arc
		(start 152.387582 152.220461)
		(mid 152.555996 151.813875)
		(end 152.387583 151.407288)
		(width 0.1)
		(layer "In4.Cu")
		(net 649)
	)
	(arc
		(start 182.500333 164.805906)
		(mid 182.49032 164.82943)
		(end 182.47525 164.84975)
		(width 0.1)
		(layer "In4.Cu")
		(net 649)
	)
	(arc
		(start 153.520012 154.093235)
		(mid 153.424822 153.863425)
		(end 153.520012 153.633615)
		(width 0.1)
		(layer "In4.Cu")
		(net 649)
	)
	(arc
		(start 152.24722 152.820443)
		(mid 152.15203 152.590633)
		(end 152.24722 152.360823)
		(width 0.1)
		(layer "In4.Cu")
		(net 649)
	)
	(arc
		(start 181.875 165.959237)
		(mid 181.785139 166.410999)
		(end 181.529237 166.793984)
		(width 0.1)
		(layer "In4.Cu")
		(net 649)
	)
	(arc
		(start 152.387582 151.407288)
		(mid 151.980996 151.238874)
		(end 151.574409 151.407287)
		(width 0.1)
		(layer "In4.Cu")
		(net 649)
	)
	(arc
		(start 157.478735 157.311644)
		(mid 157.647149 156.905058)
		(end 157.478736 156.498471)
		(width 0.1)
		(layer "In4.Cu")
		(net 649)
	)
	(arc
		(start 125.423389 147.985)
		(mid 125.203147 147.94119)
		(end 125.016429 147.816429)
		(width 0.1)
		(layer "In4.Cu")
		(net 649)
	)
	(arc
		(start 172.621778 167.045)
		(mid 171.547356 166.327094)
		(end 170.27999 166.075)
		(width 0.1)
		(layer "In4.Cu")
		(net 649)
	)
	(arc
		(start 153.660359 153.493268)
		(mid 153.828773 153.086682)
		(end 153.66036 152.680095)
		(width 0.1)
		(layer "In4.Cu")
		(net 649)
	)
	(arc
		(start 125.830344 148.153566)
		(mid 125.643631 148.028808)
		(end 125.423389 147.985)
		(width 0.1)
		(layer "In4.Cu")
		(net 649)
	)
	(arc
		(start 153.97963 154.093234)
		(mid 153.749821 154.188425)
		(end 153.520011 154.093235)
		(width 0.1)
		(layer "In4.Cu")
		(net 649)
	)
	(arc
		(start 156.205958 156.038837)
		(mid 156.374371 155.63225)
		(end 156.205957 155.225664)
		(width 0.1)
		(layer "In4.Cu")
		(net 649)
	)
	(arc
		(start 154.792804 155.366027)
		(mid 154.697614 155.136217)
		(end 154.792804 154.906407)
		(width 0.1)
		(layer "In4.Cu")
		(net 649)
	)
	(arc
		(start 157.338388 157.911611)
		(mid 157.243198 157.681801)
		(end 157.338388 157.451991)
		(width 0.1)
		(layer "In4.Cu")
		(net 649)
	)
	(arc
		(start 157.478735 156.498471)
		(mid 157.072149 156.330057)
		(end 156.665562 156.49847)
		(width 0.1)
		(layer "In4.Cu")
		(net 649)
	)
	(arc
		(start 154.933108 154.766103)
		(mid 155.101522 154.359517)
		(end 154.933109 153.95293)
		(width 0.1)
		(layer "In4.Cu")
		(net 649)
	)
	(arc
		(start 151.434046 151.54765)
		(mid 151.204237 151.642841)
		(end 150.974427 151.547651)
		(width 0.1)
		(layer "In4.Cu")
		(net 649)
	)
	(arc
		(start 153.660359 152.680095)
		(mid 153.253773 152.511681)
		(end 152.847186 152.680094)
		(width 0.1)
		(layer "In4.Cu")
		(net 649)
	)
	(arc
		(start 156.205958 155.225665)
		(mid 155.799372 155.057251)
		(end 155.392785 155.225664)
		(width 0.1)
		(layer "In4.Cu")
		(net 649)
	)
	(arc
		(start 152.706838 152.820442)
		(mid 152.477029 152.915633)
		(end 152.247219 152.820443)
		(width 0.1)
		(layer "In4.Cu")
		(net 649)
	)
	(arc
		(start 182.059566 165.059566)
		(mid 181.922967 165.264)
		(end 181.875 165.505147)
		(width 0.1)
		(layer "In4.Cu")
		(net 649)
	)
	(arc
		(start 182.347066 164.875)
		(mid 182.251967 164.893916)
		(end 182.171346 164.947785)
		(width 0.1)
		(layer "In4.Cu")
		(net 649)
	)
	(arc
		(start 156.525214 156.638818)
		(mid 156.295405 156.734009)
		(end 156.065595 156.638819)
		(width 0.1)
		(layer "In4.Cu")
		(net 649)
	)
	(arc
		(start 155.252422 155.366027)
		(mid 155.022612 155.461217)
		(end 154.792803 155.366026)
		(width 0.1)
		(layer "In4.Cu")
		(net 649)
	)
	(arc
		(start 181.091611 167.231611)
		(mid 180.223889 167.811403)
		(end 179.200342 168.015)
		(width 0.1)
		(layer "In4.Cu")
		(net 649)
	)
	(arc
		(start 154.933108 153.95293)
		(mid 154.526522 153.784516)
		(end 154.119935 153.952929)
		(width 0.1)
		(layer "In4.Cu")
		(net 649)
	)
	(arc
		(start 150.39557 150.968792)
		(mid 148.630204 149.789213)
		(end 146.547814 149.375)
		(width 0.1)
		(layer "In4.Cu")
		(net 649)
	)
	(segment
		(start 184.5005 165.4995)
		(end 185 165)
		(width 0.256)
		(layer "F.Cu")
		(net 650)
	)
	(via
		(at 125.01 150.41)
		(size 0.45)
		(drill 0.1)
		(layers "F.Cu" "B.Cu")
		(remove_unused_layers yes)
		(keep_end_layers yes)
		(zone_layer_connections)
		(net 650)
	)
	(via
		(at 184.5005 165.4995)
		(size 0.45)
		(drill 0.1)
		(layers "F.Cu" "B.Cu")
		(remove_unused_layers yes)
		(keep_end_layers yes)
		(zone_layer_connections)
		(net 650)
	)
	(segment
		(start 123.602499 150.4375)
		(end 123.43 150.61)
		(width 0.16)
		(layer "B.Cu")
		(net 650)
	)
	(segment
		(start 124.01895 150.265001)
		(end 124.65995 150.265001)
		(width 0.16)
		(layer "B.Cu")
		(net 650)
	)
	(arc
		(start 125.01 150.41)
		(mid 124.849392 150.302683)
		(end 124.65995 150.265001)
		(width 0.16)
		(layer "B.Cu")
		(net 650)
	)
	(arc
		(start 124.01895 150.265001)
		(mid 123.793568 150.309832)
		(end 123.602499 150.4375)
		(width 0.16)
		(layer "B.Cu")
		(net 650)
	)
	(segment
		(start 156.81573 159.574998)
		(end 156.865339 159.624607)
		(width 0.1)
		(layer "In4.Cu")
		(net 650)
	)
	(segment
		(start 158.438652 161.643287)
		(end 158.52704 161.554896)
		(width 0.1)
		(layer "In4.Cu")
		(net 650)
	)
	(segment
		(start 157.766845 161.593622)
		(end 157.766843 161.593621)
		(width 0.1)
		(layer "In4.Cu")
		(net 650)
	)
	(segment
		(start 156.458754 159.663389)
		(end 156.547142 159.574998)
		(width 0.1)
		(layer "In4.Cu")
		(net 650)
	)
	(segment
		(start 159.428629 162.633236)
		(end 159.428629 162.633235)
		(width 0.1)
		(layer "In4.Cu")
		(net 650)
	)
	(segment
		(start 184.236344 165.236344)
		(end 184.311515 165.161172)
		(width 0.1)
		(layer "In4.Cu")
		(net 650)
	)
	(segment
		(start 156.815731 159.574999)
		(end 156.81573 159.574998)
		(width 0.1)
		(layer "In4.Cu")
		(net 650)
	)
	(segment
		(start 125.432486 150.235)
		(end 126.897327 150.235)
		(width 0.1)
		(layer "In4.Cu")
		(net 650)
	)
	(segment
		(start 184.5005 165.211208)
		(end 184.5005 165.4995)
		(width 0.1)
		(layer "In4.Cu")
		(net 650)
	)
	(segment
		(start 160.775411 163.534796)
		(end 160.825078 163.584463)
		(width 0.1)
		(layer "In4.Cu")
		(net 650)
	)
	(segment
		(start 160.418492 163.623185)
		(end 160.506879 163.534795)
		(width 0.1)
		(layer "In4.Cu")
		(net 650)
	)
	(segment
		(start 127.723993 150.625)
		(end 144.662489 150.625)
		(width 0.1)
		(layer "In4.Cu")
		(net 650)
	)
	(segment
		(start 157.448647 160.653337)
		(end 157.537037 160.564948)
		(width 0.1)
		(layer "In4.Cu")
		(net 650)
	)
	(segment
		(start 182.798389 168.378389)
		(end 183.522513 167.654264)
		(width 0.1)
		(layer "In4.Cu")
		(net 650)
	)
	(segment
		(start 161.776306 165.603082)
		(end 162.454429 166.281207)
		(width 0.1)
		(layer "In4.Cu")
		(net 650)
	)
	(segment
		(start 161.815128 164.84294)
		(end 161.815129 164.842942)
		(width 0.1)
		(layer "In4.Cu")
		(net 650)
	)
	(segment
		(start 148.308413 152.135191)
		(end 155.836611 159.663389)
		(width 0.1)
		(layer "In4.Cu")
		(net 650)
	)
	(segment
		(start 157.805569 160.564947)
		(end 157.855233 160.614611)
		(width 0.1)
		(layer "In4.Cu")
		(net 650)
	)
	(segment
		(start 173.422227 169.705)
		(end 178.5 169.705)
		(width 0.1)
		(layer "In4.Cu")
		(net 650)
	)
	(segment
		(start 161.408543 164.613134)
		(end 161.496931 164.524743)
		(width 0.1)
		(layer "In4.Cu")
		(net 650)
	)
	(segment
		(start 156.865338 159.893196)
		(end 156.86534 159.893197)
		(width 0.1)
		(layer "In4.Cu")
		(net 650)
	)
	(segment
		(start 160.77541 163.534796)
		(end 160.775411 163.534796)
		(width 0.1)
		(layer "In4.Cu")
		(net 650)
	)
	(segment
		(start 156.776949 160.603727)
		(end 156.826559 160.653336)
		(width 0.1)
		(layer "In4.Cu")
		(net 650)
	)
	(segment
		(start 157.80557 160.564949)
		(end 157.805569 160.564947)
		(width 0.1)
		(layer "In4.Cu")
		(net 650)
	)
	(segment
		(start 161.815129 164.842942)
		(end 161.726738 164.93133)
		(width 0.1)
		(layer "In4.Cu")
		(net 650)
	)
	(segment
		(start 159.428629 162.633235)
		(end 159.517018 162.544847)
		(width 0.1)
		(layer "In4.Cu")
		(net 650)
	)
	(segment
		(start 171.133256 168.710033)
		(end 171.213222 168.79)
		(width 0.1)
		(layer "In4.Cu")
		(net 650)
	)
	(segment
		(start 155.836611 159.663389)
		(end 155.83661 159.663387)
		(width 0.1)
		(layer "In4.Cu")
		(net 650)
	)
	(segment
		(start 159.835214 162.863044)
		(end 159.746826 162.951433)
		(width 0.1)
		(layer "In4.Cu")
		(net 650)
	)
	(segment
		(start 160.736689 164.563466)
		(end 160.786357 164.613133)
		(width 0.1)
		(layer "In4.Cu")
		(net 650)
	)
	(segment
		(start 161.765564 164.524744)
		(end 161.765563 164.524743)
		(width 0.1)
		(layer "In4.Cu")
		(net 650)
	)
	(segment
		(start 157.448649 160.653338)
		(end 157.448647 160.653337)
		(width 0.1)
		(layer "In4.Cu")
		(net 650)
	)
	(segment
		(start 156.86534 159.893197)
		(end 156.776949 159.981585)
		(width 0.1)
		(layer "In4.Cu")
		(net 650)
	)
	(segment
		(start 159.785634 162.544846)
		(end 159.835214 162.594426)
		(width 0.1)
		(layer "In4.Cu")
		(net 650)
	)
	(segment
		(start 158.845238 161.873095)
		(end 158.756847 161.961483)
		(width 0.1)
		(layer "In4.Cu")
		(net 650)
	)
	(segment
		(start 184.398844 165.125)
		(end 184.414291 165.125)
		(width 0.1)
		(layer "In4.Cu")
		(net 650)
	)
	(segment
		(start 158.795628 161.554896)
		(end 158.845237 161.604505)
		(width 0.1)
		(layer "In4.Cu")
		(net 650)
	)
	(segment
		(start 160.825077 163.852994)
		(end 160.825077 163.852993)
		(width 0.1)
		(layer "In4.Cu")
		(net 650)
	)
	(segment
		(start 157.855233 160.883145)
		(end 157.766844 160.971535)
		(width 0.1)
		(layer "In4.Cu")
		(net 650)
	)
	(segment
		(start 178.5 169.705)
		(end 179.595666 169.705)
		(width 0.1)
		(layer "In4.Cu")
		(net 650)
	)
	(segment
		(start 157.766843 161.593621)
		(end 157.816508 161.643285)
		(width 0.1)
		(layer "In4.Cu")
		(net 650)
	)
	(segment
		(start 159.796408 163.623184)
		(end 159.796406 163.623183)
		(width 0.1)
		(layer "In4.Cu")
		(net 650)
	)
	(segment
		(start 184.125 166.199733)
		(end 184.125 165.505152)
		(width 0.1)
		(layer "In4.Cu")
		(net 650)
	)
	(segment
		(start 161.726738 165.553516)
		(end 161.776306 165.603082)
		(width 0.1)
		(layer "In4.Cu")
		(net 650)
	)
	(segment
		(start 160.786357 164.613133)
		(end 160.786355 164.613132)
		(width 0.1)
		(layer "In4.Cu")
		(net 650)
	)
	(segment
		(start 158.756847 162.583625)
		(end 158.806457 162.633234)
		(width 0.1)
		(layer "In4.Cu")
		(net 650)
	)
	(segment
		(start 160.825077 163.852993)
		(end 160.736689 163.941382)
		(width 0.1)
		(layer "In4.Cu")
		(net 650)
	)
	(segment
		(start 159.785635 162.544848)
		(end 159.785634 162.544846)
		(width 0.1)
		(layer "In4.Cu")
		(net 650)
	)
	(segment
		(start 127.171947 150.348739)
		(end 127.253222 150.43)
		(width 0.1)
		(layer "In4.Cu")
		(net 650)
	)
	(segment
		(start 166.302185 167.875)
		(end 169.117322 167.875)
		(width 0.1)
		(layer "In4.Cu")
		(net 650)
	)
	(segment
		(start 156.77695 160.603728)
		(end 156.776949 160.603727)
		(width 0.1)
		(layer "In4.Cu")
		(net 650)
	)
	(segment
		(start 161.765563 164.524743)
		(end 161.815128 164.574308)
		(width 0.1)
		(layer "In4.Cu")
		(net 650)
	)
	(segment
		(start 159.746826 163.573603)
		(end 159.796408 163.623184)
		(width 0.1)
		(layer "In4.Cu")
		(net 650)
	)
	(segment
		(start 159.835215 162.863043)
		(end 159.835214 162.863044)
		(width 0.1)
		(layer "In4.Cu")
		(net 650)
	)
	(segment
		(start 158.845236 161.873094)
		(end 158.845238 161.873095)
		(width 0.1)
		(layer "In4.Cu")
		(net 650)
	)
	(segment
		(start 158.756848 162.583626)
		(end 158.756847 162.583625)
		(width 0.1)
		(layer "In4.Cu")
		(net 650)
	)
	(segment
		(start 158.795629 161.554897)
		(end 158.795628 161.554896)
		(width 0.1)
		(layer "In4.Cu")
		(net 650)
	)
	(arc
		(start 157.855233 160.614611)
		(mid 157.910848 160.748878)
		(end 157.855233 160.883145)
		(width 0.1)
		(layer "In4.Cu")
		(net 650)
	)
	(arc
		(start 161.496931 164.524743)
		(mid 161.631248 164.469108)
		(end 161.765564 164.524744)
		(width 0.1)
		(layer "In4.Cu")
		(net 650)
	)
	(arc
		(start 158.756847 161.961483)
		(mid 158.627997 162.272555)
		(end 158.756848 162.583626)
		(width 0.1)
		(layer "In4.Cu")
		(net 650)
	)
	(arc
		(start 156.547142 159.574998)
		(mid 156.681438 159.519373)
		(end 156.815731 159.574999)
		(width 0.1)
		(layer "In4.Cu")
		(net 650)
	)
	(arc
		(start 184.414291 165.125)
		(mid 184.447281 165.131562)
		(end 184.47525 165.15025)
		(width 0.1)
		(layer "In4.Cu")
		(net 650)
	)
	(arc
		(start 160.786355 164.613132)
		(mid 161.09745 164.741993)
		(end 161.408543 164.613134)
		(width 0.1)
		(layer "In4.Cu")
		(net 650)
	)
	(arc
		(start 161.815128 164.574308)
		(mid 161.870764 164.708624)
		(end 161.815128 164.84294)
		(width 0.1)
		(layer "In4.Cu")
		(net 650)
	)
	(arc
		(start 156.865339 159.624607)
		(mid 156.920966 159.758903)
		(end 156.865338 159.893196)
		(width 0.1)
		(layer "In4.Cu")
		(net 650)
	)
	(arc
		(start 160.825078 163.584463)
		(mid 160.880692 163.718729)
		(end 160.825077 163.852994)
		(width 0.1)
		(layer "In4.Cu")
		(net 650)
	)
	(arc
		(start 144.662489 150.625)
		(mid 146.635649 151.017486)
		(end 148.308413 152.135191)
		(width 0.1)
		(layer "In4.Cu")
		(net 650)
	)
	(arc
		(start 169.117322 167.875)
		(mid 170.208339 168.092018)
		(end 171.133256 168.710033)
		(width 0.1)
		(layer "In4.Cu")
		(net 650)
	)
	(arc
		(start 160.506879 163.534795)
		(mid 160.641145 163.479181)
		(end 160.77541 163.534796)
		(width 0.1)
		(layer "In4.Cu")
		(net 650)
	)
	(arc
		(start 156.776949 159.981585)
		(mid 156.648099 160.292657)
		(end 156.77695 160.603728)
		(width 0.1)
		(layer "In4.Cu")
		(net 650)
	)
	(arc
		(start 184.125 165.505152)
		(mid 184.153937 165.359674)
		(end 184.236344 165.236344)
		(width 0.1)
		(layer "In4.Cu")
		(net 650)
	)
	(arc
		(start 183.522513 167.654264)
		(mid 183.968418 166.986919)
		(end 184.125 166.199733)
		(width 0.1)
		(layer "In4.Cu")
		(net 650)
	)
	(arc
		(start 171.213222 168.79)
		(mid 172.226722 169.467199)
		(end 173.422227 169.705)
		(width 0.1)
		(layer "In4.Cu")
		(net 650)
	)
	(arc
		(start 157.816508 161.643285)
		(mid 158.12758 161.772136)
		(end 158.438652 161.643287)
		(width 0.1)
		(layer "In4.Cu")
		(net 650)
	)
	(arc
		(start 179.595666 169.705)
		(mid 181.328967 169.360225)
		(end 182.798389 168.378389)
		(width 0.1)
		(layer "In4.Cu")
		(net 650)
	)
	(arc
		(start 162.454429 166.281207)
		(mid 164.219794 167.460786)
		(end 166.302185 167.875)
		(width 0.1)
		(layer "In4.Cu")
		(net 650)
	)
	(arc
		(start 158.845237 161.604505)
		(mid 158.900864 161.738801)
		(end 158.845236 161.873094)
		(width 0.1)
		(layer "In4.Cu")
		(net 650)
	)
	(arc
		(start 184.47525 165.15025)
		(mid 184.493937 165.178217)
		(end 184.5005 165.211208)
		(width 0.1)
		(layer "In4.Cu")
		(net 650)
	)
	(arc
		(start 157.537037 160.564948)
		(mid 157.671304 160.509333)
		(end 157.80557 160.564949)
		(width 0.1)
		(layer "In4.Cu")
		(net 650)
	)
	(arc
		(start 159.796406 163.623183)
		(mid 160.10745 163.752023)
		(end 160.418492 163.623185)
		(width 0.1)
		(layer "In4.Cu")
		(net 650)
	)
	(arc
		(start 126.897327 150.235)
		(mid 127.045948 150.264559)
		(end 127.171947 150.348739)
		(width 0.1)
		(layer "In4.Cu")
		(net 650)
	)
	(arc
		(start 159.835214 162.594426)
		(mid 159.890848 162.728735)
		(end 159.835215 162.863043)
		(width 0.1)
		(layer "In4.Cu")
		(net 650)
	)
	(arc
		(start 184.311515 165.161172)
		(mid 184.351581 165.1344)
		(end 184.398844 165.125)
		(width 0.1)
		(layer "In4.Cu")
		(net 650)
	)
	(arc
		(start 156.826559 160.653336)
		(mid 157.137604 160.782176)
		(end 157.448649 160.653338)
		(width 0.1)
		(layer "In4.Cu")
		(net 650)
	)
	(arc
		(start 157.766844 160.971535)
		(mid 157.638006 161.282579)
		(end 157.766845 161.593622)
		(width 0.1)
		(layer "In4.Cu")
		(net 650)
	)
	(arc
		(start 155.83661 159.663387)
		(mid 156.147682 159.792238)
		(end 156.458754 159.663389)
		(width 0.1)
		(layer "In4.Cu")
		(net 650)
	)
	(arc
		(start 159.746826 162.951433)
		(mid 159.617969 163.262517)
		(end 159.746826 163.573603)
		(width 0.1)
		(layer "In4.Cu")
		(net 650)
	)
	(arc
		(start 160.736689 163.941382)
		(mid 160.607851 164.252424)
		(end 160.736689 164.563466)
		(width 0.1)
		(layer "In4.Cu")
		(net 650)
	)
	(arc
		(start 161.726738 164.93133)
		(mid 161.597879 165.242423)
		(end 161.726738 165.553516)
		(width 0.1)
		(layer "In4.Cu")
		(net 650)
	)
	(arc
		(start 158.806457 162.633234)
		(mid 159.117543 162.762091)
		(end 159.428629 162.633236)
		(width 0.1)
		(layer "In4.Cu")
		(net 650)
	)
	(arc
		(start 159.517018 162.544847)
		(mid 159.651326 162.489214)
		(end 159.785635 162.544848)
		(width 0.1)
		(layer "In4.Cu")
		(net 650)
	)
	(arc
		(start 127.253222 150.43)
		(mid 127.469213 150.574321)
		(end 127.723993 150.625)
		(width 0.1)
		(layer "In4.Cu")
		(net 650)
	)
	(arc
		(start 125.01 150.41)
		(mid 125.203839 150.280481)
		(end 125.432486 150.235)
		(width 0.1)
		(layer "In4.Cu")
		(net 650)
	)
	(arc
		(start 158.52704 161.554896)
		(mid 158.661336 161.499271)
		(end 158.795629 161.554897)
		(width 0.1)
		(layer "In4.Cu")
		(net 650)
	)
	(segment
		(start 184.5005 164.499499)
		(end 185 164)
		(width 0.256)
		(layer "F.Cu")
		(net 651)
	)
	(via
		(at 125.01 149.81)
		(size 0.45)
		(drill 0.1)
		(layers "F.Cu" "B.Cu")
		(remove_unused_layers yes)
		(keep_end_layers yes)
		(zone_layer_connections)
		(net 651)
	)
	(via
		(at 184.5005 164.499499)
		(size 0.45)
		(drill 0.1)
		(layers "F.Cu" "B.Cu")
		(remove_unused_layers yes)
		(keep_end_layers yes)
		(zone_layer_connections)
		(net 651)
	)
	(segment
		(start 123.602499 149.782499)
		(end 123.43 149.61)
		(width 0.16)
		(layer "B.Cu")
		(net 651)
	)
	(segment
		(start 124.659953 149.954999)
		(end 124.01895 149.954999)
		(width 0.16)
		(layer "B.Cu")
		(net 651)
	)
	(arc
		(start 123.602499 149.782499)
		(mid 123.793568 149.910167)
		(end 124.01895 149.954999)
		(width 0.16)
		(layer "B.Cu")
		(net 651)
	)
	(arc
		(start 125.01 149.81)
		(mid 124.849392 149.917318)
		(end 124.659953 149.954999)
		(width 0.16)
		(layer "B.Cu")
		(net 651)
	)
	(segment
		(start 184.347066 164.875)
		(end 184.414291 164.875)
		(width 0.1)
		(layer "In4.Cu")
		(net 651)
	)
	(segment
		(start 158.933625 162.406847)
		(end 158.983234 162.456457)
		(width 0.1)
		(layer "In4.Cu")
		(net 651)
	)
	(segment
		(start 184.059566 165.059566)
		(end 184.171346 164.947785)
		(width 0.1)
		(layer "In4.Cu")
		(net 651)
	)
	(segment
		(start 160.241715 163.446407)
		(end 160.330104 163.358019)
		(width 0.1)
		(layer "In4.Cu")
		(net 651)
	)
	(segment
		(start 158.261875 161.466509)
		(end 158.350265 161.37812)
		(width 0.1)
		(layer "In4.Cu")
		(net 651)
	)
	(segment
		(start 160.011992 163.039821)
		(end 160.01199 163.03982)
		(width 0.1)
		(layer "In4.Cu")
		(net 651)
	)
	(segment
		(start 160.241715 163.446408)
		(end 160.241715 163.446407)
		(width 0.1)
		(layer "In4.Cu")
		(net 651)
	)
	(segment
		(start 160.913466 164.386689)
		(end 160.963132 164.436355)
		(width 0.1)
		(layer "In4.Cu")
		(net 651)
	)
	(segment
		(start 171.316778 168.54)
		(end 171.385283 168.608506)
		(width 0.1)
		(layer "In4.Cu")
		(net 651)
	)
	(segment
		(start 161.903517 165.376739)
		(end 161.903516 165.376738)
		(width 0.1)
		(layer "In4.Cu")
		(net 651)
	)
	(segment
		(start 156.953727 160.426949)
		(end 157.003336 160.476559)
		(width 0.1)
		(layer "In4.Cu")
		(net 651)
	)
	(segment
		(start 127.725873 150.375)
		(end 144.647814 150.375)
		(width 0.1)
		(layer "In4.Cu")
		(net 651)
	)
	(segment
		(start 158.032011 161.059922)
		(end 158.032011 161.059921)
		(width 0.1)
		(layer "In4.Cu")
		(net 651)
	)
	(segment
		(start 161.001855 164.02977)
		(end 160.913465 164.118157)
		(width 0.1)
		(layer "In4.Cu")
		(net 651)
	)
	(segment
		(start 125.432486 149.985)
		(end 126.886006 149.985)
		(width 0.1)
		(layer "In4.Cu")
		(net 651)
	)
	(segment
		(start 157.943621 161.416843)
		(end 157.993285 161.466508)
		(width 0.1)
		(layer "In4.Cu")
		(net 651)
	)
	(segment
		(start 127.356778 150.18)
		(end 127.42872 150.25193)
		(width 0.1)
		(layer "In4.Cu")
		(net 651)
	)
	(segment
		(start 158.972408 161.378121)
		(end 158.972407 161.37812)
		(width 0.1)
		(layer "In4.Cu")
		(net 651)
	)
	(segment
		(start 158.261875 161.46651)
		(end 158.261875 161.466509)
		(width 0.1)
		(layer "In4.Cu")
		(net 651)
	)
	(segment
		(start 160.952188 163.358019)
		(end 161.001855 163.407686)
		(width 0.1)
		(layer "In4.Cu")
		(net 651)
	)
	(segment
		(start 161.231766 164.436356)
		(end 161.320156 164.347967)
		(width 0.1)
		(layer "In4.Cu")
		(net 651)
	)
	(segment
		(start 157.943623 161.416844)
		(end 157.943621 161.416843)
		(width 0.1)
		(layer "In4.Cu")
		(net 651)
	)
	(segment
		(start 183.875 166.20214)
		(end 183.875 165.505147)
		(width 0.1)
		(layer "In4.Cu")
		(net 651)
	)
	(segment
		(start 158.933626 162.406848)
		(end 158.933625 162.406847)
		(width 0.1)
		(layer "In4.Cu")
		(net 651)
	)
	(segment
		(start 159.022016 162.049871)
		(end 158.933625 162.138259)
		(width 0.1)
		(layer "In4.Cu")
		(net 651)
	)
	(segment
		(start 159.923603 163.396826)
		(end 159.923601 163.396825)
		(width 0.1)
		(layer "In4.Cu")
		(net 651)
	)
	(segment
		(start 184.5005 164.788791)
		(end 184.5005 164.499499)
		(width 0.1)
		(layer "In4.Cu")
		(net 651)
	)
	(segment
		(start 157.982348 160.388171)
		(end 158.032012 160.437835)
		(width 0.1)
		(layer "In4.Cu")
		(net 651)
	)
	(segment
		(start 160.01199 163.03982)
		(end 159.923602 163.128209)
		(width 0.1)
		(layer "In4.Cu")
		(net 651)
	)
	(segment
		(start 173.428886 169.455)
		(end 178.5 169.455)
		(width 0.1)
		(layer "In4.Cu")
		(net 651)
	)
	(segment
		(start 182.62161 168.20161)
		(end 183.34744 167.475781)
		(width 0.1)
		(layer "In4.Cu")
		(net 651)
	)
	(segment
		(start 158.032011 161.059921)
		(end 157.943622 161.148311)
		(width 0.1)
		(layer "In4.Cu")
		(net 651)
	)
	(segment
		(start 148.49557 151.968792)
		(end 156.013389 159.486611)
		(width 0.1)
		(layer "In4.Cu")
		(net 651)
	)
	(segment
		(start 156.013389 159.486611)
		(end 156.013387 159.48661)
		(width 0.1)
		(layer "In4.Cu")
		(net 651)
	)
	(segment
		(start 158.972407 161.37812)
		(end 159.022016 161.427729)
		(width 0.1)
		(layer "In4.Cu")
		(net 651)
	)
	(segment
		(start 160.913466 164.386688)
		(end 160.913466 164.386689)
		(width 0.1)
		(layer "In4.Cu")
		(net 651)
	)
	(segment
		(start 161.991907 165.019718)
		(end 161.903516 165.108106)
		(width 0.1)
		(layer "In4.Cu")
		(net 651)
	)
	(segment
		(start 157.982347 160.388171)
		(end 157.982348 160.388171)
		(width 0.1)
		(layer "In4.Cu")
		(net 651)
	)
	(segment
		(start 156.99251 159.398223)
		(end 156.992509 159.398222)
		(width 0.1)
		(layer "In4.Cu")
		(net 651)
	)
	(segment
		(start 161.942342 164.347967)
		(end 161.991907 164.397532)
		(width 0.1)
		(layer "In4.Cu")
		(net 651)
	)
	(segment
		(start 159.962411 162.36807)
		(end 160.011991 162.41765)
		(width 0.1)
		(layer "In4.Cu")
		(net 651)
	)
	(segment
		(start 156.953728 160.42695)
		(end 156.953727 160.426949)
		(width 0.1)
		(layer "In4.Cu")
		(net 651)
	)
	(segment
		(start 166.307066 167.625)
		(end 169.107772 167.625)
		(width 0.1)
		(layer "In4.Cu")
		(net 651)
	)
	(segment
		(start 157.042118 160.069973)
		(end 156.953727 160.158361)
		(width 0.1)
		(layer "In4.Cu")
		(net 651)
	)
	(segment
		(start 159.923601 163.396825)
		(end 159.973183 163.446406)
		(width 0.1)
		(layer "In4.Cu")
		(net 651)
	)
	(segment
		(start 159.251852 162.456459)
		(end 159.251852 162.456458)
		(width 0.1)
		(layer "In4.Cu")
		(net 651)
	)
	(segment
		(start 178.5 169.455)
		(end 179.595662 169.455)
		(width 0.1)
		(layer "In4.Cu")
		(net 651)
	)
	(segment
		(start 156.992509 159.398222)
		(end 157.042118 159.447831)
		(width 0.1)
		(layer "In4.Cu")
		(net 651)
	)
	(segment
		(start 159.251852 162.456458)
		(end 159.340241 162.36807)
		(width 0.1)
		(layer "In4.Cu")
		(net 651)
	)
	(segment
		(start 161.231766 164.436357)
		(end 161.231766 164.436356)
		(width 0.1)
		(layer "In4.Cu")
		(net 651)
	)
	(segment
		(start 156.281977 159.486611)
		(end 156.370367 159.398222)
		(width 0.1)
		(layer "In4.Cu")
		(net 651)
	)
	(segment
		(start 157.271872 160.476561)
		(end 157.36026 160.38817)
		(width 0.1)
		(layer "In4.Cu")
		(net 651)
	)
	(segment
		(start 156.281977 159.486612)
		(end 156.281977 159.486611)
		(width 0.1)
		(layer "In4.Cu")
		(net 651)
	)
	(segment
		(start 161.903516 165.376738)
		(end 162.627759 166.100981)
		(width 0.1)
		(layer "In4.Cu")
		(net 651)
	)
	(arc
		(start 158.933625 162.138259)
		(mid 158.878 162.272555)
		(end 158.933626 162.406848)
		(width 0.1)
		(layer "In4.Cu")
		(net 651)
	)
	(arc
		(start 184.47525 164.84975)
		(mid 184.493937 164.821781)
		(end 184.5005 164.788791)
		(width 0.1)
		(layer "In4.Cu")
		(net 651)
	)
	(arc
		(start 183.875 165.505147)
		(mid 183.922967 165.264)
		(end 184.059566 165.059566)
		(width 0.1)
		(layer "In4.Cu")
		(net 651)
	)
	(arc
		(start 157.042118 159.447831)
		(mid 157.170967 159.758901)
		(end 157.042118 160.069973)
		(width 0.1)
		(layer "In4.Cu")
		(net 651)
	)
	(arc
		(start 183.34744 167.475781)
		(mid 183.737892 166.89143)
		(end 183.875 166.20214)
		(width 0.1)
		(layer "In4.Cu")
		(net 651)
	)
	(arc
		(start 159.022016 161.427729)
		(mid 159.150865 161.738799)
		(end 159.022016 162.049871)
		(width 0.1)
		(layer "In4.Cu")
		(net 651)
	)
	(arc
		(start 157.36026 160.38817)
		(mid 157.671304 160.259332)
		(end 157.982347 160.388171)
		(width 0.1)
		(layer "In4.Cu")
		(net 651)
	)
	(arc
		(start 156.370367 159.398222)
		(mid 156.681439 159.269372)
		(end 156.99251 159.398223)
		(width 0.1)
		(layer "In4.Cu")
		(net 651)
	)
	(arc
		(start 157.003336 160.476559)
		(mid 157.137605 160.532176)
		(end 157.271872 160.476561)
		(width 0.1)
		(layer "In4.Cu")
		(net 651)
	)
	(arc
		(start 169.107772 167.625)
		(mid 170.303277 167.8628)
		(end 171.316778 168.54)
		(width 0.1)
		(layer "In4.Cu")
		(net 651)
	)
	(arc
		(start 159.340241 162.36807)
		(mid 159.651325 162.239213)
		(end 159.962411 162.36807)
		(width 0.1)
		(layer "In4.Cu")
		(net 651)
	)
	(arc
		(start 158.983234 162.456457)
		(mid 159.117544 162.512091)
		(end 159.251852 162.456459)
		(width 0.1)
		(layer "In4.Cu")
		(net 651)
	)
	(arc
		(start 161.001855 163.407686)
		(mid 161.130693 163.718728)
		(end 161.001855 164.02977)
		(width 0.1)
		(layer "In4.Cu")
		(net 651)
	)
	(arc
		(start 184.171346 164.947785)
		(mid 184.251967 164.893916)
		(end 184.347066 164.875)
		(width 0.1)
		(layer "In4.Cu")
		(net 651)
	)
	(arc
		(start 156.953727 160.158361)
		(mid 156.898102 160.292657)
		(end 156.953728 160.42695)
		(width 0.1)
		(layer "In4.Cu")
		(net 651)
	)
	(arc
		(start 157.943622 161.148311)
		(mid 157.888007 161.282578)
		(end 157.943623 161.416844)
		(width 0.1)
		(layer "In4.Cu")
		(net 651)
	)
	(arc
		(start 156.013387 159.48661)
		(mid 156.147683 159.542238)
		(end 156.281977 159.486612)
		(width 0.1)
		(layer "In4.Cu")
		(net 651)
	)
	(arc
		(start 184.414291 164.875)
		(mid 184.447281 164.868437)
		(end 184.47525 164.84975)
		(width 0.1)
		(layer "In4.Cu")
		(net 651)
	)
	(arc
		(start 144.647814 150.375)
		(mid 146.730204 150.789213)
		(end 148.49557 151.968792)
		(width 0.1)
		(layer "In4.Cu")
		(net 651)
	)
	(arc
		(start 161.991907 164.397532)
		(mid 162.120766 164.708625)
		(end 161.991907 165.019718)
		(width 0.1)
		(layer "In4.Cu")
		(net 651)
	)
	(arc
		(start 160.011991 162.41765)
		(mid 160.140846 162.728734)
		(end 160.011992 163.039821)
		(width 0.1)
		(layer "In4.Cu")
		(net 651)
	)
	(arc
		(start 160.330104 163.358019)
		(mid 160.641146 163.229181)
		(end 160.952188 163.358019)
		(width 0.1)
		(layer "In4.Cu")
		(net 651)
	)
	(arc
		(start 127.42872 150.25193)
		(mid 127.565058 150.343015)
		(end 127.725873 150.375)
		(width 0.1)
		(layer "In4.Cu")
		(net 651)
	)
	(arc
		(start 159.923602 163.128209)
		(mid 159.867969 163.262517)
		(end 159.923603 163.396826)
		(width 0.1)
		(layer "In4.Cu")
		(net 651)
	)
	(arc
		(start 157.993285 161.466508)
		(mid 158.127581 161.522136)
		(end 158.261875 161.46651)
		(width 0.1)
		(layer "In4.Cu")
		(net 651)
	)
	(arc
		(start 125.01 149.81)
		(mid 125.203839 149.939519)
		(end 125.432486 149.985)
		(width 0.1)
		(layer "In4.Cu")
		(net 651)
	)
	(arc
		(start 160.963132 164.436355)
		(mid 161.09745 164.491993)
		(end 161.231766 164.436357)
		(width 0.1)
		(layer "In4.Cu")
		(net 651)
	)
	(arc
		(start 161.903516 165.108106)
		(mid 161.847881 165.242423)
		(end 161.903517 165.376739)
		(width 0.1)
		(layer "In4.Cu")
		(net 651)
	)
	(arc
		(start 160.913465 164.118157)
		(mid 160.857851 164.252423)
		(end 160.913466 164.386688)
		(width 0.1)
		(layer "In4.Cu")
		(net 651)
	)
	(arc
		(start 159.973183 163.446406)
		(mid 160.107449 163.502021)
		(end 160.241715 163.446408)
		(width 0.1)
		(layer "In4.Cu")
		(net 651)
	)
	(arc
		(start 158.350265 161.37812)
		(mid 158.661337 161.24927)
		(end 158.972408 161.378121)
		(width 0.1)
		(layer "In4.Cu")
		(net 651)
	)
	(arc
		(start 161.320156 164.347967)
		(mid 161.631249 164.219108)
		(end 161.942342 164.347967)
		(width 0.1)
		(layer "In4.Cu")
		(net 651)
	)
	(arc
		(start 126.886006 149.985)
		(mid 127.140786 150.035678)
		(end 127.356778 150.18)
		(width 0.1)
		(layer "In4.Cu")
		(net 651)
	)
	(arc
		(start 158.032012 160.437835)
		(mid 158.16085 160.748879)
		(end 158.032011 161.059922)
		(width 0.1)
		(layer "In4.Cu")
		(net 651)
	)
	(arc
		(start 171.385283 168.608506)
		(mid 172.322895 169.235003)
		(end 173.428886 169.455)
		(width 0.1)
		(layer "In4.Cu")
		(net 651)
	)
	(arc
		(start 162.627759 166.100981)
		(mid 164.315839 167.22892)
		(end 166.307066 167.625)
		(width 0.1)
		(layer "In4.Cu")
		(net 651)
	)
	(arc
		(start 179.595662 169.455)
		(mid 181.233293 169.129254)
		(end 182.62161 168.20161)
		(width 0.1)
		(layer "In4.Cu")
		(net 651)
	)
	(segment
		(start 186.5005 165.499499)
		(end 187 165)
		(width 0.256)
		(layer "F.Cu")
		(net 652)
	)
	(via
		(at 125.01 152.41)
		(size 0.45)
		(drill 0.1)
		(layers "F.Cu" "B.Cu")
		(remove_unused_layers yes)
		(keep_end_layers yes)
		(zone_layer_connections)
		(net 652)
	)
	(via
		(at 186.5005 165.499499)
		(size 0.45)
		(drill 0.1)
		(layers "F.Cu" "B.Cu")
		(remove_unused_layers yes)
		(keep_end_layers yes)
		(zone_layer_connections)
		(net 652)
	)
	(segment
		(start 124.65995 152.265001)
		(end 124.01895 152.265001)
		(width 0.16)
		(layer "B.Cu")
		(net 652)
	)
	(segment
		(start 123.602499 152.4375)
		(end 123.43 152.61)
		(width 0.16)
		(layer "B.Cu")
		(net 652)
	)
	(arc
		(start 124.65995 152.265001)
		(mid 124.849392 152.302683)
		(end 125.01 152.41)
		(width 0.16)
		(layer "B.Cu")
		(net 652)
	)
	(arc
		(start 124.01895 152.265001)
		(mid 123.793568 152.309832)
		(end 123.602499 152.4375)
		(width 0.16)
		(layer "B.Cu")
		(net 652)
	)
	(segment
		(start 149.400637 156.529797)
		(end 149.626828 156.303605)
		(width 0.1)
		(layer "In4.Cu")
		(net 652)
	)
	(segment
		(start 150.257929 156.934706)
		(end 150.257928 156.934705)
		(width 0.1)
		(layer "In4.Cu")
		(net 652)
	)
	(segment
		(start 183.50557 169.671207)
		(end 185.522512 167.654265)
		(width 0.1)
		(layer "In4.Cu")
		(net 652)
	)
	(segment
		(start 150.300367 155.902315)
		(end 150.300369 155.902316)
		(width 0.1)
		(layer "In4.Cu")
		(net 652)
	)
	(segment
		(start 170.384443 170.311225)
		(end 170.468222 170.395)
		(width 0.1)
		(layer "In4.Cu")
		(net 652)
	)
	(segment
		(start 125.432486 152.235)
		(end 127.363996 152.235)
		(width 0.1)
		(layer "In4.Cu")
		(net 652)
	)
	(segment
		(start 165.102185 169.525)
		(end 168.486277 169.525)
		(width 0.1)
		(layer "In4.Cu")
		(net 652)
	)
	(segment
		(start 150.346317 156.220513)
		(end 150.257928 156.308903)
		(width 0.1)
		(layer "In4.Cu")
		(net 652)
	)
	(segment
		(start 127.598125 152.125)
		(end 143.296726 152.125)
		(width 0.1)
		(layer "In4.Cu")
		(net 652)
	)
	(segment
		(start 150.257928 156.934705)
		(end 161.254429 167.931207)
		(width 0.1)
		(layer "In4.Cu")
		(net 652)
	)
	(segment
		(start 149.626828 156.303605)
		(end 150.028119 155.902315)
		(width 0.1)
		(layer "In4.Cu")
		(net 652)
	)
	(segment
		(start 149.356347 155.230586)
		(end 149.267957 155.318973)
		(width 0.1)
		(layer "In4.Cu")
		(net 652)
	)
	(segment
		(start 148.311611 154.988389)
		(end 148.31161 154.988387)
		(width 0.1)
		(layer "In4.Cu")
		(net 652)
	)
	(segment
		(start 148.937374 154.988389)
		(end 148.937372 154.988388)
		(width 0.1)
		(layer "In4.Cu")
		(net 652)
	)
	(segment
		(start 148.728886 156.487204)
		(end 148.771479 156.529797)
		(width 0.1)
		(layer "In4.Cu")
		(net 652)
	)
	(segment
		(start 149.297969 154.9)
		(end 149.356347 154.958378)
		(width 0.1)
		(layer "In4.Cu")
		(net 652)
	)
	(segment
		(start 172.568587 171.265)
		(end 179.657814 171.265)
		(width 0.1)
		(layer "In4.Cu")
		(net 652)
	)
	(segment
		(start 186.125 166.199732)
		(end 186.125 165.505151)
		(width 0.1)
		(layer "In4.Cu")
		(net 652)
	)
	(segment
		(start 148.937372 154.988388)
		(end 149.025761 154.9)
		(width 0.1)
		(layer "In4.Cu")
		(net 652)
	)
	(segment
		(start 149.267957 155.318973)
		(end 148.728886 155.858046)
		(width 0.1)
		(layer "In4.Cu")
		(net 652)
	)
	(segment
		(start 186.5005 165.211207)
		(end 186.5005 165.499499)
		(width 0.1)
		(layer "In4.Cu")
		(net 652)
	)
	(segment
		(start 146.969559 153.646337)
		(end 148.311611 154.988389)
		(width 0.1)
		(layer "In4.Cu")
		(net 652)
	)
	(segment
		(start 150.346317 156.220514)
		(end 150.346317 156.220513)
		(width 0.1)
		(layer "In4.Cu")
		(net 652)
	)
	(segment
		(start 186.398844 165.124999)
		(end 186.414291 165.124999)
		(width 0.1)
		(layer "In4.Cu")
		(net 652)
	)
	(segment
		(start 186.236343 165.236342)
		(end 186.311515 165.161171)
		(width 0.1)
		(layer "In4.Cu")
		(net 652)
	)
	(segment
		(start 127.496778 152.18)
		(end 127.518993 152.157781)
		(width 0.1)
		(layer "In4.Cu")
		(net 652)
	)
	(segment
		(start 150.300369 155.902316)
		(end 150.346318 155.948265)
		(width 0.1)
		(layer "In4.Cu")
		(net 652)
	)
	(arc
		(start 150.257928 156.308903)
		(mid 150.12832 156.621805)
		(end 150.257929 156.934706)
		(width 0.1)
		(layer "In4.Cu")
		(net 652)
	)
	(arc
		(start 143.296726 152.125)
		(mid 145.284449 152.520383)
		(end 146.969559 153.646337)
		(width 0.1)
		(layer "In4.Cu")
		(net 652)
	)
	(arc
		(start 149.356347 154.958378)
		(mid 149.412723 155.094482)
		(end 149.356347 155.230586)
		(width 0.1)
		(layer "In4.Cu")
		(net 652)
	)
	(arc
		(start 161.254429 167.931207)
		(mid 163.019794 169.110786)
		(end 165.102185 169.525)
		(width 0.1)
		(layer "In4.Cu")
		(net 652)
	)
	(arc
		(start 168.486277 169.525)
		(mid 169.513553 169.729333)
		(end 170.384443 170.311225)
		(width 0.1)
		(layer "In4.Cu")
		(net 652)
	)
	(arc
		(start 186.414291 165.124999)
		(mid 186.447281 165.131561)
		(end 186.47525 165.150249)
		(width 0.1)
		(layer "In4.Cu")
		(net 652)
	)
	(arc
		(start 186.125 165.505151)
		(mid 186.153937 165.359672)
		(end 186.236343 165.236342)
		(width 0.1)
		(layer "In4.Cu")
		(net 652)
	)
	(arc
		(start 179.657814 171.265)
		(mid 181.740204 170.850786)
		(end 183.50557 169.671207)
		(width 0.1)
		(layer "In4.Cu")
		(net 652)
	)
	(arc
		(start 150.028119 155.902315)
		(mid 150.164243 155.845931)
		(end 150.300367 155.902315)
		(width 0.1)
		(layer "In4.Cu")
		(net 652)
	)
	(arc
		(start 185.522512 167.654265)
		(mid 185.968418 166.986919)
		(end 186.125 166.199732)
		(width 0.1)
		(layer "In4.Cu")
		(net 652)
	)
	(arc
		(start 186.311515 165.161171)
		(mid 186.351581 165.134399)
		(end 186.398844 165.124999)
		(width 0.1)
		(layer "In4.Cu")
		(net 652)
	)
	(arc
		(start 186.47525 165.150249)
		(mid 186.493937 165.178216)
		(end 186.5005 165.211207)
		(width 0.1)
		(layer "In4.Cu")
		(net 652)
	)
	(arc
		(start 148.728886 155.858046)
		(mid 148.598583 156.172625)
		(end 148.728886 156.487204)
		(width 0.1)
		(layer "In4.Cu")
		(net 652)
	)
	(arc
		(start 149.025761 154.9)
		(mid 149.161865 154.843624)
		(end 149.297969 154.9)
		(width 0.1)
		(layer "In4.Cu")
		(net 652)
	)
	(arc
		(start 127.518993 152.157781)
		(mid 127.555298 152.133519)
		(end 127.598125 152.125)
		(width 0.1)
		(layer "In4.Cu")
		(net 652)
	)
	(arc
		(start 170.468222 170.395)
		(mid 171.431877 171.038894)
		(end 172.568587 171.265)
		(width 0.1)
		(layer "In4.Cu")
		(net 652)
	)
	(arc
		(start 148.771479 156.529797)
		(mid 149.086058 156.6601)
		(end 149.400637 156.529797)
		(width 0.1)
		(layer "In4.Cu")
		(net 652)
	)
	(arc
		(start 150.346318 155.948265)
		(mid 150.402701 156.084389)
		(end 150.346317 156.220514)
		(width 0.1)
		(layer "In4.Cu")
		(net 652)
	)
	(arc
		(start 127.363996 152.235)
		(mid 127.435857 152.220705)
		(end 127.496778 152.18)
		(width 0.1)
		(layer "In4.Cu")
		(net 652)
	)
	(arc
		(start 125.01 152.41)
		(mid 125.203839 152.280481)
		(end 125.432486 152.235)
		(width 0.1)
		(layer "In4.Cu")
		(net 652)
	)
	(arc
		(start 148.31161 154.988387)
		(mid 148.624492 155.117988)
		(end 148.937374 154.988389)
		(width 0.1)
		(layer "In4.Cu")
		(net 652)
	)
	(segment
		(start 186.5005 164.499499)
		(end 187 164)
		(width 0.256)
		(layer "F.Cu")
		(net 653)
	)
	(via
		(at 125.01 151.81)
		(size 0.45)
		(drill 0.1)
		(layers "F.Cu" "B.Cu")
		(remove_unused_layers yes)
		(keep_end_layers yes)
		(zone_layer_connections)
		(net 653)
	)
	(via
		(at 186.5005 164.499499)
		(size 0.45)
		(drill 0.1)
		(layers "F.Cu" "B.Cu")
		(remove_unused_layers yes)
		(keep_end_layers yes)
		(zone_layer_connections)
		(net 653)
	)
	(segment
		(start 124.01895 151.954999)
		(end 124.659953 151.954999)
		(width 0.16)
		(layer "B.Cu")
		(net 653)
	)
	(segment
		(start 123.602499 151.782499)
		(end 123.43 151.61)
		(width 0.16)
		(layer "B.Cu")
		(net 653)
	)
	(arc
		(start 125.01 151.81)
		(mid 124.849392 151.917318)
		(end 124.659953 151.954999)
		(width 0.16)
		(layer "B.Cu")
		(net 653)
	)
	(arc
		(start 124.01895 151.954999)
		(mid 123.793568 151.910167)
		(end 123.602499 151.782499)
		(width 0.16)
		(layer "B.Cu")
		(net 653)
	)
	(segment
		(start 149.223861 156.35302)
		(end 149.851342 155.725538)
		(width 0.1)
		(layer "In4.Cu")
		(net 653)
	)
	(segment
		(start 186.347066 164.874999)
		(end 186.414291 164.874999)
		(width 0.1)
		(layer "In4.Cu")
		(net 653)
	)
	(segment
		(start 127.349056 151.974173)
		(end 127.393222 151.93)
		(width 0.1)
		(layer "In4.Cu")
		(net 653)
	)
	(segment
		(start 150.434704 156.757927)
		(end 161.42517 167.748392)
		(width 0.1)
		(layer "In4.Cu")
		(net 653)
	)
	(segment
		(start 170.571778 170.145)
		(end 170.643292 170.216511)
		(width 0.1)
		(layer "In4.Cu")
		(net 653)
	)
	(segment
		(start 183.337304 169.485915)
		(end 185.338176 167.485045)
		(width 0.1)
		(layer "In4.Cu")
		(net 653)
	)
	(segment
		(start 165.110729 169.275)
		(end 168.471412 169.275)
		(width 0.1)
		(layer "In4.Cu")
		(net 653)
	)
	(segment
		(start 149.533125 155.407362)
		(end 149.533123 155.407361)
		(width 0.1)
		(layer "In4.Cu")
		(net 653)
	)
	(segment
		(start 149.223861 156.353019)
		(end 149.223861 156.35302)
		(width 0.1)
		(layer "In4.Cu")
		(net 653)
	)
	(segment
		(start 185.875 166.189038)
		(end 185.875 165.505146)
		(width 0.1)
		(layer "In4.Cu")
		(net 653)
	)
	(segment
		(start 172.571063 171.015)
		(end 179.645766 171.015)
		(width 0.1)
		(layer "In4.Cu")
		(net 653)
	)
	(segment
		(start 147.14557 153.468792)
		(end 148.488389 154.811611)
		(width 0.1)
		(layer "In4.Cu")
		(net 653)
	)
	(segment
		(start 150.523093 156.397289)
		(end 150.434704 156.485679)
		(width 0.1)
		(layer "In4.Cu")
		(net 653)
	)
	(segment
		(start 186.500333 164.499666)
		(end 186.5005 164.499499)
		(width 0.1)
		(layer "In4.Cu")
		(net 653)
	)
	(segment
		(start 150.434705 156.757928)
		(end 150.434704 156.757927)
		(width 0.1)
		(layer "In4.Cu")
		(net 653)
	)
	(segment
		(start 150.477144 155.725538)
		(end 150.523093 155.771487)
		(width 0.1)
		(layer "In4.Cu")
		(net 653)
	)
	(segment
		(start 186.500333 164.805905)
		(end 186.500333 164.499666)
		(width 0.1)
		(layer "In4.Cu")
		(net 653)
	)
	(segment
		(start 125.432486 151.985)
		(end 127.322921 151.985)
		(width 0.1)
		(layer "In4.Cu")
		(net 653)
	)
	(segment
		(start 148.760597 154.811612)
		(end 148.848984 154.723222)
		(width 0.1)
		(layer "In4.Cu")
		(net 653)
	)
	(segment
		(start 148.905663 156.310427)
		(end 148.948256 156.35302)
		(width 0.1)
		(layer "In4.Cu")
		(net 653)
	)
	(segment
		(start 149.474746 154.723223)
		(end 149.533124 154.781601)
		(width 0.1)
		(layer "In4.Cu")
		(net 653)
	)
	(segment
		(start 149.474745 154.723223)
		(end 149.474746 154.723223)
		(width 0.1)
		(layer "In4.Cu")
		(net 653)
	)
	(segment
		(start 149.533123 155.407361)
		(end 148.905663 156.034823)
		(width 0.1)
		(layer "In4.Cu")
		(net 653)
	)
	(segment
		(start 148.488389 154.811611)
		(end 148.488387 154.81161)
		(width 0.1)
		(layer "In4.Cu")
		(net 653)
	)
	(segment
		(start 127.526003 151.875)
		(end 143.297814 151.875)
		(width 0.1)
		(layer "In4.Cu")
		(net 653)
	)
	(segment
		(start 186.059565 165.059564)
		(end 186.171346 164.947784)
		(width 0.1)
		(layer "In4.Cu")
		(net 653)
	)
	(arc
		(start 148.948256 156.35302)
		(mid 149.086059 156.410099)
		(end 149.223861 156.353019)
		(width 0.1)
		(layer "In4.Cu")
		(net 653)
	)
	(arc
		(start 168.471412 169.275)
		(mid 169.608121 169.501105)
		(end 170.571778 170.145)
		(width 0.1)
		(layer "In4.Cu")
		(net 653)
	)
	(arc
		(start 170.643292 170.216511)
		(mid 171.527765 170.807479)
		(end 172.571063 171.015)
		(width 0.1)
		(layer "In4.Cu")
		(net 653)
	)
	(arc
		(start 127.393222 151.93)
		(mid 127.454142 151.889294)
		(end 127.526003 151.875)
		(width 0.1)
		(layer "In4.Cu")
		(net 653)
	)
	(arc
		(start 185.338176 167.485045)
		(mid 185.735484 166.890432)
		(end 185.875 166.189038)
		(width 0.1)
		(layer "In4.Cu")
		(net 653)
	)
	(arc
		(start 143.297814 151.875)
		(mid 145.380204 152.289213)
		(end 147.14557 153.468792)
		(width 0.1)
		(layer "In4.Cu")
		(net 653)
	)
	(arc
		(start 186.414291 164.874999)
		(mid 186.447281 164.868436)
		(end 186.47525 164.849749)
		(width 0.1)
		(layer "In4.Cu")
		(net 653)
	)
	(arc
		(start 161.42517 167.748392)
		(mid 163.116119 168.878248)
		(end 165.110729 169.275)
		(width 0.1)
		(layer "In4.Cu")
		(net 653)
	)
	(arc
		(start 150.434704 156.485679)
		(mid 150.378319 156.621803)
		(end 150.434705 156.757928)
		(width 0.1)
		(layer "In4.Cu")
		(net 653)
	)
	(arc
		(start 185.875 165.505146)
		(mid 185.922966 165.263999)
		(end 186.059565 165.059564)
		(width 0.1)
		(layer "In4.Cu")
		(net 653)
	)
	(arc
		(start 150.523093 155.771487)
		(mid 150.652702 156.084389)
		(end 150.523093 156.397289)
		(width 0.1)
		(layer "In4.Cu")
		(net 653)
	)
	(arc
		(start 148.488387 154.81161)
		(mid 148.624493 154.867988)
		(end 148.760597 154.811612)
		(width 0.1)
		(layer "In4.Cu")
		(net 653)
	)
	(arc
		(start 127.322921 151.985)
		(mid 127.337066 151.982186)
		(end 127.349056 151.974173)
		(width 0.1)
		(layer "In4.Cu")
		(net 653)
	)
	(arc
		(start 149.533124 154.781601)
		(mid 149.662724 155.094481)
		(end 149.533125 155.407362)
		(width 0.1)
		(layer "In4.Cu")
		(net 653)
	)
	(arc
		(start 179.645766 171.015)
		(mid 181.643612 170.617603)
		(end 183.337304 169.485915)
		(width 0.1)
		(layer "In4.Cu")
		(net 653)
	)
	(arc
		(start 186.171346 164.947784)
		(mid 186.251967 164.893915)
		(end 186.347066 164.874999)
		(width 0.1)
		(layer "In4.Cu")
		(net 653)
	)
	(arc
		(start 148.848984 154.723222)
		(mid 149.161865 154.593623)
		(end 149.474745 154.723223)
		(width 0.1)
		(layer "In4.Cu")
		(net 653)
	)
	(arc
		(start 186.47525 164.849749)
		(mid 186.49032 164.829429)
		(end 186.500333 164.805905)
		(width 0.1)
		(layer "In4.Cu")
		(net 653)
	)
	(arc
		(start 125.01 151.81)
		(mid 125.203839 151.939519)
		(end 125.432486 151.985)
		(width 0.1)
		(layer "In4.Cu")
		(net 653)
	)
	(arc
		(start 149.851342 155.725538)
		(mid 150.164244 155.595931)
		(end 150.477144 155.725538)
		(width 0.1)
		(layer "In4.Cu")
		(net 653)
	)
	(arc
		(start 148.905663 156.034823)
		(mid 148.848584 156.172625)
		(end 148.905663 156.310427)
		(width 0.1)
		(layer "In4.Cu")
		(net 653)
	)
	(segment
		(start 120.213499 183.5525)
		(end 120.851 183.5525)
		(width 0.16)
		(layer "F.Cu")
		(net 654)
	)
	(segment
		(start 111.463999 183.7695)
		(end 111.775498 183.458001)
		(width 0.16)
		(layer "F.Cu")
		(net 654)
	)
	(segment
		(start 114.425 183.4575)
		(end 120.118499 183.4575)
		(width 0.16)
		(layer "F.Cu")
		(net 654)
	)
	(segment
		(start 114.33 183.5525)
		(end 114.425 183.4575)
		(width 0.16)
		(layer "F.Cu")
		(net 654)
	)
	(segment
		(start 114.425 183.458)
		(end 120.118499 183.458)
		(width 0.16)
		(layer "F.Cu")
		(net 654)
	)
	(segment
		(start 109.375 183.7695)
		(end 111.463999 183.7695)
		(width 0.16)
		(layer "F.Cu")
		(net 654)
	)
	(segment
		(start 120.118499 183.458)
		(end 120.213499 183.553)
		(width 0.16)
		(layer "F.Cu")
		(net 654)
	)
	(segment
		(start 120.213499 183.553)
		(end 120.851 183.553)
		(width 0.16)
		(layer "F.Cu")
		(net 654)
	)
	(segment
		(start 120.118499 183.4575)
		(end 120.213499 183.5525)
		(width 0.16)
		(layer "F.Cu")
		(net 654)
	)
	(segment
		(start 111.775498 183.458001)
		(end 112.6375 183.458001)
		(width 0.16)
		(layer "F.Cu")
		(net 654)
	)
	(segment
		(start 114.33 183.553)
		(end 114.425 183.458)
		(width 0.16)
		(layer "F.Cu")
		(net 654)
	)
	(segment
		(start 113.917499 183.553)
		(end 114.33 183.553)
		(width 0.16)
		(layer "F.Cu")
		(net 654)
	)
	(segment
		(start 112.732499 183.553)
		(end 113.145499 183.553)
		(width 0.16)
		(layer "F.Cu")
		(net 654)
	)
	(segment
		(start 113.917499 183.5525)
		(end 114.33 183.5525)
		(width 0.16)
		(layer "F.Cu")
		(net 654)
	)
	(segment
		(start 113.917499 183.553)
		(end 113.145499 183.553)
		(width 0.15)
		(layer "F.Cu")
		(net 654)
	)
	(segment
		(start 112.6375 183.458001)
		(end 112.732499 183.553)
		(width 0.16)
		(layer "F.Cu")
		(net 654)
	)
	(segment
		(start 113.145499 183.053)
		(end 113.917499 183.053)
		(width 0.15)
		(layer "F.Cu")
		(net 655)
	)
	(segment
		(start 111.395999 182.7685)
		(end 111.775498 183.147999)
		(width 0.16)
		(layer "F.Cu")
		(net 655)
	)
	(segment
		(start 114.425 183.148)
		(end 120.118499 183.148)
		(width 0.16)
		(layer "F.Cu")
		(net 655)
	)
	(segment
		(start 112.627498 183.147999)
		(end 112.722497 183.053)
		(width 0.16)
		(layer "F.Cu")
		(net 655)
	)
	(segment
		(start 111.775498 183.147999)
		(end 112.627498 183.147999)
		(width 0.16)
		(layer "F.Cu")
		(net 655)
	)
	(segment
		(start 120.213499 183.053)
		(end 120.851 183.053)
		(width 0.16)
		(layer "F.Cu")
		(net 655)
	)
	(segment
		(start 120.118499 183.148)
		(end 120.213499 183.053)
		(width 0.16)
		(layer "F.Cu")
		(net 655)
	)
	(segment
		(start 112.722497 183.053)
		(end 113.145499 183.053)
		(width 0.16)
		(layer "F.Cu")
		(net 655)
	)
	(segment
		(start 114.33 183.053)
		(end 114.425 183.148)
		(width 0.16)
		(layer "F.Cu")
		(net 655)
	)
	(segment
		(start 113.917499 183.0525)
		(end 114.33 183.0525)
		(width 0.16)
		(layer "F.Cu")
		(net 655)
	)
	(segment
		(start 120.213499 183.0525)
		(end 120.851 183.0525)
		(width 0.16)
		(layer "F.Cu")
		(net 655)
	)
	(segment
		(start 114.33 183.0525)
		(end 114.425 183.1475)
		(width 0.16)
		(layer "F.Cu")
		(net 655)
	)
	(segment
		(start 114.425 183.1475)
		(end 120.118499 183.1475)
		(width 0.16)
		(layer "F.Cu")
		(net 655)
	)
	(segment
		(start 120.118499 183.1475)
		(end 120.213499 183.0525)
		(width 0.16)
		(layer "F.Cu")
		(net 655)
	)
	(segment
		(start 109.375 182.7685)
		(end 111.395999 182.7685)
		(width 0.16)
		(layer "F.Cu")
		(net 655)
	)
	(segment
		(start 113.917499 183.053)
		(end 114.33 183.053)
		(width 0.16)
		(layer "F.Cu")
		(net 655)
	)
	(segment
		(start 113.917499 182.053)
		(end 114.33 182.053)
		(width 0.16)
		(layer "F.Cu")
		(net 656)
	)
	(segment
		(start 120.213499 182.053)
		(end 120.851 182.053)
		(width 0.16)
		(layer "F.Cu")
		(net 656)
	)
	(segment
		(start 109.375 182.2695)
		(end 111.463999 182.2695)
		(width 0.16)
		(layer "F.Cu")
		(net 656)
	)
	(segment
		(start 112.6375 181.958001)
		(end 112.732499 182.053)
		(width 0.16)
		(layer "F.Cu")
		(net 656)
	)
	(segment
		(start 112.732499 182.053)
		(end 113.145499 182.053)
		(width 0.16)
		(layer "F.Cu")
		(net 656)
	)
	(segment
		(start 112.6375 181.958001)
		(end 112.732499 182.053)
		(width 0.16)
		(layer "F.Cu")
		(net 656)
	)
	(segment
		(start 120.213499 182.053)
		(end 120.851 182.053)
		(width 0.16)
		(layer "F.Cu")
		(net 656)
	)
	(segment
		(start 111.775498 181.958001)
		(end 112.6375 181.958001)
		(width 0.16)
		(layer "F.Cu")
		(net 656)
	)
	(segment
		(start 112.732499 182.053)
		(end 113.145499 182.053)
		(width 0.16)
		(layer "F.Cu")
		(net 656)
	)
	(segment
		(start 113.917499 182.053)
		(end 114.33 182.053)
		(width 0.16)
		(layer "F.Cu")
		(net 656)
	)
	(segment
		(start 113.917499 182.053)
		(end 113.145499 182.053)
		(width 0.15)
		(layer "F.Cu")
		(net 656)
	)
	(segment
		(start 111.463999 182.2695)
		(end 111.775498 181.958001)
		(width 0.16)
		(layer "F.Cu")
		(net 656)
	)
	(segment
		(start 111.775498 181.958001)
		(end 112.6375 181.958001)
		(width 0.16)
		(layer "F.Cu")
		(net 656)
	)
	(segment
		(start 114.33 182.053)
		(end 114.425 181.958)
		(width 0.16)
		(layer "F.Cu")
		(net 656)
	)
	(segment
		(start 114.425 181.958)
		(end 120.118499 181.958)
		(width 0.16)
		(layer "F.Cu")
		(net 656)
	)
	(segment
		(start 113.917499 182.053)
		(end 113.145499 182.053)
		(width 0.15)
		(layer "F.Cu")
		(net 656)
	)
	(segment
		(start 114.425 181.958)
		(end 120.118499 181.958)
		(width 0.16)
		(layer "F.Cu")
		(net 656)
	)
	(segment
		(start 120.118499 181.958)
		(end 120.213499 182.053)
		(width 0.16)
		(layer "F.Cu")
		(net 656)
	)
	(segment
		(start 114.33 182.053)
		(end 114.425 181.958)
		(width 0.16)
		(layer "F.Cu")
		(net 656)
	)
	(segment
		(start 111.463999 182.2695)
		(end 111.775498 181.958001)
		(width 0.16)
		(layer "F.Cu")
		(net 656)
	)
	(segment
		(start 109.375 182.2695)
		(end 111.463999 182.2695)
		(width 0.16)
		(layer "F.Cu")
		(net 656)
	)
	(segment
		(start 120.118499 181.958)
		(end 120.213499 182.053)
		(width 0.16)
		(layer "F.Cu")
		(net 656)
	)
	(segment
		(start 112.722497 181.553)
		(end 113.145499 181.553)
		(width 0.16)
		(layer "F.Cu")
		(net 657)
	)
	(segment
		(start 113.145499 181.553)
		(end 113.917499 181.553)
		(width 0.15)
		(layer "F.Cu")
		(net 657)
	)
	(segment
		(start 120.213499 181.553)
		(end 120.851 181.553)
		(width 0.16)
		(layer "F.Cu")
		(net 657)
	)
	(segment
		(start 113.145499 181.553)
		(end 113.917499 181.553)
		(width 0.15)
		(layer "F.Cu")
		(net 657)
	)
	(segment
		(start 114.33 181.553)
		(end 114.425 181.648)
		(width 0.16)
		(layer "F.Cu")
		(net 657)
	)
	(segment
		(start 112.627498 181.647999)
		(end 112.722497 181.553)
		(width 0.16)
		(layer "F.Cu")
		(net 657)
	)
	(segment
		(start 112.627498 181.647999)
		(end 112.722497 181.553)
		(width 0.16)
		(layer "F.Cu")
		(net 657)
	)
	(segment
		(start 114.425 181.648)
		(end 120.118499 181.648)
		(width 0.16)
		(layer "F.Cu")
		(net 657)
	)
	(segment
		(start 109.375 181.2685)
		(end 111.395999 181.2685)
		(width 0.16)
		(layer "F.Cu")
		(net 657)
	)
	(segment
		(start 120.118499 181.648)
		(end 120.213499 181.553)
		(width 0.16)
		(layer "F.Cu")
		(net 657)
	)
	(segment
		(start 111.775498 181.647999)
		(end 112.627498 181.647999)
		(width 0.16)
		(layer "F.Cu")
		(net 657)
	)
	(segment
		(start 113.917499 181.553)
		(end 114.33 181.553)
		(width 0.16)
		(layer "F.Cu")
		(net 657)
	)
	(segment
		(start 109.375 181.2685)
		(end 111.395999 181.2685)
		(width 0.16)
		(layer "F.Cu")
		(net 657)
	)
	(segment
		(start 114.425 181.648)
		(end 120.118499 181.648)
		(width 0.16)
		(layer "F.Cu")
		(net 657)
	)
	(segment
		(start 111.395999 181.2685)
		(end 111.775498 181.647999)
		(width 0.16)
		(layer "F.Cu")
		(net 657)
	)
	(segment
		(start 120.213499 181.553)
		(end 120.851 181.553)
		(width 0.16)
		(layer "F.Cu")
		(net 657)
	)
	(segment
		(start 111.395999 181.2685)
		(end 111.775498 181.647999)
		(width 0.16)
		(layer "F.Cu")
		(net 657)
	)
	(segment
		(start 113.917499 181.553)
		(end 114.33 181.553)
		(width 0.16)
		(layer "F.Cu")
		(net 657)
	)
	(segment
		(start 120.118499 181.648)
		(end 120.213499 181.553)
		(width 0.16)
		(layer "F.Cu")
		(net 657)
	)
	(segment
		(start 111.775498 181.647999)
		(end 112.627498 181.647999)
		(width 0.16)
		(layer "F.Cu")
		(net 657)
	)
	(segment
		(start 112.722497 181.553)
		(end 113.145499 181.553)
		(width 0.16)
		(layer "F.Cu")
		(net 657)
	)
	(segment
		(start 114.33 181.553)
		(end 114.425 181.648)
		(width 0.16)
		(layer "F.Cu")
		(net 657)
	)
	(segment
		(start 109.375 180.7695)
		(end 111.463999 180.7695)
		(width 0.16)
		(layer "F.Cu")
		(net 658)
	)
	(segment
		(start 112.6375 180.458001)
		(end 112.732499 180.553)
		(width 0.16)
		(layer "F.Cu")
		(net 658)
	)
	(segment
		(start 120.118499 180.458)
		(end 120.213499 180.553)
		(width 0.16)
		(layer "F.Cu")
		(net 658)
	)
	(segment
		(start 111.775498 180.458001)
		(end 112.6375 180.458001)
		(width 0.16)
		(layer "F.Cu")
		(net 658)
	)
	(segment
		(start 112.732499 180.553)
		(end 113.145499 180.553)
		(width 0.16)
		(layer "F.Cu")
		(net 658)
	)
	(segment
		(start 111.775498 180.458001)
		(end 112.6375 180.458001)
		(width 0.16)
		(layer "F.Cu")
		(net 658)
	)
	(segment
		(start 114.425 180.458)
		(end 120.118499 180.458)
		(width 0.16)
		(layer "F.Cu")
		(net 658)
	)
	(segment
		(start 112.732499 180.553)
		(end 113.145499 180.553)
		(width 0.16)
		(layer "F.Cu")
		(net 658)
	)
	(segment
		(start 114.33 180.553)
		(end 114.425 180.458)
		(width 0.16)
		(layer "F.Cu")
		(net 658)
	)
	(segment
		(start 111.463999 180.7695)
		(end 111.775498 180.458001)
		(width 0.16)
		(layer "F.Cu")
		(net 658)
	)
	(segment
		(start 114.33 180.553)
		(end 114.425 180.458)
		(width 0.16)
		(layer "F.Cu")
		(net 658)
	)
	(segment
		(start 113.917499 180.553)
		(end 114.33 180.553)
		(width 0.16)
		(layer "F.Cu")
		(net 658)
	)
	(segment
		(start 109.375 180.7695)
		(end 111.463999 180.7695)
		(width 0.16)
		(layer "F.Cu")
		(net 658)
	)
	(segment
		(start 113.917499 180.553)
		(end 113.145499 180.553)
		(width 0.15)
		(layer "F.Cu")
		(net 658)
	)
	(segment
		(start 113.917499 180.553)
		(end 114.33 180.553)
		(width 0.16)
		(layer "F.Cu")
		(net 658)
	)
	(segment
		(start 113.917499 180.553)
		(end 113.145499 180.553)
		(width 0.15)
		(layer "F.Cu")
		(net 658)
	)
	(segment
		(start 114.425 180.458)
		(end 120.118499 180.458)
		(width 0.16)
		(layer "F.Cu")
		(net 658)
	)
	(segment
		(start 120.118499 180.458)
		(end 120.213499 180.553)
		(width 0.16)
		(layer "F.Cu")
		(net 658)
	)
	(segment
		(start 120.213499 180.553)
		(end 120.851 180.553)
		(width 0.16)
		(layer "F.Cu")
		(net 658)
	)
	(segment
		(start 120.213499 180.553)
		(end 120.851 180.553)
		(width 0.16)
		(layer "F.Cu")
		(net 658)
	)
	(segment
		(start 111.463999 180.7695)
		(end 111.775498 180.458001)
		(width 0.16)
		(layer "F.Cu")
		(net 658)
	)
	(segment
		(start 112.6375 180.458001)
		(end 112.732499 180.553)
		(width 0.16)
		(layer "F.Cu")
		(net 658)
	)
	(segment
		(start 120.118499 180.148)
		(end 120.213499 180.053)
		(width 0.16)
		(layer "F.Cu")
		(net 659)
	)
	(segment
		(start 120.118499 180.148)
		(end 120.213499 180.053)
		(width 0.16)
		(layer "F.Cu")
		(net 659)
	)
	(segment
		(start 114.33 180.053)
		(end 114.425 180.148)
		(width 0.16)
		(layer "F.Cu")
		(net 659)
	)
	(segment
		(start 120.213499 180.053)
		(end 120.851 180.053)
		(width 0.16)
		(layer "F.Cu")
		(net 659)
	)
	(segment
		(start 111.775498 180.147999)
		(end 112.627498 180.147999)
		(width 0.16)
		(layer "F.Cu")
		(net 659)
	)
	(segment
		(start 113.917499 180.053)
		(end 114.33 180.053)
		(width 0.16)
		(layer "F.Cu")
		(net 659)
	)
	(segment
		(start 114.33 180.053)
		(end 114.425 180.148)
		(width 0.16)
		(layer "F.Cu")
		(net 659)
	)
	(segment
		(start 111.395999 179.7685)
		(end 111.775498 180.147999)
		(width 0.16)
		(layer "F.Cu")
		(net 659)
	)
	(segment
		(start 113.917499 180.053)
		(end 114.33 180.053)
		(width 0.16)
		(layer "F.Cu")
		(net 659)
	)
	(segment
		(start 112.627498 180.147999)
		(end 112.722497 180.053)
		(width 0.16)
		(layer "F.Cu")
		(net 659)
	)
	(segment
		(start 111.395999 179.7685)
		(end 111.775498 180.147999)
		(width 0.16)
		(layer "F.Cu")
		(net 659)
	)
	(segment
		(start 113.145499 180.053)
		(end 113.917499 180.053)
		(width 0.15)
		(layer "F.Cu")
		(net 659)
	)
	(segment
		(start 114.425 180.148)
		(end 120.118499 180.148)
		(width 0.16)
		(layer "F.Cu")
		(net 659)
	)
	(segment
		(start 113.145499 180.053)
		(end 113.917499 180.053)
		(width 0.15)
		(layer "F.Cu")
		(net 659)
	)
	(segment
		(start 111.775498 180.147999)
		(end 112.627498 180.147999)
		(width 0.16)
		(layer "F.Cu")
		(net 659)
	)
	(segment
		(start 112.722497 180.053)
		(end 113.145499 180.053)
		(width 0.16)
		(layer "F.Cu")
		(net 659)
	)
	(segment
		(start 112.627498 180.147999)
		(end 112.722497 180.053)
		(width 0.16)
		(layer "F.Cu")
		(net 659)
	)
	(segment
		(start 109.375 179.7685)
		(end 111.395999 179.7685)
		(width 0.16)
		(layer "F.Cu")
		(net 659)
	)
	(segment
		(start 120.213499 180.053)
		(end 120.851 180.053)
		(width 0.16)
		(layer "F.Cu")
		(net 659)
	)
	(segment
		(start 114.425 180.148)
		(end 120.118499 180.148)
		(width 0.16)
		(layer "F.Cu")
		(net 659)
	)
	(segment
		(start 109.375 179.7685)
		(end 111.395999 179.7685)
		(width 0.16)
		(layer "F.Cu")
		(net 659)
	)
	(segment
		(start 112.722497 180.053)
		(end 113.145499 180.053)
		(width 0.16)
		(layer "F.Cu")
		(net 659)
	)
	(segment
		(start 113.917499 179.053)
		(end 113.145499 179.053)
		(width 0.15)
		(layer "F.Cu")
		(net 660)
	)
	(segment
		(start 109.375 179.2695)
		(end 111.463999 179.2695)
		(width 0.16)
		(layer "F.Cu")
		(net 660)
	)
	(segment
		(start 120.118499 178.958)
		(end 120.213499 179.053)
		(width 0.16)
		(layer "F.Cu")
		(net 660)
	)
	(segment
		(start 114.33 179.053)
		(end 114.425 178.958)
		(width 0.16)
		(layer "F.Cu")
		(net 660)
	)
	(segment
		(start 111.775498 178.958001)
		(end 112.6375 178.958001)
		(width 0.16)
		(layer "F.Cu")
		(net 660)
	)
	(segment
		(start 114.425 178.958)
		(end 120.118499 178.958)
		(width 0.16)
		(layer "F.Cu")
		(net 660)
	)
	(segment
		(start 111.463999 179.2695)
		(end 111.775498 178.958001)
		(width 0.16)
		(layer "F.Cu")
		(net 660)
	)
	(segment
		(start 112.732499 179.053)
		(end 113.145499 179.053)
		(width 0.16)
		(layer "F.Cu")
		(net 660)
	)
	(segment
		(start 113.917499 179.053)
		(end 114.33 179.053)
		(width 0.16)
		(layer "F.Cu")
		(net 660)
	)
	(segment
		(start 111.463999 179.2695)
		(end 111.775498 178.958001)
		(width 0.16)
		(layer "F.Cu")
		(net 660)
	)
	(segment
		(start 120.213499 179.053)
		(end 120.851 179.053)
		(width 0.16)
		(layer "F.Cu")
		(net 660)
	)
	(segment
		(start 120.118499 178.958)
		(end 120.213499 179.053)
		(width 0.16)
		(layer "F.Cu")
		(net 660)
	)
	(segment
		(start 114.425 178.958)
		(end 120.118499 178.958)
		(width 0.16)
		(layer "F.Cu")
		(net 660)
	)
	(segment
		(start 120.213499 179.053)
		(end 120.851 179.053)
		(width 0.16)
		(layer "F.Cu")
		(net 660)
	)
	(segment
		(start 113.917499 179.053)
		(end 113.145499 179.053)
		(width 0.15)
		(layer "F.Cu")
		(net 660)
	)
	(segment
		(start 114.33 179.053)
		(end 114.425 178.958)
		(width 0.16)
		(layer "F.Cu")
		(net 660)
	)
	(segment
		(start 111.775498 178.958001)
		(end 112.6375 178.958001)
		(width 0.16)
		(layer "F.Cu")
		(net 660)
	)
	(segment
		(start 112.6375 178.958001)
		(end 112.732499 179.053)
		(width 0.16)
		(layer "F.Cu")
		(net 660)
	)
	(segment
		(start 112.732499 179.053)
		(end 113.145499 179.053)
		(width 0.16)
		(layer "F.Cu")
		(net 660)
	)
	(segment
		(start 112.6375 178.958001)
		(end 112.732499 179.053)
		(width 0.16)
		(layer "F.Cu")
		(net 660)
	)
	(segment
		(start 113.917499 179.053)
		(end 114.33 179.053)
		(width 0.16)
		(layer "F.Cu")
		(net 660)
	)
	(segment
		(start 109.375 179.2695)
		(end 111.463999 179.2695)
		(width 0.16)
		(layer "F.Cu")
		(net 660)
	)
	(segment
		(start 120.213499 178.553)
		(end 120.851 178.553)
		(width 0.16)
		(layer "F.Cu")
		(net 661)
	)
	(segment
		(start 109.375 178.2685)
		(end 111.395999 178.2685)
		(width 0.16)
		(layer "F.Cu")
		(net 661)
	)
	(segment
		(start 111.775498 178.647999)
		(end 112.627498 178.647999)
		(width 0.16)
		(layer "F.Cu")
		(net 661)
	)
	(segment
		(start 113.917499 178.553)
		(end 114.33 178.553)
		(width 0.16)
		(layer "F.Cu")
		(net 661)
	)
	(segment
		(start 111.395999 178.2685)
		(end 111.775498 178.647999)
		(width 0.16)
		(layer "F.Cu")
		(net 661)
	)
	(segment
		(start 114.33 178.553)
		(end 114.425 178.648)
		(width 0.16)
		(layer "F.Cu")
		(net 661)
	)
	(segment
		(start 114.33 178.553)
		(end 114.425 178.648)
		(width 0.16)
		(layer "F.Cu")
		(net 661)
	)
	(segment
		(start 120.118499 178.648)
		(end 120.213499 178.553)
		(width 0.16)
		(layer "F.Cu")
		(net 661)
	)
	(segment
		(start 114.425 178.648)
		(end 120.118499 178.648)
		(width 0.16)
		(layer "F.Cu")
		(net 661)
	)
	(segment
		(start 120.118499 178.648)
		(end 120.213499 178.553)
		(width 0.16)
		(layer "F.Cu")
		(net 661)
	)
	(segment
		(start 120.213499 178.553)
		(end 120.851 178.553)
		(width 0.16)
		(layer "F.Cu")
		(net 661)
	)
	(segment
		(start 113.145499 178.553)
		(end 113.917499 178.553)
		(width 0.15)
		(layer "F.Cu")
		(net 661)
	)
	(segment
		(start 114.425 178.648)
		(end 120.118499 178.648)
		(width 0.16)
		(layer "F.Cu")
		(net 661)
	)
	(segment
		(start 113.145499 178.553)
		(end 113.917499 178.553)
		(width 0.15)
		(layer "F.Cu")
		(net 661)
	)
	(segment
		(start 113.917499 178.553)
		(end 114.33 178.553)
		(width 0.16)
		(layer "F.Cu")
		(net 661)
	)
	(segment
		(start 112.627498 178.647999)
		(end 112.722497 178.553)
		(width 0.16)
		(layer "F.Cu")
		(net 661)
	)
	(segment
		(start 111.775498 178.647999)
		(end 112.627498 178.647999)
		(width 0.16)
		(layer "F.Cu")
		(net 661)
	)
	(segment
		(start 111.395999 178.2685)
		(end 111.775498 178.647999)
		(width 0.16)
		(layer "F.Cu")
		(net 661)
	)
	(segment
		(start 112.722497 178.553)
		(end 113.145499 178.553)
		(width 0.16)
		(layer "F.Cu")
		(net 661)
	)
	(segment
		(start 112.627498 178.647999)
		(end 112.722497 178.553)
		(width 0.16)
		(layer "F.Cu")
		(net 661)
	)
	(segment
		(start 109.375 178.2685)
		(end 111.395999 178.2685)
		(width 0.16)
		(layer "F.Cu")
		(net 661)
	)
	(segment
		(start 112.722497 178.553)
		(end 113.145499 178.553)
		(width 0.16)
		(layer "F.Cu")
		(net 661)
	)
	(segment
		(start 247.955 183.419)
		(end 247.975 183.399)
		(width 0.182)
		(layer "B.Cu")
		(net 662)
	)
	(segment
		(start 247.955 187.338)
		(end 247.955 185.299)
		(width 0.182)
		(layer "B.Cu")
		(net 662)
	)
	(segment
		(start 247.955 185.299)
		(end 247.955 183.419)
		(width 0.182)
		(layer "B.Cu")
		(net 662)
	)
	(segment
		(start 122.7005 162.51)
		(end 122.7005 162.2505)
		(width 0.1)
		(layer "F.Cu")
		(net 663)
	)
	(segment
		(start 122.5 162.05)
		(end 121.68 162.05)
		(width 0.1)
		(layer "F.Cu")
		(net 663)
	)
	(segment
		(start 121.68 162.05)
		(end 121.58 162.15)
		(width 0.1)
		(layer "F.Cu")
		(net 663)
	)
	(segment
		(start 122.7005 162.2505)
		(end 122.5 162.05)
		(width 0.1)
		(layer "F.Cu")
		(net 663)
	)
	(segment
		(start 252.925 183.549)
		(end 252.88 183.549)
		(width 0.182)
		(layer "F.Cu")
		(net 664)
	)
	(segment
		(start 253.325 184.475)
		(end 252.88 184.03)
		(width 0.256)
		(layer "F.Cu")
		(net 664)
	)
	(segment
		(start 252.959 182.558)
		(end 253.25 182.849)
		(width 0.182)
		(layer "F.Cu")
		(net 664)
	)
	(segment
		(start 252.88 184.03)
		(end 252.88 183.549)
		(width 0.256)
		(layer "F.Cu")
		(net 664)
	)
	(segment
		(start 253.25 182.849)
		(end 253.25 183.179)
		(width 0.182)
		(layer "F.Cu")
		(net 664)
	)
	(segment
		(start 252.92 182.558)
		(end 252.959 182.558)
		(width 0.182)
		(layer "F.Cu")
		(net 664)
	)
	(segment
		(start 253.25 183.179)
		(end 253.25 183.224)
		(width 0.182)
		(layer "F.Cu")
		(net 664)
	)
	(segment
		(start 253.25 183.224)
		(end 252.925 183.549)
		(width 0.182)
		(layer "F.Cu")
		(net 664)
	)
	(segment
		(start 254.525 184.475)
		(end 253.325 184.475)
		(width 0.256)
		(layer "F.Cu")
		(net 664)
	)
	(segment
		(start 252.92 182.558)
		(end 252.91 182.558)
		(width 0.182)
		(layer "F.Cu")
		(net 664)
	)
	(segment
		(start 175.9995 143.9995)
		(end 175.5 143.5)
		(width 0.256)
		(layer "F.Cu")
		(net 665)
	)
	(via
		(at 175.5 143.5)
		(size 0.45)
		(drill 0.1)
		(layers "F.Cu" "B.Cu")
		(remove_unused_layers yes)
		(keep_end_layers yes)
		(zone_layer_connections)
		(net 665)
	)
	(segment
		(start 176.9995 149.9995)
		(end 176.5 149.5)
		(width 0.256)
		(layer "F.Cu")
		(net 666)
	)
	(via
		(at 176.5 149.5)
		(size 0.45)
		(drill 0.1)
		(layers "F.Cu" "B.Cu")
		(remove_unused_layers yes)
		(keep_end_layers yes)
		(zone_layer_connections)
		(net 666)
	)
	(segment
		(start 206.215 154.44)
		(end 206.065 154.29)
		(width 0.1)
		(layer "F.Cu")
		(net 667)
	)
	(segment
		(start 206.44 154.44)
		(end 206.215 154.44)
		(width 0.1)
		(layer "F.Cu")
		(net 667)
	)
	(segment
		(start 191.0005 153.0005)
		(end 191.5 153.5)
		(width 0.256)
		(layer "F.Cu")
		(net 667)
	)
	(segment
		(start 206.065 154.29)
		(end 205.844698 154.29)
		(width 0.1)
		(layer "F.Cu")
		(net 667)
	)
	(segment
		(start 205.844698 154.29)
		(end 205.669698 154.465)
		(width 0.1)
		(layer "F.Cu")
		(net 667)
	)
	(via
		(at 191.5 153.5)
		(size 0.45)
		(drill 0.1)
		(layers "F.Cu" "B.Cu")
		(remove_unused_layers yes)
		(keep_end_layers yes)
		(zone_layer_connections)
		(net 667)
	)
	(via
		(at 205.669698 154.465)
		(size 0.45)
		(drill 0.1)
		(layers "F.Cu" "B.Cu")
		(remove_unused_layers yes)
		(keep_end_layers yes)
		(zone_layer_connections)
		(net 667)
	)
	(segment
		(start 194.231718 154.1)
		(end 193.89814 153.766422)
		(width 0.1)
		(layer "In2.Cu")
		(net 667)
	)
	(segment
		(start 193.89814 153.766422)
		(end 193.89814 152.84814)
		(width 0.1)
		(layer "In2.Cu")
		(net 667)
	)
	(segment
		(start 204.048578 154.29)
		(end 205.494698 154.29)
		(width 0.1)
		(layer "In2.Cu")
		(net 667)
	)
	(segment
		(start 191.5 152.7)
		(end 191.5 153.5)
		(width 0.1)
		(layer "In2.Cu")
		(net 667)
	)
	(segment
		(start 191.6 152.6)
		(end 191.5 152.7)
		(width 0.1)
		(layer "In2.Cu")
		(net 667)
	)
	(segment
		(start 205.494698 154.29)
		(end 205.669698 154.465)
		(width 0.1)
		(layer "In2.Cu")
		(net 667)
	)
	(segment
		(start 193.65 152.6)
		(end 191.6 152.6)
		(width 0.1)
		(layer "In2.Cu")
		(net 667)
	)
	(segment
		(start 193.89814 152.84814)
		(end 193.65 152.6)
		(width 0.1)
		(layer "In2.Cu")
		(net 667)
	)
	(segment
		(start 203.858578 154.1)
		(end 204.048578 154.29)
		(width 0.1)
		(layer "In2.Cu")
		(net 667)
	)
	(segment
		(start 194.231718 154.1)
		(end 203.858578 154.1)
		(width 0.1)
		(layer "In2.Cu")
		(net 667)
	)
	(segment
		(start 206.215 153.94)
		(end 206.065 154.09)
		(width 0.1)
		(layer "F.Cu")
		(net 668)
	)
	(segment
		(start 206.065 154.09)
		(end 205.844698 154.09)
		(width 0.1)
		(layer "F.Cu")
		(net 668)
	)
	(segment
		(start 206.44 153.94)
		(end 206.215 153.94)
		(width 0.1)
		(layer "F.Cu")
		(net 668)
	)
	(segment
		(start 205.844698 154.09)
		(end 205.669698 153.915)
		(width 0.1)
		(layer "F.Cu")
		(net 668)
	)
	(segment
		(start 191.0005 151.9995)
		(end 191.5 151.5)
		(width 0.256)
		(layer "F.Cu")
		(net 668)
	)
	(via
		(at 191.5 151.5)
		(size 0.45)
		(drill 0.1)
		(layers "F.Cu" "B.Cu")
		(remove_unused_layers yes)
		(keep_end_layers yes)
		(zone_layer_connections)
		(net 668)
	)
	(via
		(at 205.669698 153.915)
		(size 0.45)
		(drill 0.1)
		(layers "F.Cu" "B.Cu")
		(remove_unused_layers yes)
		(keep_end_layers yes)
		(zone_layer_connections)
		(net 668)
	)
	(segment
		(start 204.131422 154.09)
		(end 205.494698 154.09)
		(width 0.1)
		(layer "In2.Cu")
		(net 668)
	)
	(segment
		(start 194.09814 153.683578)
		(end 194.09814 152.765296)
		(width 0.1)
		(layer "In2.Cu")
		(net 668)
	)
	(segment
		(start 194.314562 153.9)
		(end 203.941422 153.9)
		(width 0.1)
		(layer "In2.Cu")
		(net 668)
	)
	(segment
		(start 194.314562 153.9)
		(end 194.09814 153.683578)
		(width 0.1)
		(layer "In2.Cu")
		(net 668)
	)
	(segment
		(start 203.941422 153.9)
		(end 204.131422 154.09)
		(width 0.1)
		(layer "In2.Cu")
		(net 668)
	)
	(segment
		(start 205.494698 154.09)
		(end 205.669698 153.915)
		(width 0.1)
		(layer "In2.Cu")
		(net 668)
	)
	(segment
		(start 191.575 152.4)
		(end 191.5 152.325)
		(width 0.1)
		(layer "In2.Cu")
		(net 668)
	)
	(segment
		(start 194.09814 152.765296)
		(end 193.732844 152.4)
		(width 0.1)
		(layer "In2.Cu")
		(net 668)
	)
	(segment
		(start 191.5 152.325)
		(end 191.5 151.5)
		(width 0.1)
		(layer "In2.Cu")
		(net 668)
	)
	(segment
		(start 193.732844 152.4)
		(end 191.575 152.4)
		(width 0.1)
		(layer "In2.Cu")
		(net 668)
	)
	(segment
		(start 181.9995 146.9995)
		(end 181.5 146.5)
		(width 0.256)
		(layer "F.Cu")
		(net 672)
	)
	(via
		(at 181.5 146.5)
		(size 0.45)
		(drill 0.1)
		(layers "F.Cu" "B.Cu")
		(remove_unused_layers yes)
		(keep_end_layers yes)
		(zone_layer_connections)
		(net 672)
	)
	(segment
		(start 120.52 149.61)
		(end 119.63 149.61)
		(width 0.16)
		(layer "F.Cu")
		(net 673)
	)
	(segment
		(start 120.52 148.61)
		(end 119.63 148.61)
		(width 0.16)
		(layer "F.Cu")
		(net 674)
	)
	(segment
		(start 120.52 150.61)
		(end 119.63 150.61)
		(width 0.16)
		(layer "F.Cu")
		(net 675)
	)
	(segment
		(start 120.52 147.61)
		(end 119.63 147.61)
		(width 0.16)
		(layer "F.Cu")
		(net 676)
	)
	(segment
		(start 120.52 154.61)
		(end 119.63 154.61)
		(width 0.16)
		(layer "F.Cu")
		(net 677)
	)
	(segment
		(start 119.635 153.61)
		(end 120.52 153.61)
		(width 0.16)
		(layer "F.Cu")
		(net 678)
	)
	(segment
		(start 120.52 152.61)
		(end 119.635 152.61)
		(width 0.16)
		(layer "F.Cu")
		(net 679)
	)
	(segment
		(start 119.63 151.61)
		(end 120.52 151.61)
		(width 0.16)
		(layer "F.Cu")
		(net 680)
	)
	(segment
		(start 237.2775 174.750001)
		(end 237.276998 174.7495)
		(width 0.256)
		(layer "F.Cu")
		(net 681)
	)
	(segment
		(start 237.849499 174.75)
		(end 237.2775 174.750001)
		(width 0.256)
		(layer "F.Cu")
		(net 681)
	)
	(via
		(at 237.276998 174.7495)
		(size 0.45)
		(drill 0.1)
		(layers "F.Cu" "B.Cu")
		(remove_unused_layers yes)
		(keep_end_layers yes)
		(zone_layer_connections)
		(net 681)
	)
	(via
		(at 246.597499 177.548)
		(size 0.45)
		(drill 0.1)
		(layers "F.Cu" "B.Cu")
		(remove_unused_layers yes)
		(keep_end_layers yes)
		(zone_layer_connections)
		(net 681)
	)
	(segment
		(start 241.391422 177.7)
		(end 238.691421 175)
		(width 0.1)
		(layer "In4.Cu")
		(net 681)
	)
	(segment
		(start 238.691421 175)
		(end 237.527498 175)
		(width 0.1)
		(layer "In4.Cu")
		(net 681)
	)
	(segment
		(start 246.597499 177.548)
		(end 246.422499 177.373)
		(width 0.1)
		(layer "In4.Cu")
		(net 681)
	)
	(segment
		(start 242.558578 177.7)
		(end 241.391422 177.7)
		(width 0.1)
		(layer "In4.Cu")
		(net 681)
	)
	(segment
		(start 246.422499 177.373)
		(end 246.422499 177.081077)
		(width 0.1)
		(layer "In4.Cu")
		(net 681)
	)
	(segment
		(start 246.091422 176.75)
		(end 243.508578 176.75)
		(width 0.1)
		(layer "In4.Cu")
		(net 681)
	)
	(segment
		(start 246.422499 177.081077)
		(end 246.091422 176.75)
		(width 0.1)
		(layer "In4.Cu")
		(net 681)
	)
	(segment
		(start 237.527498 175)
		(end 237.276998 174.7495)
		(width 0.1)
		(layer "In4.Cu")
		(net 681)
	)
	(segment
		(start 243.508578 176.75)
		(end 242.558578 177.7)
		(width 0.1)
		(layer "In4.Cu")
		(net 681)
	)
	(segment
		(start 237.2775 170.200002)
		(end 237.276998 170.199501)
		(width 0.256)
		(layer "F.Cu")
		(net 682)
	)
	(segment
		(start 237.849499 170.200001)
		(end 237.2775 170.200002)
		(width 0.256)
		(layer "F.Cu")
		(net 682)
	)
	(segment
		(start 246.551 167.949)
		(end 246.3 168.2)
		(width 0.1)
		(layer "F.Cu")
		(net 682)
	)
	(via
		(at 246.3 168.2)
		(size 0.45)
		(drill 0.1)
		(layers "F.Cu" "B.Cu")
		(remove_unused_layers yes)
		(keep_end_layers yes)
		(zone_layer_connections)
		(net 682)
	)
	(via
		(at 237.276998 170.199501)
		(size 0.45)
		(drill 0.1)
		(layers "F.Cu" "B.Cu")
		(remove_unused_layers yes)
		(keep_end_layers yes)
		(zone_layer_connections)
		(net 682)
	)
	(segment
		(start 246.566422 166.9)
		(end 242.683578 166.9)
		(width 0.1)
		(layer "In4.Cu")
		(net 682)
	)
	(segment
		(start 237.477497 170.4)
		(end 237.276998 170.199501)
		(width 0.1)
		(layer "In4.Cu")
		(net 682)
	)
	(segment
		(start 246.3 168.2)
		(end 246.47136 168.02864)
		(width 0.1)
		(layer "In4.Cu")
		(net 682)
	)
	(segment
		(start 239.183578 170.4)
		(end 237.477497 170.4)
		(width 0.1)
		(layer "In4.Cu")
		(net 682)
	)
	(segment
		(start 246.638711 168.02864)
		(end 246.925 167.742351)
		(width 0.1)
		(layer "In4.Cu")
		(net 682)
	)
	(segment
		(start 242.683578 166.9)
		(end 239.183578 170.4)
		(width 0.1)
		(layer "In4.Cu")
		(net 682)
	)
	(segment
		(start 246.925 167.258578)
		(end 246.566422 166.9)
		(width 0.1)
		(layer "In4.Cu")
		(net 682)
	)
	(segment
		(start 246.47136 168.02864)
		(end 246.638711 168.02864)
		(width 0.1)
		(layer "In4.Cu")
		(net 682)
	)
	(segment
		(start 246.925 167.742351)
		(end 246.925 167.258578)
		(width 0.1)
		(layer "In4.Cu")
		(net 682)
	)
	(segment
		(start 257.147 165.793)
		(end 257.147 165.876)
		(width 0.1)
		(layer "F.Cu")
		(net 683)
	)
	(segment
		(start 257.32 165.62)
		(end 257.147 165.793)
		(width 0.1)
		(layer "F.Cu")
		(net 683)
	)
	(segment
		(start 237.2775 169.200001)
		(end 237.276998 169.1995)
		(width 0.256)
		(layer "F.Cu")
		(net 683)
	)
	(segment
		(start 237.849499 169.2)
		(end 237.2775 169.200001)
		(width 0.256)
		(layer "F.Cu")
		(net 683)
	)
	(via
		(at 237.276998 169.1995)
		(size 0.45)
		(drill 0.1)
		(layers "F.Cu" "B.Cu")
		(remove_unused_layers yes)
		(keep_end_layers yes)
		(zone_layer_connections)
		(net 683)
	)
	(via
		(at 257.147 165.876)
		(size 0.45)
		(drill 0.1)
		(layers "F.Cu" "B.Cu")
		(remove_unused_layers yes)
		(keep_end_layers yes)
		(zone_layer_connections)
		(net 683)
	)
	(segment
		(start 257.233578 166.7)
		(end 257.725 166.208578)
		(width 0.1)
		(layer "In4.Cu")
		(net 683)
	)
	(segment
		(start 248.091422 166.7)
		(end 257.233578 166.7)
		(width 0.1)
		(layer "In4.Cu")
		(net 683)
	)
	(segment
		(start 257.725 165.817842)
		(end 257.607158 165.7)
		(width 0.1)
		(layer "In4.Cu")
		(net 683)
	)
	(segment
		(start 247.59142 166.2)
		(end 248.091422 166.7)
		(width 0.1)
		(layer "In4.Cu")
		(net 683)
	)
	(segment
		(start 241.75858 166.2)
		(end 247.59142 166.2)
		(width 0.1)
		(layer "In4.Cu")
		(net 683)
	)
	(segment
		(start 257.323 165.7)
		(end 257.147 165.876)
		(width 0.1)
		(layer "In4.Cu")
		(net 683)
	)
	(segment
		(start 238.558578 169.4)
		(end 241.75858 166.2)
		(width 0.1)
		(layer "In4.Cu")
		(net 683)
	)
	(segment
		(start 237.276998 169.1995)
		(end 237.477498 169.4)
		(width 0.1)
		(layer "In4.Cu")
		(net 683)
	)
	(segment
		(start 257.725 166.208578)
		(end 257.725 165.817842)
		(width 0.1)
		(layer "In4.Cu")
		(net 683)
	)
	(segment
		(start 257.607158 165.7)
		(end 257.323 165.7)
		(width 0.1)
		(layer "In4.Cu")
		(net 683)
	)
	(segment
		(start 237.477498 169.4)
		(end 238.558578 169.4)
		(width 0.1)
		(layer "In4.Cu")
		(net 683)
	)
	(segment
		(start 237.2775 175.750002)
		(end 237.276998 175.749501)
		(width 0.256)
		(layer "F.Cu")
		(net 684)
	)
	(segment
		(start 237.849499 175.750001)
		(end 237.2775 175.750002)
		(width 0.256)
		(layer "F.Cu")
		(net 684)
	)
	(via
		(at 256.897499 179.773)
		(size 0.45)
		(drill 0.1)
		(layers "F.Cu" "B.Cu")
		(remove_unused_layers yes)
		(keep_end_layers yes)
		(zone_layer_connections)
		(net 684)
	)
	(via
		(at 237.276998 175.749501)
		(size 0.45)
		(drill 0.1)
		(layers "F.Cu" "B.Cu")
		(remove_unused_layers yes)
		(keep_end_layers yes)
		(zone_layer_connections)
		(net 684)
	)
	(segment
		(start 255.283077 178.749)
		(end 253.852077 180.18)
		(width 0.1)
		(layer "In4.Cu")
		(net 684)
	)
	(segment
		(start 239.611855 178.094934)
		(end 239.611855 177.270433)
		(width 0.1)
		(layer "In4.Cu")
		(net 684)
	)
	(segment
		(start 241.696921 180.18)
		(end 239.611855 178.094934)
		(width 0.1)
		(layer "In4.Cu")
		(net 684)
	)
	(segment
		(start 239.611855 177.270433)
		(end 238.29142 175.95)
		(width 0.1)
		(layer "In4.Cu")
		(net 684)
	)
	(segment
		(start 253.852077 180.18)
		(end 241.696921 180.18)
		(width 0.1)
		(layer "In4.Cu")
		(net 684)
	)
	(segment
		(start 256.265921 178.749)
		(end 255.283077 178.749)
		(width 0.1)
		(layer "In4.Cu")
		(net 684)
	)
	(segment
		(start 256.897499 179.773)
		(end 256.722499 179.598)
		(width 0.1)
		(layer "In4.Cu")
		(net 684)
	)
	(segment
		(start 256.722499 179.598)
		(end 256.722499 179.205578)
		(width 0.1)
		(layer "In4.Cu")
		(net 684)
	)
	(segment
		(start 238.29142 175.95)
		(end 237.477497 175.95)
		(width 0.1)
		(layer "In4.Cu")
		(net 684)
	)
	(segment
		(start 256.722499 179.205578)
		(end 256.265921 178.749)
		(width 0.1)
		(layer "In4.Cu")
		(net 684)
	)
	(segment
		(start 237.477497 175.95)
		(end 237.276998 175.749501)
		(width 0.1)
		(layer "In4.Cu")
		(net 684)
	)
	(via
		(at 246.566499 160.15)
		(size 0.45)
		(drill 0.1)
		(layers "F.Cu" "B.Cu")
		(remove_unused_layers yes)
		(keep_end_layers yes)
		(zone_layer_connections)
		(net 685)
	)
	(via
		(at 236.8 156.68)
		(size 0.45)
		(drill 0.1)
		(layers "F.Cu" "B.Cu")
		(remove_unused_layers yes)
		(keep_end_layers yes)
		(zone_layer_connections)
		(net 685)
	)
	(segment
		(start 236.22 156.662)
		(end 236.782 156.662)
		(width 0.256)
		(layer "B.Cu")
		(net 685)
	)
	(segment
		(start 236.782 156.662)
		(end 236.8 156.68)
		(width 0.256)
		(layer "B.Cu")
		(net 685)
	)
	(segment
		(start 240.658578 161.45)
		(end 237.4 158.191422)
		(width 0.1)
		(layer "In4.Cu")
		(net 685)
	)
	(segment
		(start 237.4 156.891422)
		(end 237.208578 156.7)
		(width 0.1)
		(layer "In4.Cu")
		(net 685)
	)
	(segment
		(start 246.391499 160.325)
		(end 246.391499 160.649923)
		(width 0.1)
		(layer "In4.Cu")
		(net 685)
	)
	(segment
		(start 246.566499 160.15)
		(end 246.391499 160.325)
		(width 0.1)
		(layer "In4.Cu")
		(net 685)
	)
	(segment
		(start 237.208578 156.7)
		(end 236.82 156.7)
		(width 0.1)
		(layer "In4.Cu")
		(net 685)
	)
	(segment
		(start 245.591422 161.45)
		(end 240.658578 161.45)
		(width 0.1)
		(layer "In4.Cu")
		(net 685)
	)
	(segment
		(start 236.82 156.7)
		(end 236.8 156.68)
		(width 0.1)
		(layer "In4.Cu")
		(net 685)
	)
	(segment
		(start 237.4 158.191422)
		(end 237.4 156.891422)
		(width 0.1)
		(layer "In4.Cu")
		(net 685)
	)
	(segment
		(start 246.391499 160.649923)
		(end 245.591422 161.45)
		(width 0.1)
		(layer "In4.Cu")
		(net 685)
	)
	(via
		(at 238.55 158.25)
		(size 0.45)
		(drill 0.1)
		(layers "F.Cu" "B.Cu")
		(remove_unused_layers yes)
		(keep_end_layers yes)
		(zone_layer_connections)
		(net 686)
	)
	(via
		(at 246.562999 150.449)
		(size 0.45)
		(drill 0.1)
		(layers "F.Cu" "B.Cu")
		(remove_unused_layers yes)
		(keep_end_layers yes)
		(zone_layer_connections)
		(net 686)
	)
	(segment
		(start 238.09 158.25)
		(end 237.925 158.085)
		(width 0.256)
		(layer "B.Cu")
		(net 686)
	)
	(segment
		(start 238.55 158.25)
		(end 238.09 158.25)
		(width 0.256)
		(layer "B.Cu")
		(net 686)
	)
	(segment
		(start 238.75 158.05)
		(end 238.967158 158.05)
		(width 0.1)
		(layer "In4.Cu")
		(net 686)
	)
	(segment
		(start 246.387999 150.624)
		(end 246.562999 150.449)
		(width 0.1)
		(layer "In4.Cu")
		(net 686)
	)
	(segment
		(start 238.967158 158.05)
		(end 239.917158 159)
		(width 0.1)
		(layer "In4.Cu")
		(net 686)
	)
	(segment
		(start 246.387999 151.271078)
		(end 246.387999 150.624)
		(width 0.1)
		(layer "In4.Cu")
		(net 686)
	)
	(segment
		(start 241.314921 159)
		(end 246.924499 153.390422)
		(width 0.1)
		(layer "In4.Cu")
		(net 686)
	)
	(segment
		(start 246.924499 153.390422)
		(end 246.924499 151.807578)
		(width 0.1)
		(layer "In4.Cu")
		(net 686)
	)
	(segment
		(start 239.917158 159)
		(end 241.314921 159)
		(width 0.1)
		(layer "In4.Cu")
		(net 686)
	)
	(segment
		(start 246.924499 151.807578)
		(end 246.387999 151.271078)
		(width 0.1)
		(layer "In4.Cu")
		(net 686)
	)
	(segment
		(start 238.55 158.25)
		(end 238.75 158.05)
		(width 0.1)
		(layer "In4.Cu")
		(net 686)
	)
	(segment
		(start 196.000501 144.9995)
		(end 196.5 144.500001)
		(width 0.256)
		(layer "F.Cu")
		(net 687)
	)
	(segment
		(start 119.8 169.675)
		(end 119.225 169.675)
		(width 0.4)
		(layer "F.Cu")
		(net 687)
	)
	(segment
		(start 120 169.875)
		(end 119.8 169.675)
		(width 0.4)
		(layer "F.Cu")
		(net 687)
	)
	(segment
		(start 199.0005 143.9995)
		(end 199.5 143.5)
		(width 0.256)
		(layer "F.Cu")
		(net 687)
	)
	(segment
		(start 255.987 148.15)
		(end 255.179 148.15)
		(width 0.114)
		(layer "F.Cu")
		(net 687)
	)
	(segment
		(start 120 170.295)
		(end 120 169.875)
		(width 0.4)
		(layer "F.Cu")
		(net 687)
	)
	(segment
		(start 192.0005 142.9995)
		(end 192.5 142.5)
		(width 0.256)
		(layer "F.Cu")
		(net 687)
	)
	(segment
		(start 255.179 148.15)
		(end 255.177 148.148)
		(width 0.1)
		(layer "F.Cu")
		(net 687)
	)
	(segment
		(start 183.9995 143.9995)
		(end 183.5 143.5)
		(width 0.256)
		(layer "F.Cu")
		(net 687)
	)
	(segment
		(start 195.0005 141.9995)
		(end 195.5 141.5)
		(width 0.256)
		(layer "F.Cu")
		(net 687)
	)
	(segment
		(start 197.0005 147.9995)
		(end 197.5 147.5)
		(width 0.256)
		(layer "F.Cu")
		(net 687)
	)
	(segment
		(start 182.9995 140.9995)
		(end 182.5 140.5)
		(width 0.256)
		(layer "F.Cu")
		(net 687)
	)
	(segment
		(start 189 144)
		(end 188.5 144.5)
		(width 0.256)
		(layer "F.Cu")
		(net 687)
	)
	(segment
		(start 119.38 169.675)
		(end 120 170.295)
		(width 0.4)
		(layer "F.Cu")
		(net 687)
	)
	(segment
		(start 179.9995 141.9995)
		(end 179.5 141.5)
		(width 0.256)
		(layer "F.Cu")
		(net 687)
	)
	(segment
		(start 119.225 169.675)
		(end 119.38 169.675)
		(width 0.4)
		(layer "F.Cu")
		(net 687)
	)
	(via
		(at 195.5 141.5)
		(size 0.45)
		(drill 0.1)
		(layers "F.Cu" "B.Cu")
		(remove_unused_layers yes)
		(keep_end_layers yes)
		(zone_layer_connections "In8.Cu")
		(net 687)
	)
	(via
		(at 245.1 147.825)
		(size 0.45)
		(drill 0.1)
		(layers "F.Cu" "B.Cu")
		(remove_unused_layers yes)
		(keep_end_layers yes)
		(free yes)
		(zone_layer_connections "In8.Cu")
		(net 687)
	)
	(via
		(at 196.5 144.500001)
		(size 0.45)
		(drill 0.1)
		(layers "F.Cu" "B.Cu")
		(remove_unused_layers yes)
		(keep_end_layers yes)
		(zone_layer_connections "In8.Cu")
		(net 687)
	)
	(via
		(at 192.5 142.5)
		(size 0.45)
		(drill 0.1)
		(layers "F.Cu" "B.Cu")
		(remove_unused_layers yes)
		(keep_end_layers yes)
		(zone_layer_connections "In8.Cu")
		(net 687)
	)
	(via
		(at 246.45 147.825)
		(size 0.45)
		(drill 0.1)
		(layers "F.Cu" "B.Cu")
		(remove_unused_layers yes)
		(keep_end_layers yes)
		(free yes)
		(zone_layer_connections "In8.Cu")
		(net 687)
	)
	(via
		(at 199.5 143.5)
		(size 0.45)
		(drill 0.1)
		(layers "F.Cu" "B.Cu")
		(remove_unused_layers yes)
		(keep_end_layers yes)
		(zone_layer_connections "In8.Cu")
		(net 687)
	)
	(via
		(at 248.4 147.95)
		(size 0.45)
		(drill 0.1)
		(layers "F.Cu" "B.Cu")
		(remove_unused_layers yes)
		(keep_end_layers yes)
		(free yes)
		(zone_layer_connections "In8.Cu")
		(net 687)
	)
	(via
		(at 210.4 136.6)
		(size 0.45)
		(drill 0.1)
		(layers "F.Cu" "B.Cu")
		(net 687)
	)
	(via
		(at 182.5 140.5)
		(size 0.45)
		(drill 0.1)
		(layers "F.Cu" "B.Cu")
		(remove_unused_layers yes)
		(keep_end_layers yes)
		(zone_layer_connections "In8.Cu")
		(net 687)
	)
	(via
		(at 203.535 107.75)
		(size 0.45)
		(drill 0.1)
		(layers "F.Cu" "B.Cu")
		(remove_unused_layers yes)
		(keep_end_layers yes)
		(zone_layer_connections "In8.Cu")
		(net 687)
	)
	(via
		(at 173.835 107.75)
		(size 0.45)
		(drill 0.1)
		(layers "F.Cu" "B.Cu")
		(remove_unused_layers yes)
		(keep_end_layers yes)
		(zone_layer_connections "In8.Cu")
		(net 687)
	)
	(via
		(at 197.5 147.5)
		(size 0.45)
		(drill 0.1)
		(layers "F.Cu" "B.Cu")
		(remove_unused_layers yes)
		(keep_end_layers yes)
		(zone_layer_connections "In8.Cu")
		(net 687)
	)
	(via
		(at 245.775 147.775)
		(size 0.45)
		(drill 0.1)
		(layers "F.Cu" "B.Cu")
		(remove_unused_layers yes)
		(keep_end_layers yes)
		(free yes)
		(zone_layer_connections "In8.Cu")
		(net 687)
	)
	(via
		(at 246.675 148.6)
		(size 0.45)
		(drill 0.1)
		(layers "F.Cu" "B.Cu")
		(remove_unused_layers yes)
		(keep_end_layers yes)
		(free yes)
		(zone_layer_connections "In8.Cu")
		(net 687)
	)
	(via
		(at 247.820616 148.600948)
		(size 0.45)
		(drill 0.1)
		(layers "F.Cu" "B.Cu")
		(remove_unused_layers yes)
		(keep_end_layers yes)
		(free yes)
		(zone_layer_connections "In8.Cu")
		(net 687)
	)
	(via
		(at 187.915 107.75)
		(size 0.45)
		(drill 0.1)
		(layers "F.Cu" "B.Cu")
		(remove_unused_layers yes)
		(keep_end_layers yes)
		(zone_layer_connections "In8.Cu")
		(net 687)
	)
	(via
		(at 119.8 169.675)
		(size 0.45)
		(drill 0.1)
		(layers "F.Cu" "B.Cu")
		(net 687)
	)
	(via
		(at 119.225 169.675)
		(size 0.45)
		(drill 0.1)
		(layers "F.Cu" "B.Cu")
		(net 687)
	)
	(via
		(at 249.125 148.575)
		(size 0.45)
		(drill 0.1)
		(layers "F.Cu" "B.Cu")
		(remove_unused_layers yes)
		(keep_end_layers yes)
		(free yes)
		(zone_layer_connections "In8.Cu")
		(net 687)
	)
	(via
		(at 179.5 141.5)
		(size 0.45)
		(drill 0.1)
		(layers "F.Cu" "B.Cu")
		(remove_unused_layers yes)
		(keep_end_layers yes)
		(zone_layer_connections "In8.Cu")
		(net 687)
	)
	(via
		(at 247.197334 147.977666)
		(size 0.45)
		(drill 0.1)
		(layers "F.Cu" "B.Cu")
		(remove_unused_layers yes)
		(keep_end_layers yes)
		(free yes)
		(zone_layer_connections "In8.Cu")
		(net 687)
	)
	(via
		(at 183.5 143.5)
		(size 0.45)
		(drill 0.1)
		(layers "F.Cu" "B.Cu")
		(remove_unused_layers yes)
		(keep_end_layers yes)
		(zone_layer_connections "In8.Cu")
		(net 687)
	)
	(via
		(at 188.5 144.5)
		(size 0.45)
		(drill 0.1)
		(layers "F.Cu" "B.Cu")
		(remove_unused_layers yes)
		(keep_end_layers yes)
		(zone_layer_connections "In8.Cu")
		(net 687)
	)
	(segment
		(start 182 141)
		(end 182.5 140.5)
		(width 0.256)
		(layer "B.Cu")
		(net 687)
	)
	(segment
		(start 173.84 108.3)
		(end 173.84 107.755)
		(width 0.4)
		(layer "B.Cu")
		(net 687)
	)
	(segment
		(start 210.4 136.6)
		(end 209.8045 136.0045)
		(width 0.4)
		(layer "B.Cu")
		(net 687)
	)
	(segment
		(start 207.801 134.801)
		(end 207.4 134.4)
		(width 0.256)
		(layer "B.Cu")
		(net 687)
	)
	(segment
		(start 209.8045 136.0045)
		(end 207.801 136.0045)
		(width 0.4)
		(layer "B.Cu")
		(net 687)
	)
	(segment
		(start 203.54 107.755)
		(end 203.535 107.75)
		(width 0.4)
		(layer "B.Cu")
		(net 687)
	)
	(segment
		(start 207.4 134.4)
		(end 206.1 134.4)
		(width 0.256)
		(layer "B.Cu")
		(net 687)
	)
	(segment
		(start 179 142)
		(end 179.5 141.5)
		(width 0.256)
		(layer "B.Cu")
		(net 687)
	)
	(segment
		(start 207.801 137.0045)
		(end 207.801 136.0045)
		(width 0.256)
		(layer "B.Cu")
		(net 687)
	)
	(segment
		(start 196 141)
		(end 195.5 141.5)
		(width 0.256)
		(layer "B.Cu")
		(net 687)
	)
	(segment
		(start 199.502 143.5)
		(end 200.002 144)
		(width 0.256)
		(layer "B.Cu")
		(net 687)
	)
	(segment
		(start 179 142.002)
		(end 179 142)
		(width 0.256)
		(layer "B.Cu")
		(net 687)
	)
	(segment
		(start 183 144.002)
		(end 183 144)
		(width 0.256)
		(layer "B.Cu")
		(net 687)
	)
	(segment
		(start 206.1 134.4)
		(end 205.71 134.79)
		(width 0.256)
		(layer "B.Cu")
		(net 687)
	)
	(segment
		(start 173.84 107.755)
		(end 173.835 107.75)
		(width 0.4)
		(layer "B.Cu")
		(net 687)
	)
	(segment
		(start 197 148.002)
		(end 197 148)
		(width 0.256)
		(layer "B.Cu")
		(net 687)
	)
	(segment
		(start 205.71 134.79)
		(end 205.71 136.0045)
		(width 0.256)
		(layer "B.Cu")
		(net 687)
	)
	(segment
		(start 196.5 144.500001)
		(end 196.502001 144.500001)
		(width 0.256)
		(layer "B.Cu")
		(net 687)
	)
	(segment
		(start 192 143)
		(end 192.5 142.5)
		(width 0.256)
		(layer "B.Cu")
		(net 687)
	)
	(segment
		(start 199.5 143.5)
		(end 199.502 143.5)
		(width 0.256)
		(layer "B.Cu")
		(net 687)
	)
	(segment
		(start 203.54 108.3)
		(end 203.54 107.755)
		(width 0.4)
		(layer "B.Cu")
		(net 687)
	)
	(segment
		(start 187.92 107.755)
		(end 187.915 107.75)
		(width 0.4)
		(layer "B.Cu")
		(net 687)
	)
	(segment
		(start 197 148)
		(end 197.5 147.5)
		(width 0.256)
		(layer "B.Cu")
		(net 687)
	)
	(segment
		(start 183 144)
		(end 183.5 143.5)
		(width 0.256)
		(layer "B.Cu")
		(net 687)
	)
	(segment
		(start 192 143.002)
		(end 192 143)
		(width 0.256)
		(layer "B.Cu")
		(net 687)
	)
	(segment
		(start 196.502001 144.500001)
		(end 197.002 145)
		(width 0.256)
		(layer "B.Cu")
		(net 687)
	)
	(segment
		(start 207.801 138.1525)
		(end 207.801 137.0045)
		(width 0.256)
		(layer "B.Cu")
		(net 687)
	)
	(segment
		(start 182 141.002)
		(end 182 141)
		(width 0.256)
		(layer "B.Cu")
		(net 687)
	)
	(segment
		(start 196 140.998)
		(end 196 141)
		(width 0.256)
		(layer "B.Cu")
		(net 687)
	)
	(segment
		(start 187.92 108.3)
		(end 187.92 107.755)
		(width 0.4)
		(layer "B.Cu")
		(net 687)
	)
	(segment
		(start 188.5 145.05)
		(end 188.5 144.5)
		(width 0.4)
		(layer "B.Cu")
		(net 687)
	)
	(segment
		(start 207.801 136.0045)
		(end 207.801 134.801)
		(width 0.256)
		(layer "B.Cu")
		(net 687)
	)
	(via
		(at 257.4245 162.423998)
		(size 0.45)
		(drill 0.1)
		(layers "F.Cu" "B.Cu")
		(remove_unused_layers yes)
		(keep_end_layers yes)
		(zone_layer_connections)
		(net 688)
	)
	(via
		(at 236.8 153.8)
		(size 0.45)
		(drill 0.1)
		(layers "F.Cu" "B.Cu")
		(remove_unused_layers yes)
		(keep_end_layers yes)
		(zone_layer_connections)
		(net 688)
	)
	(segment
		(start 236.22 153.782)
		(end 236.782 153.782)
		(width 0.256)
		(layer "B.Cu")
		(net 688)
	)
	(segment
		(start 236.782 153.782)
		(end 236.8 153.8)
		(width 0.256)
		(layer "B.Cu")
		(net 688)
	)
	(segment
		(start 257.2495 162.991922)
		(end 256.791421 163.45)
		(width 0.1)
		(layer "In4.Cu")
		(net 688)
	)
	(segment
		(start 257.4245 162.423998)
		(end 257.2495 162.598998)
		(width 0.1)
		(layer "In4.Cu")
		(net 688)
	)
	(segment
		(start 236.5775 154.0225)
		(end 236.8 153.8)
		(width 0.1)
		(layer "In4.Cu")
		(net 688)
	)
	(segment
		(start 256.791421 163.45)
		(end 240.967158 163.45)
		(width 0.1)
		(layer "In4.Cu")
		(net 688)
	)
	(segment
		(start 235.25 155.108578)
		(end 236.336078 154.0225)
		(width 0.1)
		(layer "In4.Cu")
		(net 688)
	)
	(segment
		(start 235.25 157.732842)
		(end 235.25 155.108578)
		(width 0.1)
		(layer "In4.Cu")
		(net 688)
	)
	(segment
		(start 240.967158 163.45)
		(end 235.25 157.732842)
		(width 0.1)
		(layer "In4.Cu")
		(net 688)
	)
	(segment
		(start 257.2495 162.598998)
		(end 257.2495 162.991922)
		(width 0.1)
		(layer "In4.Cu")
		(net 688)
	)
	(segment
		(start 236.336078 154.0225)
		(end 236.5775 154.0225)
		(width 0.1)
		(layer "In4.Cu")
		(net 688)
	)
	(segment
		(start 237.849499 175.25)
		(end 236.952499 175.250001)
		(width 0.256)
		(layer "F.Cu")
		(net 689)
	)
	(segment
		(start 236.952499 175.250001)
		(end 236.951999 175.2495)
		(width 0.256)
		(layer "F.Cu")
		(net 689)
	)
	(via
		(at 236.951999 175.2495)
		(size 0.45)
		(drill 0.1)
		(layers "F.Cu" "B.Cu")
		(remove_unused_layers yes)
		(keep_end_layers yes)
		(zone_layer_connections)
		(net 689)
	)
	(via
		(at 246.047499 177.548)
		(size 0.45)
		(drill 0.1)
		(layers "F.Cu" "B.Cu")
		(remove_unused_layers yes)
		(keep_end_layers yes)
		(zone_layer_connections)
		(net 689)
	)
	(segment
		(start 237.36084 175.2495)
		(end 236.951999 175.2495)
		(width 0.1)
		(layer "In4.Cu")
		(net 689)
	)
	(segment
		(start 241.308578 177.9)
		(end 238.608578 175.2)
		(width 0.1)
		(layer "In4.Cu")
		(net 689)
	)
	(segment
		(start 242.641422 177.9)
		(end 241.308578 177.9)
		(width 0.1)
		(layer "In4.Cu")
		(net 689)
	)
	(segment
		(start 246.222499 177.373)
		(end 246.222499 177.163921)
		(width 0.1)
		(layer "In4.Cu")
		(net 689)
	)
	(segment
		(start 246.222499 177.163921)
		(end 246.008578 176.95)
		(width 0.1)
		(layer "In4.Cu")
		(net 689)
	)
	(segment
		(start 243.591422 176.95)
		(end 242.641422 177.9)
		(width 0.1)
		(layer "In4.Cu")
		(net 689)
	)
	(segment
		(start 238.608578 175.2)
		(end 237.41034 175.2)
		(width 0.1)
		(layer "In4.Cu")
		(net 689)
	)
	(segment
		(start 246.047499 177.548)
		(end 246.222499 177.373)
		(width 0.1)
		(layer "In4.Cu")
		(net 689)
	)
	(segment
		(start 237.41034 175.2)
		(end 237.36084 175.2495)
		(width 0.1)
		(layer "In4.Cu")
		(net 689)
	)
	(segment
		(start 246.008578 176.95)
		(end 243.591422 176.95)
		(width 0.1)
		(layer "In4.Cu")
		(net 689)
	)
	(segment
		(start 246.000877 167.95)
		(end 246.272236 167.678641)
		(width 0.1)
		(layer "F.Cu")
		(net 690)
	)
	(segment
		(start 246.272236 167.678641)
		(end 246.272236 167.629517)
		(width 0.1)
		(layer "F.Cu")
		(net 690)
	)
	(segment
		(start 237.849499 170.698001)
		(end 236.9525 170.698001)
		(width 0.256)
		(layer "F.Cu")
		(net 690)
	)
	(segment
		(start 236.9525 170.698001)
		(end 236.951999 170.6975)
		(width 0.256)
		(layer "F.Cu")
		(net 690)
	)
	(via
		(at 236.951999 170.6975)
		(size 0.45)
		(drill 0.1)
		(layers "F.Cu" "B.Cu")
		(remove_unused_layers yes)
		(keep_end_layers yes)
		(zone_layer_connections)
		(net 690)
	)
	(via
		(at 246.272236 167.629517)
		(size 0.45)
		(drill 0.1)
		(layers "F.Cu" "B.Cu")
		(remove_unused_layers yes)
		(keep_end_layers yes)
		(zone_layer_connections)
		(net 690)
	)
	(segment
		(start 246.725 167.341422)
		(end 246.483578 167.1)
		(width 0.1)
		(layer "In4.Cu")
		(net 690)
	)
	(segment
		(start 246.272236 167.629517)
		(end 246.471359 167.82864)
		(width 0.1)
		(layer "In4.Cu")
		(net 690)
	)
	(segment
		(start 237.3275 170.6975)
		(end 236.951999 170.6975)
		(width 0.1)
		(layer "In4.Cu")
		(net 690)
	)
	(segment
		(start 246.471359 167.82864)
		(end 246.555867 167.82864)
		(width 0.1)
		(layer "In4.Cu")
		(net 690)
	)
	(segment
		(start 246.483578 167.1)
		(end 242.766422 167.1)
		(width 0.1)
		(layer "In4.Cu")
		(net 690)
	)
	(segment
		(start 239.266422 170.6)
		(end 237.425 170.6)
		(width 0.1)
		(layer "In4.Cu")
		(net 690)
	)
	(segment
		(start 237.425 170.6)
		(end 237.3275 170.6975)
		(width 0.1)
		(layer "In4.Cu")
		(net 690)
	)
	(segment
		(start 246.725 167.659507)
		(end 246.725 167.341422)
		(width 0.1)
		(layer "In4.Cu")
		(net 690)
	)
	(segment
		(start 246.555867 167.82864)
		(end 246.725 167.659507)
		(width 0.1)
		(layer "In4.Cu")
		(net 690)
	)
	(segment
		(start 242.766422 167.1)
		(end 239.266422 170.6)
		(width 0.1)
		(layer "In4.Cu")
		(net 690)
	)
	(segment
		(start 257.075737 165.300517)
		(end 257.075737 165.391263)
		(width 0.1)
		(layer "F.Cu")
		(net 691)
	)
	(segment
		(start 257.075737 165.391263)
		(end 256.847 165.62)
		(width 0.1)
		(layer "F.Cu")
		(net 691)
	)
	(segment
		(start 237.849499 169.7)
		(end 236.952499 169.700001)
		(width 0.256)
		(layer "F.Cu")
		(net 691)
	)
	(segment
		(start 236.952499 169.700001)
		(end 236.951999 169.6995)
		(width 0.256)
		(layer "F.Cu")
		(net 691)
	)
	(via
		(at 236.951999 169.6995)
		(size 0.45)
		(drill 0.1)
		(layers "F.Cu" "B.Cu")
		(remove_unused_layers yes)
		(keep_end_layers yes)
		(zone_layer_connections)
		(net 691)
	)
	(via
		(at 257.075737 165.300517)
		(size 0.45)
		(drill 0.1)
		(layers "F.Cu" "B.Cu")
		(remove_unused_layers yes)
		(keep_end_layers yes)
		(zone_layer_connections)
		(net 691)
	)
	(segment
		(start 238.641422 169.6)
		(end 241.841422 166.4)
		(width 0.1)
		(layer "In4.Cu")
		(net 691)
	)
	(segment
		(start 257.925 165.735)
		(end 257.69 165.5)
		(width 0.1)
		(layer "In4.Cu")
		(net 691)
	)
	(segment
		(start 237.4 169.6)
		(end 238.641422 169.6)
		(width 0.1)
		(layer "In4.Cu")
		(net 691)
	)
	(segment
		(start 236.951999 169.6995)
		(end 237.3005 169.6995)
		(width 0.1)
		(layer "In4.Cu")
		(net 691)
	)
	(segment
		(start 241.841422 166.4)
		(end 247.508578 166.4)
		(width 0.1)
		(layer "In4.Cu")
		(net 691)
	)
	(segment
		(start 248.008578 166.9)
		(end 257.316422 166.9)
		(width 0.1)
		(layer "In4.Cu")
		(net 691)
	)
	(segment
		(start 257.925 166.291422)
		(end 257.925 165.735)
		(width 0.1)
		(layer "In4.Cu")
		(net 691)
	)
	(segment
		(start 237.3005 169.6995)
		(end 237.4 169.6)
		(width 0.1)
		(layer "In4.Cu")
		(net 691)
	)
	(segment
		(start 247.508578 166.4)
		(end 248.008578 166.9)
		(width 0.1)
		(layer "In4.Cu")
		(net 691)
	)
	(segment
		(start 257.316422 166.9)
		(end 257.925 166.291422)
		(width 0.1)
		(layer "In4.Cu")
		(net 691)
	)
	(segment
		(start 257.27522 165.5)
		(end 257.075737 165.300517)
		(width 0.1)
		(layer "In4.Cu")
		(net 691)
	)
	(segment
		(start 257.69 165.5)
		(end 257.27522 165.5)
		(width 0.1)
		(layer "In4.Cu")
		(net 691)
	)
	(segment
		(start 236.9525 176.248001)
		(end 236.951999 176.2475)
		(width 0.256)
		(layer "F.Cu")
		(net 692)
	)
	(segment
		(start 237.849499 176.248001)
		(end 236.9525 176.248001)
		(width 0.256)
		(layer "F.Cu")
		(net 692)
	)
	(via
		(at 236.951999 176.2475)
		(size 0.45)
		(drill 0.1)
		(layers "F.Cu" "B.Cu")
		(remove_unused_layers yes)
		(keep_end_layers yes)
		(zone_layer_connections)
		(net 692)
	)
	(via
		(at 256.347499 179.773)
		(size 0.45)
		(drill 0.1)
		(layers "F.Cu" "B.Cu")
		(remove_unused_layers yes)
		(keep_end_layers yes)
		(zone_layer_connections)
		(net 692)
	)
	(segment
		(start 256.522499 179.598)
		(end 256.522499 179.288422)
		(width 0.1)
		(layer "In4.Cu")
		(net 692)
	)
	(segment
		(start 255.365921 178.949)
		(end 253.934921 180.38)
		(width 0.1)
		(layer "In4.Cu")
		(net 692)
	)
	(segment
		(start 239.411855 178.177778)
		(end 239.411855 177.353277)
		(width 0.1)
		(layer "In4.Cu")
		(net 692)
	)
	(segment
		(start 256.522499 179.288422)
		(end 256.183077 178.949)
		(width 0.1)
		(layer "In4.Cu")
		(net 692)
	)
	(segment
		(start 256.183077 178.949)
		(end 255.365921 178.949)
		(width 0.1)
		(layer "In4.Cu")
		(net 692)
	)
	(segment
		(start 238.208578 176.15)
		(end 237.4 176.15)
		(width 0.1)
		(layer "In4.Cu")
		(net 692)
	)
	(segment
		(start 237.4 176.15)
		(end 237.3025 176.2475)
		(width 0.1)
		(layer "In4.Cu")
		(net 692)
	)
	(segment
		(start 256.347499 179.773)
		(end 256.522499 179.598)
		(width 0.1)
		(layer "In4.Cu")
		(net 692)
	)
	(segment
		(start 237.3025 176.2475)
		(end 236.951999 176.2475)
		(width 0.1)
		(layer "In4.Cu")
		(net 692)
	)
	(segment
		(start 239.411855 177.353277)
		(end 238.208578 176.15)
		(width 0.1)
		(layer "In4.Cu")
		(net 692)
	)
	(segment
		(start 241.614077 180.38)
		(end 239.411855 178.177778)
		(width 0.1)
		(layer "In4.Cu")
		(net 692)
	)
	(segment
		(start 253.934921 180.38)
		(end 241.614077 180.38)
		(width 0.1)
		(layer "In4.Cu")
		(net 692)
	)
	(segment
		(start 237.2415 156.0585)
		(end 237.240998 156.057999)
		(width 0.256)
		(layer "F.Cu")
		(net 693)
	)
	(segment
		(start 237.813499 156.058499)
		(end 237.2415 156.0585)
		(width 0.256)
		(layer "F.Cu")
		(net 693)
	)
	(via
		(at 237.240998 156.057999)
		(size 0.45)
		(drill 0.1)
		(layers "F.Cu" "B.Cu")
		(remove_unused_layers yes)
		(keep_end_layers yes)
		(zone_layer_connections)
		(net 693)
	)
	(via
		(at 246.016499 160.15)
		(size 0.45)
		(drill 0.1)
		(layers "F.Cu" "B.Cu")
		(remove_unused_layers yes)
		(keep_end_layers yes)
		(zone_layer_connections)
		(net 693)
	)
	(segment
		(start 237.3 156.508578)
		(end 237.3 156.117001)
		(width 0.1)
		(layer "In4.Cu")
		(net 693)
	)
	(segment
		(start 237.3 156.508578)
		(end 237.6 156.808578)
		(width 0.1)
		(layer "In4.Cu")
		(net 693)
	)
	(segment
		(start 246.191499 160.325)
		(end 246.191499 160.567079)
		(width 0.1)
		(layer "In4.Cu")
		(net 693)
	)
	(segment
		(start 237.3 156.117001)
		(end 237.240998 156.057999)
		(width 0.1)
		(layer "In4.Cu")
		(net 693)
	)
	(segment
		(start 246.191499 160.567079)
		(end 245.508578 161.25)
		(width 0.1)
		(layer "In4.Cu")
		(net 693)
	)
	(segment
		(start 245.508578 161.25)
		(end 240.741422 161.25)
		(width 0.1)
		(layer "In4.Cu")
		(net 693)
	)
	(segment
		(start 240.741422 161.25)
		(end 237.6 158.108578)
		(width 0.1)
		(layer "In4.Cu")
		(net 693)
	)
	(segment
		(start 237.6 158.108578)
		(end 237.6 156.808578)
		(width 0.1)
		(layer "In4.Cu")
		(net 693)
	)
	(segment
		(start 246.016499 160.15)
		(end 246.191499 160.325)
		(width 0.1)
		(layer "In4.Cu")
		(net 693)
	)
	(segment
		(start 239.027499 157.344499)
		(end 239.026998 157.345001)
		(width 0.256)
		(layer "F.Cu")
		(net 694)
	)
	(segment
		(start 239.027498 156.7725)
		(end 239.027499 157.344499)
		(width 0.256)
		(layer "F.Cu")
		(net 694)
	)
	(via
		(at 239.026998 157.345001)
		(size 0.45)
		(drill 0.1)
		(layers "F.Cu" "B.Cu")
		(remove_unused_layers yes)
		(keep_end_layers yes)
		(zone_layer_connections)
		(net 694)
	)
	(via
		(at 246.012999 150.449)
		(size 0.45)
		(drill 0.1)
		(layers "F.Cu" "B.Cu")
		(remove_unused_layers yes)
		(keep_end_layers yes)
		(zone_layer_connections)
		(net 694)
	)
	(segment
		(start 246.724499 153.307578)
		(end 246.724499 151.890422)
		(width 0.1)
		(layer "In4.Cu")
		(net 694)
	)
	(segment
		(start 246.187999 150.624)
		(end 246.012999 150.449)
		(width 0.1)
		(layer "In4.Cu")
		(net 694)
	)
	(segment
		(start 241.232077 158.8)
		(end 246.724499 153.307578)
		(width 0.1)
		(layer "In4.Cu")
		(net 694)
	)
	(segment
		(start 239.026998 157.345001)
		(end 239.026998 157.826998)
		(width 0.1)
		(layer "In4.Cu")
		(net 694)
	)
	(segment
		(start 240 158.8)
		(end 241.232077 158.8)
		(width 0.1)
		(layer "In4.Cu")
		(net 694)
	)
	(segment
		(start 246.724499 151.890422)
		(end 246.187999 151.353922)
		(width 0.1)
		(layer "In4.Cu")
		(net 694)
	)
	(segment
		(start 246.187999 151.353922)
		(end 246.187999 150.624)
		(width 0.1)
		(layer "In4.Cu")
		(net 694)
	)
	(segment
		(start 239.026998 157.826998)
		(end 240 158.8)
		(width 0.1)
		(layer "In4.Cu")
		(net 694)
	)
	(segment
		(start 257.14 148.15)
		(end 256.953 148.15)
		(width 0.1)
		(layer "F.Cu")
		(net 695)
	)
	(segment
		(start 256.953 148.15)
		(end 256.951 148.148)
		(width 0.1)
		(layer "F.Cu")
		(net 695)
	)
	(via
		(at 238.541875 152.692735)
		(size 0.45)
		(drill 0.1)
		(layers "F.Cu" "B.Cu")
		(remove_unused_layers yes)
		(keep_end_layers yes)
		(zone_layer_connections)
		(net 695)
	)
	(via
		(at 256.951 148.148)
		(size 0.45)
		(drill 0.1)
		(layers "F.Cu" "B.Cu")
		(remove_unused_layers yes)
		(keep_end_layers yes)
		(zone_layer_connections)
		(net 695)
	)
	(segment
		(start 238.022265 152.692735)
		(end 237.925 152.79)
		(width 0.256)
		(layer "B.Cu")
		(net 695)
	)
	(segment
		(start 238.541875 152.692735)
		(end 238.022265 152.692735)
		(width 0.256)
		(layer "B.Cu")
		(net 695)
	)
	(segment
		(start 256.291422 147.2)
		(end 244.058578 147.2)
		(width 0.1)
		(layer "In4.Cu")
		(net 695)
	)
	(segment
		(start 238.8 152.55)
		(end 238.657265 152.692735)
		(width 0.1)
		(layer "In4.Cu")
		(net 695)
	)
	(segment
		(start 244.058578 147.2)
		(end 238.8 152.458578)
		(width 0.1)
		(layer "In4.Cu")
		(net 695)
	)
	(segment
		(start 256.776 147.973)
		(end 256.776 147.684578)
		(width 0.1)
		(layer "In4.Cu")
		(net 695)
	)
	(segment
		(start 238.8 152.458578)
		(end 238.8 152.55)
		(width 0.1)
		(layer "In4.Cu")
		(net 695)
	)
	(segment
		(start 238.657265 152.692735)
		(end 238.541875 152.692735)
		(width 0.1)
		(layer "In4.Cu")
		(net 695)
	)
	(segment
		(start 256.776 147.684578)
		(end 256.291422 147.2)
		(width 0.1)
		(layer "In4.Cu")
		(net 695)
	)
	(segment
		(start 256.951 148.148)
		(end 256.776 147.973)
		(width 0.1)
		(layer "In4.Cu")
		(net 695)
	)
	(segment
		(start 236.9165 154.5615)
		(end 236.915999 154.560999)
		(width 0.256)
		(layer "F.Cu")
		(net 696)
	)
	(segment
		(start 237.813499 154.5615)
		(end 236.9165 154.5615)
		(width 0.256)
		(layer "F.Cu")
		(net 696)
	)
	(via
		(at 236.915999 154.560999)
		(size 0.45)
		(drill 0.1)
		(layers "F.Cu" "B.Cu")
		(remove_unused_layers yes)
		(keep_end_layers yes)
		(zone_layer_connections)
		(net 696)
	)
	(via
		(at 256.8745 162.423998)
		(size 0.45)
		(drill 0.1)
		(layers "F.Cu" "B.Cu")
		(remove_unused_layers yes)
		(keep_end_layers yes)
		(zone_layer_connections)
		(net 696)
	)
	(segment
		(start 257.0495 162.909078)
		(end 256.708578 163.25)
		(width 0.1)
		(layer "In4.Cu")
		(net 696)
	)
	(segment
		(start 241.05 163.25)
		(end 235.45 157.65)
		(width 0.1)
		(layer "In4.Cu")
		(net 696)
	)
	(segment
		(start 256.708578 163.25)
		(end 241.05 163.25)
		(width 0.1)
		(layer "In4.Cu")
		(net 696)
	)
	(segment
		(start 236.5775 154.2225)
		(end 236.915999 154.560999)
		(width 0.1)
		(layer "In4.Cu")
		(net 696)
	)
	(segment
		(start 235.45 157.65)
		(end 235.45 155.191422)
		(width 0.1)
		(layer "In4.Cu")
		(net 696)
	)
	(segment
		(start 256.8745 162.423998)
		(end 257.0495 162.598998)
		(width 0.1)
		(layer "In4.Cu")
		(net 696)
	)
	(segment
		(start 257.0495 162.598998)
		(end 257.0495 162.909078)
		(width 0.1)
		(layer "In4.Cu")
		(net 696)
	)
	(segment
		(start 236.418922 154.2225)
		(end 236.5775 154.2225)
		(width 0.1)
		(layer "In4.Cu")
		(net 696)
	)
	(segment
		(start 235.45 155.191422)
		(end 236.418922 154.2225)
		(width 0.1)
		(layer "In4.Cu")
		(net 696)
	)
	(segment
		(start 183.9995 157.0005)
		(end 183.5 157.500001)
		(width 0.256)
		(layer "F.Cu")
		(net 697)
	)
	(via
		(at 116.435 115)
		(size 0.45)
		(drill 0.1)
		(layers "F.Cu" "B.Cu")
		(remove_unused_layers yes)
		(keep_end_layers yes)
		(zone_layer_connections)
		(net 697)
	)
	(via
		(at 183.5 157.500001)
		(size 0.45)
		(drill 0.1)
		(layers "F.Cu" "B.Cu")
		(remove_unused_layers yes)
		(keep_end_layers yes)
		(zone_layer_connections)
		(net 697)
	)
	(segment
		(start 115.705 115)
		(end 116.435 115)
		(width 0.15)
		(layer "B.Cu")
		(net 697)
	)
	(segment
		(start 181.75 156)
		(end 181.25 156)
		(width 0.1)
		(layer "In6.Cu")
		(net 697)
	)
	(segment
		(start 175.469669 155)
		(end 168.969669 148.5)
		(width 0.1)
		(layer "In6.Cu")
		(net 697)
	)
	(segment
		(start 181 155.25)
		(end 180.75 155)
		(width 0.1)
		(layer "In6.Cu")
		(net 697)
	)
	(segment
		(start 183.5 157.500001)
		(end 182.999999 157)
		(width 0.1)
		(layer "In6.Cu")
		(net 697)
	)
	(segment
		(start 182.4 157)
		(end 182 156.6)
		(width 0.1)
		(layer "In6.Cu")
		(net 697)
	)
	(segment
		(start 121.55 115)
		(end 116.43 115)
		(width 0.1)
		(layer "In6.Cu")
		(net 697)
	)
	(segment
		(start 168.969669 148.5)
		(end 155.05 148.5)
		(width 0.1)
		(layer "In6.Cu")
		(net 697)
	)
	(segment
		(start 182.999999 157)
		(end 182.4 157)
		(width 0.1)
		(layer "In6.Cu")
		(net 697)
	)
	(segment
		(start 155.05 148.5)
		(end 121.55 115)
		(width 0.1)
		(layer "In6.Cu")
		(net 697)
	)
	(segment
		(start 182 156.25)
		(end 181.75 156)
		(width 0.1)
		(layer "In6.Cu")
		(net 697)
	)
	(segment
		(start 180.75 155)
		(end 175.469669 155)
		(width 0.1)
		(layer "In6.Cu")
		(net 697)
	)
	(segment
		(start 182 156.6)
		(end 182 156.25)
		(width 0.1)
		(layer "In6.Cu")
		(net 697)
	)
	(segment
		(start 181 155.75)
		(end 181 155.25)
		(width 0.1)
		(layer "In6.Cu")
		(net 697)
	)
	(segment
		(start 181.25 156)
		(end 181 155.75)
		(width 0.1)
		(layer "In6.Cu")
		(net 697)
	)
	(segment
		(start 183.9995 156.0005)
		(end 183.5 156.5)
		(width 0.256)
		(layer "F.Cu")
		(net 698)
	)
	(via
		(at 116.4 112.3)
		(size 0.45)
		(drill 0.1)
		(layers "F.Cu" "B.Cu")
		(remove_unused_layers yes)
		(keep_end_layers yes)
		(zone_layer_connections)
		(net 698)
	)
	(via
		(at 183.5 156.5)
		(size 0.45)
		(drill 0.1)
		(layers "F.Cu" "B.Cu")
		(remove_unused_layers yes)
		(keep_end_layers yes)
		(zone_layer_connections)
		(net 698)
	)
	(segment
		(start 115.705 112.3)
		(end 116.4 112.3)
		(width 0.15)
		(layer "B.Cu")
		(net 698)
	)
	(segment
		(start 155.6375 148)
		(end 122.1375 114.5)
		(width 0.1)
		(layer "In6.Cu")
		(net 698)
	)
	(segment
		(start 183.5 156.5)
		(end 183 156)
		(width 0.1)
		(layer "In6.Cu")
		(net 698)
	)
	(segment
		(start 175.469669 154)
		(end 169.469669 148)
		(width 0.1)
		(layer "In6.Cu")
		(net 698)
	)
	(segment
		(start 182.3 156)
		(end 182 155.7)
		(width 0.1)
		(layer "In6.Cu")
		(net 698)
	)
	(segment
		(start 169.469669 148)
		(end 155.6375 148)
		(width 0.1)
		(layer "In6.Cu")
		(net 698)
	)
	(segment
		(start 182 155.7)
		(end 182 154.25)
		(width 0.1)
		(layer "In6.Cu")
		(net 698)
	)
	(segment
		(start 122.1375 114.5)
		(end 118.63 114.5)
		(width 0.1)
		(layer "In6.Cu")
		(net 698)
	)
	(segment
		(start 118.63 114.5)
		(end 116.43 112.3)
		(width 0.1)
		(layer "In6.Cu")
		(net 698)
	)
	(segment
		(start 182 154.25)
		(end 181.75 154)
		(width 0.1)
		(layer "In6.Cu")
		(net 698)
	)
	(segment
		(start 181.75 154)
		(end 175.469669 154)
		(width 0.1)
		(layer "In6.Cu")
		(net 698)
	)
	(segment
		(start 183 156)
		(end 182.3 156)
		(width 0.1)
		(layer "In6.Cu")
		(net 698)
	)
	(segment
		(start 183.9995 155.0005)
		(end 183.5 155.5)
		(width 0.256)
		(layer "F.Cu")
		(net 699)
	)
	(via
		(at 183.5 155.5)
		(size 0.45)
		(drill 0.1)
		(layers "F.Cu" "B.Cu")
		(remove_unused_layers yes)
		(keep_end_layers yes)
		(zone_layer_connections)
		(net 699)
	)
	(via
		(at 116.435 109.6)
		(size 0.45)
		(drill 0.1)
		(layers "F.Cu" "B.Cu")
		(remove_unused_layers yes)
		(keep_end_layers yes)
		(zone_layer_connections)
		(net 699)
	)
	(segment
		(start 115.705 109.6)
		(end 116.435 109.6)
		(width 0.15)
		(layer "B.Cu")
		(net 699)
	)
	(segment
		(start 175.5 153)
		(end 170 147.5)
		(width 0.1)
		(layer "In6.Cu")
		(net 699)
	)
	(segment
		(start 183 155)
		(end 183 153.469669)
		(width 0.1)
		(layer "In6.Cu")
		(net 699)
	)
	(segment
		(start 183 153.469669)
		(end 182.530331 153)
		(width 0.1)
		(layer "In6.Cu")
		(net 699)
	)
	(segment
		(start 170 147.5)
		(end 156.225 147.5)
		(width 0.1)
		(layer "In6.Cu")
		(net 699)
	)
	(segment
		(start 182.530331 153)
		(end 175.5 153)
		(width 0.1)
		(layer "In6.Cu")
		(net 699)
	)
	(segment
		(start 116.9 109.83)
		(end 116.67 109.6)
		(width 0.1)
		(layer "In6.Cu")
		(net 699)
	)
	(segment
		(start 156.225 147.5)
		(end 122.725 114)
		(width 0.1)
		(layer "In6.Cu")
		(net 699)
	)
	(segment
		(start 183.5 155.5)
		(end 183 155)
		(width 0.1)
		(layer "In6.Cu")
		(net 699)
	)
	(segment
		(start 116.9 111.9)
		(end 116.9 109.83)
		(width 0.1)
		(layer "In6.Cu")
		(net 699)
	)
	(segment
		(start 119 114)
		(end 116.9 111.9)
		(width 0.1)
		(layer "In6.Cu")
		(net 699)
	)
	(segment
		(start 116.67 109.6)
		(end 116.43 109.6)
		(width 0.1)
		(layer "In6.Cu")
		(net 699)
	)
	(segment
		(start 122.725 114)
		(end 119 114)
		(width 0.1)
		(layer "In6.Cu")
		(net 699)
	)
	(segment
		(start 184.9995 157.0005)
		(end 184.5 157.5)
		(width 0.256)
		(layer "F.Cu")
		(net 700)
	)
	(via
		(at 184.5 157.5)
		(size 0.45)
		(drill 0.1)
		(layers "F.Cu" "B.Cu")
		(remove_unused_layers yes)
		(keep_end_layers yes)
		(zone_layer_connections)
		(net 700)
	)
	(via
		(at 116.435 106.9)
		(size 0.45)
		(drill 0.1)
		(layers "F.Cu" "B.Cu")
		(remove_unused_layers yes)
		(keep_end_layers yes)
		(zone_layer_connections)
		(net 700)
	)
	(segment
		(start 115.705 106.9)
		(end 116.435 106.9)
		(width 0.15)
		(layer "B.Cu")
		(net 700)
	)
	(segment
		(start 175.469669 152)
		(end 170.469669 147)
		(width 0.1)
		(layer "In6.Cu")
		(net 700)
	)
	(segment
		(start 117.2 107.67)
		(end 116.43 106.9)
		(width 0.1)
		(layer "In6.Cu")
		(net 700)
	)
	(segment
		(start 184.5 157.5)
		(end 183.88 156.88)
		(width 0.1)
		(layer "In6.Cu")
		(net 700)
	)
	(segment
		(start 183.88 156.88)
		(end 183.88 152.88)
		(width 0.1)
		(layer "In6.Cu")
		(net 700)
	)
	(segment
		(start 119.5 113.5)
		(end 117.2 111.2)
		(width 0.1)
		(layer "In6.Cu")
		(net 700)
	)
	(segment
		(start 117.2 111.2)
		(end 117.2 107.67)
		(width 0.1)
		(layer "In6.Cu")
		(net 700)
	)
	(segment
		(start 183 152)
		(end 175.469669 152)
		(width 0.1)
		(layer "In6.Cu")
		(net 700)
	)
	(segment
		(start 156.75 147)
		(end 123.25 113.5)
		(width 0.1)
		(layer "In6.Cu")
		(net 700)
	)
	(segment
		(start 170.469669 147)
		(end 156.75 147)
		(width 0.1)
		(layer "In6.Cu")
		(net 700)
	)
	(segment
		(start 123.25 113.5)
		(end 119.5 113.5)
		(width 0.1)
		(layer "In6.Cu")
		(net 700)
	)
	(segment
		(start 183.88 152.88)
		(end 183 152)
		(width 0.1)
		(layer "In6.Cu")
		(net 700)
	)
	(segment
		(start 184.999501 156.0005)
		(end 184.5 156.5)
		(width 0.256)
		(layer "F.Cu")
		(net 701)
	)
	(via
		(at 184.5 156.5)
		(size 0.45)
		(drill 0.1)
		(layers "F.Cu" "B.Cu")
		(remove_unused_layers yes)
		(keep_end_layers yes)
		(zone_layer_connections)
		(net 701)
	)
	(via
		(at 116.435 104.2)
		(size 0.45)
		(drill 0.1)
		(layers "F.Cu" "B.Cu")
		(remove_unused_layers yes)
		(keep_end_layers yes)
		(zone_layer_connections)
		(net 701)
	)
	(segment
		(start 115.705 104.2)
		(end 116.435 104.2)
		(width 0.15)
		(layer "B.Cu")
		(net 701)
	)
	(segment
		(start 157.325 146.5)
		(end 123.825 113)
		(width 0.1)
		(layer "In6.Cu")
		(net 701)
	)
	(segment
		(start 183.75 151)
		(end 175.469669 151)
		(width 0.1)
		(layer "In6.Cu")
		(net 701)
	)
	(segment
		(start 117.5 104.5)
		(end 117.2 104.2)
		(width 0.1)
		(layer "In6.Cu")
		(net 701)
	)
	(segment
		(start 184.5 156.5)
		(end 184.1 156.1)
		(width 0.1)
		(layer "In6.Cu")
		(net 701)
	)
	(segment
		(start 184.1 151.35)
		(end 183.75 151)
		(width 0.1)
		(layer "In6.Cu")
		(net 701)
	)
	(segment
		(start 120 113)
		(end 117.5 110.5)
		(width 0.1)
		(layer "In6.Cu")
		(net 701)
	)
	(segment
		(start 117.2 104.2)
		(end 116.43 104.2)
		(width 0.1)
		(layer "In6.Cu")
		(net 701)
	)
	(segment
		(start 175.469669 151)
		(end 170.969669 146.5)
		(width 0.1)
		(layer "In6.Cu")
		(net 701)
	)
	(segment
		(start 170.969669 146.5)
		(end 157.325 146.5)
		(width 0.1)
		(layer "In6.Cu")
		(net 701)
	)
	(segment
		(start 184.1 156.1)
		(end 184.1 151.35)
		(width 0.1)
		(layer "In6.Cu")
		(net 701)
	)
	(segment
		(start 123.825 113)
		(end 120 113)
		(width 0.1)
		(layer "In6.Cu")
		(net 701)
	)
	(segment
		(start 117.5 110.5)
		(end 117.5 104.5)
		(width 0.1)
		(layer "In6.Cu")
		(net 701)
	)
	(segment
		(start 248.6 142.675)
		(end 249.198499 142.675)
		(width 0.1)
		(layer "F.Cu")
		(net 702)
	)
	(segment
		(start 249.198499 142.675)
		(end 249.223499 142.65)
		(width 0.1)
		(layer "F.Cu")
		(net 702)
	)
	(segment
		(start 201.0005 150.9995)
		(end 201.5 150.5)
		(width 0.256)
		(layer "F.Cu")
		(net 702)
	)
	(via
		(at 248.6 142.675)
		(size 0.45)
		(drill 0.1)
		(layers "F.Cu" "B.Cu")
		(remove_unused_layers yes)
		(keep_end_layers yes)
		(zone_layer_connections)
		(net 702)
	)
	(via
		(at 201.5 150.5)
		(size 0.45)
		(drill 0.1)
		(layers "F.Cu" "B.Cu")
		(remove_unused_layers yes)
		(keep_end_layers yes)
		(zone_layer_connections)
		(net 702)
	)
	(segment
		(start 248.6 142.675)
		(end 247.450001 142.675)
		(width 0.1)
		(layer "In6.Cu")
		(net 702)
	)
	(segment
		(start 202.08 150.5)
		(end 201.5 150.5)
		(width 0.1)
		(layer "In6.Cu")
		(net 702)
	)
	(segment
		(start 247.450001 142.675)
		(end 240.625001 149.5)
		(width 0.1)
		(layer "In6.Cu")
		(net 702)
	)
	(segment
		(start 218.97 149.5)
		(end 217.34 147.87)
		(width 0.1)
		(layer "In6.Cu")
		(net 702)
	)
	(segment
		(start 217.34 147.87)
		(end 204.71 147.87)
		(width 0.1)
		(layer "In6.Cu")
		(net 702)
	)
	(segment
		(start 240.625001 149.5)
		(end 218.97 149.5)
		(width 0.1)
		(layer "In6.Cu")
		(net 702)
	)
	(segment
		(start 204.71 147.87)
		(end 202.08 150.5)
		(width 0.1)
		(layer "In6.Cu")
		(net 702)
	)
	(segment
		(start 188.75 106)
		(end 188.75 104.848)
		(width 0.38)
		(layer "F.Cu")
		(net 703)
	)
	(via
		(at 188.75 104.848)
		(size 0.45)
		(drill 0.1)
		(layers "F.Cu" "B.Cu")
		(remove_unused_layers yes)
		(keep_end_layers yes)
		(zone_layer_connections)
		(net 703)
	)
	(segment
		(start 188.75 105.37)
		(end 188.88 105.5)
		(width 0.198)
		(layer "B.Cu")
		(net 703)
	)
	(segment
		(start 188.75 103.33)
		(end 188.88 103.2)
		(width 0.198)
		(layer "B.Cu")
		(net 703)
	)
	(segment
		(start 188.75 104.848)
		(end 188.75 103.33)
		(width 0.198)
		(layer "B.Cu")
		(net 703)
	)
	(segment
		(start 188.75 104.848)
		(end 188.75 105.37)
		(width 0.198)
		(layer "B.Cu")
		(net 703)
	)
	(segment
		(start 199.5 153.5)
		(end 199.0005 153.0005)
		(width 0.256)
		(layer "F.Cu")
		(net 704)
	)
	(via
		(at 199.5 153.5)
		(size 0.45)
		(drill 0.1)
		(layers "F.Cu" "B.Cu")
		(remove_unused_layers yes)
		(keep_end_layers yes)
		(zone_layer_connections)
		(net 704)
	)
	(via
		(at 187.3 105.5)
		(size 0.45)
		(drill 0.1)
		(layers "F.Cu" "B.Cu")
		(remove_unused_layers yes)
		(keep_end_layers yes)
		(zone_layer_connections)
		(net 704)
	)
	(segment
		(start 187.92 105.5)
		(end 187.3 105.5)
		(width 0.198)
		(layer "B.Cu")
		(net 704)
	)
	(segment
		(start 194.475 147.875)
		(end 194 148.35)
		(width 0.1)
		(layer "In6.Cu")
		(net 704)
	)
	(segment
		(start 199.5 152.3)
		(end 199.5 153.5)
		(width 0.1)
		(layer "In6.Cu")
		(net 704)
	)
	(segment
		(start 194.22 149.98)
		(end 194.67 149.98)
		(width 0.1)
		(layer "In6.Cu")
		(net 704)
	)
	(segment
		(start 195.35 147.025)
		(end 195.075 147.3)
		(width 0.1)
		(layer "In6.Cu")
		(net 704)
	)
	(segment
		(start 187.3 105.25)
		(end 188.85 103.7)
		(width 0.1)
		(layer "In6.Cu")
		(net 704)
	)
	(segment
		(start 195.075 147.3)
		(end 195.075 147.575)
		(width 0.1)
		(layer "In6.Cu")
		(net 704)
	)
	(segment
		(start 194 148.35)
		(end 194 149.76)
		(width 0.1)
		(layer "In6.Cu")
		(net 704)
	)
	(segment
		(start 222.85 103.7)
		(end 225.3 106.15)
		(width 0.1)
		(layer "In6.Cu")
		(net 704)
	)
	(segment
		(start 225.3 108.118)
		(end 224.884 108.534)
		(width 0.1)
		(layer "In6.Cu")
		(net 704)
	)
	(segment
		(start 194.67 149.98)
		(end 194.99 150.3)
		(width 0.1)
		(layer "In6.Cu")
		(net 704)
	)
	(segment
		(start 194.99 150.3)
		(end 194.99 150.75)
		(width 0.1)
		(layer "In6.Cu")
		(net 704)
	)
	(segment
		(start 210.8 141.68)
		(end 207.655 144.825)
		(width 0.1)
		(layer "In6.Cu")
		(net 704)
	)
	(segment
		(start 195.81 150.95)
		(end 196.04 151.18)
		(width 0.1)
		(layer "In6.Cu")
		(net 704)
	)
	(segment
		(start 210.8 138.775)
		(end 210.8 141.68)
		(width 0.1)
		(layer "In6.Cu")
		(net 704)
	)
	(segment
		(start 225.3 106.15)
		(end 225.3 108.118)
		(width 0.1)
		(layer "In6.Cu")
		(net 704)
	)
	(segment
		(start 203.825 144.825)
		(end 201.625 147.025)
		(width 0.1)
		(layer "In6.Cu")
		(net 704)
	)
	(segment
		(start 187.3 105.5)
		(end 187.3 105.25)
		(width 0.1)
		(layer "In6.Cu")
		(net 704)
	)
	(segment
		(start 201.625 147.025)
		(end 195.35 147.025)
		(width 0.1)
		(layer "In6.Cu")
		(net 704)
	)
	(segment
		(start 199.175 151.975)
		(end 199.5 152.3)
		(width 0.1)
		(layer "In6.Cu")
		(net 704)
	)
	(segment
		(start 195.075 147.575)
		(end 194.775 147.875)
		(width 0.1)
		(layer "In6.Cu")
		(net 704)
	)
	(segment
		(start 194.775 147.875)
		(end 194.475 147.875)
		(width 0.1)
		(layer "In6.Cu")
		(net 704)
	)
	(segment
		(start 194 149.76)
		(end 194.22 149.98)
		(width 0.1)
		(layer "In6.Cu")
		(net 704)
	)
	(segment
		(start 224.884 124.691)
		(end 210.8 138.775)
		(width 0.1)
		(layer "In6.Cu")
		(net 704)
	)
	(segment
		(start 195.19 150.95)
		(end 195.81 150.95)
		(width 0.1)
		(layer "In6.Cu")
		(net 704)
	)
	(segment
		(start 207.655 144.825)
		(end 203.825 144.825)
		(width 0.1)
		(layer "In6.Cu")
		(net 704)
	)
	(segment
		(start 188.85 103.7)
		(end 222.85 103.7)
		(width 0.1)
		(layer "In6.Cu")
		(net 704)
	)
	(segment
		(start 196.04 151.71)
		(end 196.305 151.975)
		(width 0.1)
		(layer "In6.Cu")
		(net 704)
	)
	(segment
		(start 196.04 151.18)
		(end 196.04 151.71)
		(width 0.1)
		(layer "In6.Cu")
		(net 704)
	)
	(segment
		(start 224.884 108.534)
		(end 224.884 124.691)
		(width 0.1)
		(layer "In6.Cu")
		(net 704)
	)
	(segment
		(start 194.99 150.75)
		(end 195.19 150.95)
		(width 0.1)
		(layer "In6.Cu")
		(net 704)
	)
	(segment
		(start 196.305 151.975)
		(end 199.175 151.975)
		(width 0.1)
		(layer "In6.Cu")
		(net 704)
	)
	(segment
		(start 206.44 154.94)
		(end 206.22 154.94)
		(width 0.1)
		(layer "F.Cu")
		(net 705)
	)
	(segment
		(start 206.22 154.94)
		(end 205.8 155.36)
		(width 0.201)
		(layer "F.Cu")
		(net 705)
	)
	(segment
		(start 205.8 155.36)
		(end 205.8 155.37)
		(width 0.201)
		(layer "F.Cu")
		(net 705)
	)
	(via
		(at 205.8 155.37)
		(size 0.45)
		(drill 0.1)
		(layers "F.Cu" "B.Cu")
		(remove_unused_layers yes)
		(keep_end_layers yes)
		(zone_layer_connections)
		(net 705)
	)
	(segment
		(start 206.06 155.11)
		(end 206.06 154.935)
		(width 0.182)
		(layer "B.Cu")
		(net 705)
	)
	(segment
		(start 205.8 155.37)
		(end 206.06 155.11)
		(width 0.182)
		(layer "B.Cu")
		(net 705)
	)
	(segment
		(start 206.06 154.935)
		(end 206.325 154.67)
		(width 0.182)
		(layer "B.Cu")
		(net 705)
	)
	(segment
		(start 126.681 166.5925)
		(end 126.681 167.8325)
		(width 0.201)
		(layer "F.Cu")
		(net 707)
	)
	(segment
		(start 128.497 184.053)
		(end 128.996 184.552)
		(width 0.201)
		(layer "F.Cu")
		(net 707)
	)
	(segment
		(start 127.801 184.053)
		(end 128.497 184.053)
		(width 0.201)
		(layer "F.Cu")
		(net 707)
	)
	(via
		(at 128.996 184.552)
		(size 0.45)
		(drill 0.1)
		(layers "F.Cu" "B.Cu")
		(remove_unused_layers yes)
		(keep_end_layers yes)
		(zone_layer_connections)
		(net 707)
	)
	(via
		(at 126.681 167.212)
		(size 0.45)
		(drill 0.1)
		(layers "F.Cu" "B.Cu")
		(remove_unused_layers yes)
		(keep_end_layers yes)
		(zone_layer_connections)
		(net 707)
	)
	(segment
		(start 126.7315 182.2875)
		(end 126.7315 167.2625)
		(width 0.201)
		(layer "B.Cu")
		(net 707)
	)
	(segment
		(start 128.996 184.552)
		(end 126.7315 182.2875)
		(width 0.201)
		(layer "B.Cu")
		(net 707)
	)
	(segment
		(start 126.7315 167.2625)
		(end 126.681 167.212)
		(width 0.201)
		(layer "B.Cu")
		(net 707)
	)
	(segment
		(start 158.73 165.549999)
		(end 158.73 166.124999)
		(width 0.256)
		(layer "F.Cu")
		(net 708)
	)
	(segment
		(start 158.81 165.469999)
		(end 158.73 165.549999)
		(width 0.256)
		(layer "F.Cu")
		(net 708)
	)
	(segment
		(start 158.81 164.614999)
		(end 158.81 165.469999)
		(width 0.256)
		(layer "F.Cu")
		(net 708)
	)
	(segment
		(start 123.056 176.472)
		(end 123.056 175.4175)
		(width 0.201)
		(layer "F.Cu")
		(net 709)
	)
	(segment
		(start 122.576 176.952)
		(end 123.056 176.472)
		(width 0.201)
		(layer "F.Cu")
		(net 709)
	)
	(segment
		(start 122.576 177.828)
		(end 122.576 176.952)
		(width 0.201)
		(layer "F.Cu")
		(net 709)
	)
	(segment
		(start 127.801 179.553)
		(end 128.716 179.553)
		(width 0.201)
		(layer "F.Cu")
		(net 710)
	)
	(segment
		(start 127.681 166.5925)
		(end 127.681 167.8325)
		(width 0.201)
		(layer "F.Cu")
		(net 710)
	)
	(via
		(at 127.681 167.212)
		(size 0.45)
		(drill 0.1)
		(layers "F.Cu" "B.Cu")
		(remove_unused_layers yes)
		(keep_end_layers yes)
		(zone_layer_connections)
		(net 710)
	)
	(via
		(at 128.716 179.553)
		(size 0.45)
		(drill 0.1)
		(layers "F.Cu" "B.Cu")
		(remove_unused_layers yes)
		(keep_end_layers yes)
		(zone_layer_connections)
		(net 710)
	)
	(segment
		(start 128.716 179.553)
		(end 127.806 178.643)
		(width 0.201)
		(layer "B.Cu")
		(net 710)
	)
	(segment
		(start 127.806 178.643)
		(end 127.806 167.952)
		(width 0.201)
		(layer "B.Cu")
		(net 710)
	)
	(segment
		(start 127.681 167.827)
		(end 127.681 167.212)
		(width 0.201)
		(layer "B.Cu")
		(net 710)
	)
	(segment
		(start 127.806 167.952)
		(end 127.681 167.827)
		(width 0.201)
		(layer "B.Cu")
		(net 710)
	)
	(segment
		(start 241.272498 176.247999)
		(end 241.273 176.2485)
		(width 0.256)
		(layer "F.Cu")
		(net 711)
	)
	(segment
		(start 240.700499 176.248)
		(end 241.272498 176.247999)
		(width 0.256)
		(layer "F.Cu")
		(net 711)
	)
	(via
		(at 241.273 176.2485)
		(size 0.45)
		(drill 0.1)
		(layers "F.Cu" "B.Cu")
		(remove_unused_layers yes)
		(keep_end_layers yes)
		(zone_layer_connections)
		(net 711)
	)
	(segment
		(start 241.273 176.2485)
		(end 240.8735 176.2485)
		(width 0.256)
		(layer "B.Cu")
		(net 711)
	)
	(segment
		(start 240.8735 176.2485)
		(end 240.6 175.975)
		(width 0.256)
		(layer "B.Cu")
		(net 711)
	)
	(segment
		(start 254.67 177.4445)
		(end 254.505 177.6095)
		(width 0.182)
		(layer "F.Cu")
		(net 712)
	)
	(segment
		(start 254.67 175.897)
		(end 254.67 176.8095)
		(width 0.182)
		(layer "F.Cu")
		(net 712)
	)
	(segment
		(start 254.67 176.8095)
		(end 254.67 177.4445)
		(width 0.182)
		(layer "F.Cu")
		(net 712)
	)
	(via
		(at 254.67 176.8095)
		(size 0.45)
		(drill 0.1)
		(layers "F.Cu" "B.Cu")
		(remove_unused_layers yes)
		(keep_end_layers yes)
		(zone_layer_connections)
		(net 712)
	)
	(segment
		(start 254.699499 176.838999)
		(end 254.67 176.8095)
		(width 0.256)
		(layer "B.Cu")
		(net 712)
	)
	(segment
		(start 254.699499 177.514)
		(end 254.699499 176.838999)
		(width 0.256)
		(layer "B.Cu")
		(net 712)
	)
	(segment
		(start 254.809499 177.624)
		(end 254.699499 177.514)
		(width 0.256)
		(layer "B.Cu")
		(net 712)
	)
	(segment
		(start 254.02 167.9745)
		(end 254.02 168.6595)
		(width 0.182)
		(layer "F.Cu")
		(net 713)
	)
	(segment
		(start 254.02 169.622)
		(end 254.02 168.6595)
		(width 0.182)
		(layer "F.Cu")
		(net 713)
	)
	(segment
		(start 253.905 167.8595)
		(end 254.02 167.9745)
		(width 0.182)
		(layer "F.Cu")
		(net 713)
	)
	(via
		(at 254.02 168.6595)
		(size 0.45)
		(drill 0.1)
		(layers "F.Cu" "B.Cu")
		(remove_unused_layers yes)
		(keep_end_layers yes)
		(zone_layer_connections)
		(net 713)
	)
	(segment
		(start 253.839499 167.849)
		(end 253.949499 167.959)
		(width 0.256)
		(layer "B.Cu")
		(net 713)
	)
	(segment
		(start 253.949499 168.588999)
		(end 254.02 168.6595)
		(width 0.256)
		(layer "B.Cu")
		(net 713)
	)
	(segment
		(start 253.949499 167.959)
		(end 253.949499 168.588999)
		(width 0.256)
		(layer "B.Cu")
		(net 713)
	)
	(segment
		(start 254.643 160.1185)
		(end 254.5905 160.171)
		(width 0.182)
		(layer "F.Cu")
		(net 714)
	)
	(segment
		(start 254.643 158.446)
		(end 254.643 160.1185)
		(width 0.182)
		(layer "F.Cu")
		(net 714)
	)
	(via
		(at 254.643 159.4085)
		(size 0.45)
		(drill 0.1)
		(layers "F.Cu" "B.Cu")
		(remove_unused_layers yes)
		(keep_end_layers yes)
		(zone_layer_connections)
		(net 714)
	)
	(segment
		(start 254.649499 159.414999)
		(end 254.643 159.4085)
		(width 0.182)
		(layer "B.Cu")
		(net 714)
	)
	(segment
		(start 254.809499 160.174)
		(end 254.674499 160.039)
		(width 0.256)
		(layer "B.Cu")
		(net 714)
	)
	(segment
		(start 254.674499 159.439999)
		(end 254.643 159.4085)
		(width 0.256)
		(layer "B.Cu")
		(net 714)
	)
	(segment
		(start 254.674499 160.039)
		(end 254.674499 159.439999)
		(width 0.256)
		(layer "B.Cu")
		(net 714)
	)
	(segment
		(start 253.993 151.1835)
		(end 254.0055 151.171)
		(width 0.182)
		(layer "F.Cu")
		(net 715)
	)
	(segment
		(start 253.9905 151.156)
		(end 254.0055 151.171)
		(width 0.182)
		(layer "F.Cu")
		(net 715)
	)
	(segment
		(start 253.9905 150.371)
		(end 253.9905 151.156)
		(width 0.182)
		(layer "F.Cu")
		(net 715)
	)
	(segment
		(start 253.993 152.171)
		(end 253.993 151.1835)
		(width 0.182)
		(layer "F.Cu")
		(net 715)
	)
	(via
		(at 254.0055 151.171)
		(size 0.45)
		(drill 0.1)
		(layers "F.Cu" "B.Cu")
		(remove_unused_layers yes)
		(keep_end_layers yes)
		(zone_layer_connections)
		(net 715)
	)
	(segment
		(start 253.924499 151.089999)
		(end 254.0055 151.171)
		(width 0.256)
		(layer "B.Cu")
		(net 715)
	)
	(segment
		(start 253.9905 151.156)
		(end 254.0055 151.171)
		(width 0.182)
		(layer "B.Cu")
		(net 715)
	)
	(segment
		(start 253.814499 150.399)
		(end 253.924499 150.509)
		(width 0.256)
		(layer "B.Cu")
		(net 715)
	)
	(segment
		(start 253.924499 150.509)
		(end 253.924499 151.089999)
		(width 0.256)
		(layer "B.Cu")
		(net 715)
	)
	(segment
		(start 260.55 169.8795)
		(end 259.945 170.4845)
		(width 0.182)
		(layer "F.Cu")
		(net 716)
	)
	(segment
		(start 259.945 170.4845)
		(end 259.645 170.4845)
		(width 0.182)
		(layer "F.Cu")
		(net 716)
	)
	(segment
		(start 258.7825 170.4845)
		(end 259.645 170.4845)
		(width 0.182)
		(layer "F.Cu")
		(net 716)
	)
	(via
		(at 259.645 170.4845)
		(size 0.45)
		(drill 0.1)
		(layers "F.Cu" "B.Cu")
		(remove_unused_layers yes)
		(keep_end_layers yes)
		(zone_layer_connections)
		(net 716)
	)
	(segment
		(start 260.439499 170.474)
		(end 259.6555 170.474)
		(width 0.256)
		(layer "B.Cu")
		(net 716)
	)
	(segment
		(start 259.6555 170.474)
		(end 259.645 170.4845)
		(width 0.256)
		(layer "B.Cu")
		(net 716)
	)
	(segment
		(start 260.549499 170.364)
		(end 260.439499 170.474)
		(width 0.256)
		(layer "B.Cu")
		(net 716)
	)
	(segment
		(start 259.93 175.0345)
		(end 260.52 175.6245)
		(width 0.182)
		(layer "F.Cu")
		(net 717)
	)
	(segment
		(start 258.7825 175.0345)
		(end 259.645 175.0345)
		(width 0.182)
		(layer "F.Cu")
		(net 717)
	)
	(segment
		(start 259.645 175.0345)
		(end 259.93 175.0345)
		(width 0.182)
		(layer "F.Cu")
		(net 717)
	)
	(via
		(at 259.645 175.0345)
		(size 0.45)
		(drill 0.1)
		(layers "F.Cu" "B.Cu")
		(remove_unused_layers yes)
		(keep_end_layers yes)
		(zone_layer_connections)
		(net 717)
	)
	(segment
		(start 259.645 175.0345)
		(end 259.969999 175.0345)
		(width 0.182)
		(layer "B.Cu")
		(net 717)
	)
	(segment
		(start 259.969999 175.0345)
		(end 260.549499 175.614)
		(width 0.182)
		(layer "B.Cu")
		(net 717)
	)
	(segment
		(start 259.878 153.0335)
		(end 260.5055 152.406)
		(width 0.182)
		(layer "F.Cu")
		(net 718)
	)
	(segment
		(start 259.668 153.0335)
		(end 259.878 153.0335)
		(width 0.182)
		(layer "F.Cu")
		(net 718)
	)
	(segment
		(start 258.7555 153.0335)
		(end 259.668 153.0335)
		(width 0.182)
		(layer "F.Cu")
		(net 718)
	)
	(via
		(at 259.668 153.0335)
		(size 0.45)
		(drill 0.1)
		(layers "F.Cu" "B.Cu")
		(remove_unused_layers yes)
		(keep_end_layers yes)
		(zone_layer_connections)
		(net 718)
	)
	(segment
		(start 260.339499 152.974)
		(end 259.7275 152.974)
		(width 0.256)
		(layer "B.Cu")
		(net 718)
	)
	(segment
		(start 260.499499 152.814)
		(end 260.339499 152.974)
		(width 0.256)
		(layer "B.Cu")
		(net 718)
	)
	(segment
		(start 259.7275 152.974)
		(end 259.668 153.0335)
		(width 0.256)
		(layer "B.Cu")
		(net 718)
	)
	(segment
		(start 259.418 157.5835)
		(end 259.7555 157.921)
		(width 0.182)
		(layer "F.Cu")
		(net 719)
	)
	(segment
		(start 258.7555 157.5835)
		(end 259.418 157.5835)
		(width 0.182)
		(layer "F.Cu")
		(net 719)
	)
	(segment
		(start 260.5055 158.186)
		(end 260.0205 158.186)
		(width 0.182)
		(layer "F.Cu")
		(net 719)
	)
	(segment
		(start 260.0205 158.186)
		(end 259.7555 157.921)
		(width 0.182)
		(layer "F.Cu")
		(net 719)
	)
	(via
		(at 259.7555 157.921)
		(size 0.45)
		(drill 0.1)
		(layers "F.Cu" "B.Cu")
		(remove_unused_layers yes)
		(keep_end_layers yes)
		(zone_layer_connections)
		(net 719)
	)
	(segment
		(start 259.7555 157.921)
		(end 260.0085 158.174)
		(width 0.182)
		(layer "B.Cu")
		(net 719)
	)
	(segment
		(start 260.4935 158.174)
		(end 260.5055 158.186)
		(width 0.182)
		(layer "B.Cu")
		(net 719)
	)
	(segment
		(start 260.0085 158.174)
		(end 260.4935 158.174)
		(width 0.182)
		(layer "B.Cu")
		(net 719)
	)
	(segment
		(start 240.024499 157.344499)
		(end 240.023998 157.345001)
		(width 0.256)
		(layer "F.Cu")
		(net 720)
	)
	(segment
		(start 240.024498 156.7725)
		(end 240.024499 157.344499)
		(width 0.256)
		(layer "F.Cu")
		(net 720)
	)
	(via
		(at 240.023998 157.345001)
		(size 0.45)
		(drill 0.1)
		(layers "F.Cu" "B.Cu")
		(remove_unused_layers yes)
		(keep_end_layers yes)
		(zone_layer_connections)
		(net 720)
	)
	(segment
		(start 240.454999 157.345001)
		(end 240.675 157.125)
		(width 0.198)
		(layer "B.Cu")
		(net 720)
	)
	(segment
		(start 240.023998 157.345001)
		(end 240.454999 157.345001)
		(width 0.198)
		(layer "B.Cu")
		(net 720)
	)
	(via
		(at 216.300001 183.045001)
		(size 0.45)
		(drill 0.1)
		(layers "F.Cu" "B.Cu")
		(remove_unused_layers yes)
		(keep_end_layers yes)
		(zone_layer_connections)
		(net 721)
	)
	(via
		(at 224.37 183.755)
		(size 0.45)
		(drill 0.1)
		(layers "F.Cu" "B.Cu")
		(remove_unused_layers yes)
		(keep_end_layers yes)
		(zone_layer_connections)
		(net 721)
	)
	(segment
		(start 224.37 183.755)
		(end 224.84 183.755)
		(width 0.4)
		(layer "B.Cu")
		(net 721)
	)
	(segment
		(start 216.300001 183.045001)
		(end 215.340001 183.045001)
		(width 0.114)
		(layer "B.Cu")
		(net 721)
	)
	(segment
		(start 215.340001 183.045001)
		(end 215.1 182.805)
		(width 0.114)
		(layer "B.Cu")
		(net 721)
	)
	(segment
		(start 220.692641 183.045001)
		(end 216.300001 183.045001)
		(width 0.114)
		(layer "In2.Cu")
		(net 721)
	)
	(segment
		(start 224.37 183.755)
		(end 223.798 184.327)
		(width 0.114)
		(layer "In2.Cu")
		(net 721)
	)
	(segment
		(start 223.798 184.327)
		(end 221.97464 184.327)
		(width 0.114)
		(layer "In2.Cu")
		(net 721)
	)
	(segment
		(start 221.97464 184.327)
		(end 220.692641 183.045001)
		(width 0.114)
		(layer "In2.Cu")
		(net 721)
	)
	(segment
		(start 226.545001 183.440001)
		(end 227.590001 183.440001)
		(width 0.114)
		(layer "F.Cu")
		(net 722)
	)
	(via
		(at 226.545001 183.440001)
		(size 0.45)
		(drill 0.1)
		(layers "F.Cu" "B.Cu")
		(remove_unused_layers yes)
		(keep_end_layers yes)
		(zone_layer_connections)
		(net 722)
	)
	(segment
		(start 226.114999 183.440001)
		(end 225.8 183.755)
		(width 0.114)
		(layer "B.Cu")
		(net 722)
	)
	(segment
		(start 226.545001 183.440001)
		(end 226.114999 183.440001)
		(width 0.114)
		(layer "B.Cu")
		(net 722)
	)
	(via
		(at 226.995001 183.040001)
		(size 0.45)
		(drill 0.1)
		(layers "F.Cu" "B.Cu")
		(remove_unused_layers yes)
		(keep_end_layers yes)
		(zone_layer_connections)
		(net 723)
	)
	(segment
		(start 226.075001 183.040001)
		(end 225.8 182.765)
		(width 0.114)
		(layer "B.Cu")
		(net 723)
	)
	(segment
		(start 226.995001 183.040001)
		(end 226.075001 183.040001)
		(width 0.114)
		(layer "B.Cu")
		(net 723)
	)
	(segment
		(start 215.850001 183.445001)
		(end 216.895001 183.445001)
		(width 0.114)
		(layer "F.Cu")
		(net 724)
	)
	(via
		(at 224.37 182.765)
		(size 0.45)
		(drill 0.1)
		(layers "F.Cu" "B.Cu")
		(remove_unused_layers yes)
		(keep_end_layers yes)
		(zone_layer_connections)
		(net 724)
	)
	(via
		(at 215.850001 183.445001)
		(size 0.45)
		(drill 0.1)
		(layers "F.Cu" "B.Cu")
		(remove_unused_layers yes)
		(keep_end_layers yes)
		(zone_layer_connections)
		(net 724)
	)
	(segment
		(start 215.850001 183.445001)
		(end 215.419999 183.445001)
		(width 0.114)
		(layer "B.Cu")
		(net 724)
	)
	(segment
		(start 215.419999 183.445001)
		(end 215.1 183.765)
		(width 0.114)
		(layer "B.Cu")
		(net 724)
	)
	(segment
		(start 215.1 183.765)
		(end 215.1 184.755)
		(width 0.114)
		(layer "B.Cu")
		(net 724)
	)
	(segment
		(start 224.37 182.765)
		(end 224.84 182.765)
		(width 0.4)
		(layer "B.Cu")
		(net 724)
	)
	(segment
		(start 224.37 182.765)
		(end 224.752 183.147)
		(width 0.1)
		(layer "In2.Cu")
		(net 724)
	)
	(segment
		(start 220.535499 183.8625)
		(end 221.3 184.627001)
		(width 0.1)
		(layer "In2.Cu")
		(net 724)
	)
	(segment
		(start 224.752 183.147)
		(end 224.752 183.971001)
		(width 0.1)
		(layer "In2.Cu")
		(net 724)
	)
	(segment
		(start 224.096 184.627001)
		(end 221.3 184.627001)
		(width 0.1)
		(layer "In2.Cu")
		(net 724)
	)
	(segment
		(start 217.4625 183.8625)
		(end 220.535499 183.8625)
		(width 0.1)
		(layer "In2.Cu")
		(net 724)
	)
	(segment
		(start 224.752 183.971001)
		(end 224.096 184.627001)
		(width 0.1)
		(layer "In2.Cu")
		(net 724)
	)
	(segment
		(start 217.4625 183.8625)
		(end 217.045001 183.445001)
		(width 0.1)
		(layer "In2.Cu")
		(net 724)
	)
	(segment
		(start 217.045001 183.445001)
		(end 215.850001 183.445001)
		(width 0.1)
		(layer "In2.Cu")
		(net 724)
	)
	(segment
		(start 222.640001 182.645)
		(end 221.595001 182.645001)
		(width 0.114)
		(layer "F.Cu")
		(net 725)
	)
	(via
		(at 222.640001 182.645)
		(size 0.45)
		(drill 0.1)
		(layers "F.Cu" "B.Cu")
		(remove_unused_layers yes)
		(keep_end_layers yes)
		(zone_layer_connections)
		(net 725)
	)
	(segment
		(start 222.640001 182.645)
		(end 221.86 182.645)
		(width 0.15)
		(layer "B.Cu")
		(net 725)
	)
	(segment
		(start 221.86 182.645)
		(end 221.51 182.995)
		(width 0.15)
		(layer "B.Cu")
		(net 725)
	)
	(segment
		(start 233.335001 182.640001)
		(end 232.290001 182.640002)
		(width 0.114)
		(layer "F.Cu")
		(net 726)
	)
	(via
		(at 233.335001 182.640001)
		(size 0.45)
		(drill 0.1)
		(layers "F.Cu" "B.Cu")
		(remove_unused_layers yes)
		(keep_end_layers yes)
		(zone_layer_connections)
		(net 726)
	)
	(segment
		(start 233.335001 182.640001)
		(end 232.569999 182.640001)
		(width 0.15)
		(layer "B.Cu")
		(net 726)
	)
	(segment
		(start 232.569999 182.640001)
		(end 232.215 182.995)
		(width 0.15)
		(layer "B.Cu")
		(net 726)
	)
	(segment
		(start 222.640002 183.445)
		(end 221.595001 183.445)
		(width 0.114)
		(layer "F.Cu")
		(net 727)
	)
	(via
		(at 222.640002 183.445)
		(size 0.45)
		(drill 0.1)
		(layers "F.Cu" "B.Cu")
		(remove_unused_layers yes)
		(keep_end_layers yes)
		(zone_layer_connections)
		(net 727)
	)
	(segment
		(start 222.609502 183.4755)
		(end 222.0045 183.4755)
		(width 0.201)
		(layer "B.Cu")
		(net 727)
	)
	(segment
		(start 222.640002 183.445)
		(end 222.609502 183.4755)
		(width 0.201)
		(layer "B.Cu")
		(net 727)
	)
	(segment
		(start 222.0045 183.4755)
		(end 221.51 183.97)
		(width 0.201)
		(layer "B.Cu")
		(net 727)
	)
	(segment
		(start 233.335002 183.440001)
		(end 232.290001 183.440001)
		(width 0.114)
		(layer "F.Cu")
		(net 728)
	)
	(via
		(at 233.335002 183.440001)
		(size 0.45)
		(drill 0.1)
		(layers "F.Cu" "B.Cu")
		(remove_unused_layers yes)
		(keep_end_layers yes)
		(zone_layer_connections)
		(net 728)
	)
	(segment
		(start 232.685 183.45)
		(end 232.165 183.97)
		(width 0.15)
		(layer "B.Cu")
		(net 728)
	)
	(segment
		(start 233.335002 183.440001)
		(end 233.325003 183.45)
		(width 0.15)
		(layer "B.Cu")
		(net 728)
	)
	(segment
		(start 233.325003 183.45)
		(end 232.685 183.45)
		(width 0.15)
		(layer "B.Cu")
		(net 728)
	)
	(segment
		(start 240.700499 176.748)
		(end 241.597498 176.748)
		(width 0.256)
		(layer "F.Cu")
		(net 729)
	)
	(segment
		(start 241.597498 176.748)
		(end 241.597999 176.748501)
		(width 0.256)
		(layer "F.Cu")
		(net 729)
	)
	(via
		(at 241.597999 176.748501)
		(size 0.45)
		(drill 0.1)
		(layers "F.Cu" "B.Cu")
		(remove_unused_layers yes)
		(keep_end_layers yes)
		(zone_layer_connections)
		(net 729)
	)
	(segment
		(start 241.597999 176.748501)
		(end 240.826499 176.748501)
		(width 0.256)
		(layer "B.Cu")
		(net 729)
	)
	(segment
		(start 240.826499 176.748501)
		(end 240.6 176.975)
		(width 0.256)
		(layer "B.Cu")
		(net 729)
	)
	(segment
		(start 236.9165 155.5585)
		(end 236.915999 155.557999)
		(width 0.256)
		(layer "F.Cu")
		(net 730)
	)
	(segment
		(start 237.813499 155.5585)
		(end 236.9165 155.5585)
		(width 0.256)
		(layer "F.Cu")
		(net 730)
	)
	(via
		(at 236.915999 155.557999)
		(size 0.45)
		(drill 0.1)
		(layers "F.Cu" "B.Cu")
		(remove_unused_layers yes)
		(keep_end_layers yes)
		(zone_layer_connections)
		(net 730)
	)
	(segment
		(start 236.364001 155.557999)
		(end 236.22 155.702)
		(width 0.256)
		(layer "B.Cu")
		(net 730)
	)
	(segment
		(start 236.915999 155.557999)
		(end 236.364001 155.557999)
		(width 0.256)
		(layer "B.Cu")
		(net 730)
	)
	(segment
		(start 241.272498 170.697999)
		(end 241.273 170.6985)
		(width 0.256)
		(layer "F.Cu")
		(net 731)
	)
	(segment
		(start 240.700499 170.698)
		(end 241.272498 170.697999)
		(width 0.256)
		(layer "F.Cu")
		(net 731)
	)
	(via
		(at 241.273 170.6985)
		(size 0.45)
		(drill 0.1)
		(layers "F.Cu" "B.Cu")
		(remove_unused_layers yes)
		(keep_end_layers yes)
		(zone_layer_connections)
		(net 731)
	)
	(segment
		(start 241.273 170.6985)
		(end 240.8735 170.6985)
		(width 0.256)
		(layer "B.Cu")
		(net 731)
	)
	(segment
		(start 240.8735 170.6985)
		(end 240.6 170.425)
		(width 0.256)
		(layer "B.Cu")
		(net 731)
	)
	(segment
		(start 238.527499 157.669499)
		(end 238.526998 157.67)
		(width 0.256)
		(layer "F.Cu")
		(net 732)
	)
	(segment
		(start 238.527499 156.7725)
		(end 238.527499 157.669499)
		(width 0.256)
		(layer "F.Cu")
		(net 732)
	)
	(via
		(at 238.526998 157.67)
		(size 0.45)
		(drill 0.1)
		(layers "F.Cu" "B.Cu")
		(remove_unused_layers yes)
		(keep_end_layers yes)
		(zone_layer_connections)
		(net 732)
	)
	(segment
		(start 238.47 157.67)
		(end 237.925 157.125)
		(width 0.256)
		(layer "B.Cu")
		(net 732)
	)
	(segment
		(start 238.526998 157.67)
		(end 238.47 157.67)
		(width 0.256)
		(layer "B.Cu")
		(net 732)
	)
	(segment
		(start 238.527499 153.275501)
		(end 238.528 153.275)
		(width 0.256)
		(layer "F.Cu")
		(net 733)
	)
	(segment
		(start 238.527499 153.8475)
		(end 238.527499 153.275501)
		(width 0.256)
		(layer "F.Cu")
		(net 733)
	)
	(via
		(at 238.528 153.275)
		(size 0.45)
		(drill 0.1)
		(layers "F.Cu" "B.Cu")
		(remove_unused_layers yes)
		(keep_end_layers yes)
		(zone_layer_connections)
		(net 733)
	)
	(segment
		(start 238.4 153.275)
		(end 237.925 153.75)
		(width 0.256)
		(layer "B.Cu")
		(net 733)
	)
	(segment
		(start 238.528 153.275)
		(end 238.4 153.275)
		(width 0.256)
		(layer "B.Cu")
		(net 733)
	)
	(segment
		(start 237.2415 155.0615)
		(end 237.240998 155.060999)
		(width 0.256)
		(layer "F.Cu")
		(net 734)
	)
	(segment
		(start 237.813499 155.061499)
		(end 237.2415 155.0615)
		(width 0.256)
		(layer "F.Cu")
		(net 734)
	)
	(via
		(at 237.240998 155.060999)
		(size 0.45)
		(drill 0.1)
		(layers "F.Cu" "B.Cu")
		(remove_unused_layers yes)
		(keep_end_layers yes)
		(zone_layer_connections)
		(net 734)
	)
	(segment
		(start 237.240998 155.060999)
		(end 236.538999 155.060999)
		(width 0.256)
		(layer "B.Cu")
		(net 734)
	)
	(segment
		(start 236.538999 155.060999)
		(end 236.22 154.742)
		(width 0.256)
		(layer "B.Cu")
		(net 734)
	)
	(segment
		(start 240.700499 171.198)
		(end 241.597498 171.198)
		(width 0.256)
		(layer "F.Cu")
		(net 735)
	)
	(segment
		(start 241.597498 171.198)
		(end 241.597999 171.198501)
		(width 0.256)
		(layer "F.Cu")
		(net 735)
	)
	(via
		(at 241.597999 171.198501)
		(size 0.45)
		(drill 0.1)
		(layers "F.Cu" "B.Cu")
		(remove_unused_layers yes)
		(keep_end_layers yes)
		(zone_layer_connections)
		(net 735)
	)
	(segment
		(start 241.597999 171.198501)
		(end 240.826499 171.198501)
		(width 0.256)
		(layer "B.Cu")
		(net 735)
	)
	(segment
		(start 240.826499 171.198501)
		(end 240.6 171.425)
		(width 0.256)
		(layer "B.Cu")
		(net 735)
	)
	(segment
		(start 123.576 177.232)
		(end 124.156 176.652)
		(width 0.201)
		(layer "F.Cu")
		(net 736)
	)
	(segment
		(start 125.681 166.5925)
		(end 125.681 167.8325)
		(width 0.201)
		(layer "F.Cu")
		(net 736)
	)
	(segment
		(start 124.156 173.852)
		(end 125.656 172.352)
		(width 0.201)
		(layer "F.Cu")
		(net 736)
	)
	(segment
		(start 124.156 176.652)
		(end 124.156 173.852)
		(width 0.201)
		(layer "F.Cu")
		(net 736)
	)
	(segment
		(start 125.656 172.352)
		(end 125.681 172.352)
		(width 0.201)
		(layer "F.Cu")
		(net 736)
	)
	(segment
		(start 123.576 177.828)
		(end 123.576 177.232)
		(width 0.201)
		(layer "F.Cu")
		(net 736)
	)
	(via
		(at 125.681 172.352)
		(size 0.45)
		(drill 0.1)
		(layers "F.Cu" "B.Cu")
		(remove_unused_layers yes)
		(keep_end_layers yes)
		(zone_layer_connections)
		(net 736)
	)
	(via
		(at 125.681 167.212)
		(size 0.45)
		(drill 0.1)
		(layers "F.Cu" "B.Cu")
		(remove_unused_layers yes)
		(keep_end_layers yes)
		(zone_layer_connections)
		(net 736)
	)
	(segment
		(start 125.681 167.212)
		(end 125.681 172.352)
		(width 0.201)
		(layer "B.Cu")
		(net 736)
	)
	(segment
		(start 123.706 173.327)
		(end 124.681 172.352)
		(width 0.201)
		(layer "F.Cu")
		(net 737)
	)
	(segment
		(start 124.681 166.5925)
		(end 124.681 167.8325)
		(width 0.201)
		(layer "F.Cu")
		(net 737)
	)
	(segment
		(start 123.706 176.502)
		(end 123.706 173.327)
		(width 0.201)
		(layer "F.Cu")
		(net 737)
	)
	(segment
		(start 123.076 177.828)
		(end 123.076 177.132)
		(width 0.201)
		(layer "F.Cu")
		(net 737)
	)
	(segment
		(start 123.076 177.132)
		(end 123.706 176.502)
		(width 0.201)
		(layer "F.Cu")
		(net 737)
	)
	(via
		(at 124.681 172.352)
		(size 0.45)
		(drill 0.1)
		(layers "F.Cu" "B.Cu")
		(remove_unused_layers yes)
		(keep_end_layers yes)
		(zone_layer_connections)
		(net 737)
	)
	(via
		(at 124.681 167.212)
		(size 0.45)
		(drill 0.1)
		(layers "F.Cu" "B.Cu")
		(remove_unused_layers yes)
		(keep_end_layers yes)
		(zone_layer_connections)
		(net 737)
	)
	(segment
		(start 124.681 167.212)
		(end 124.681 172.352)
		(width 0.201)
		(layer "B.Cu")
		(net 737)
	)
	(segment
		(start 120.851 179.553)
		(end 120.006 179.553)
		(width 0.201)
		(layer "F.Cu")
		(net 738)
	)
	(segment
		(start 121.681 166.5925)
		(end 121.681 167.8325)
		(width 0.201)
		(layer "F.Cu")
		(net 738)
	)
	(via
		(at 120.006 179.553)
		(size 0.45)
		(drill 0.1)
		(layers "F.Cu" "B.Cu")
		(remove_unused_layers yes)
		(keep_end_layers yes)
		(zone_layer_connections)
		(net 738)
	)
	(via
		(at 121.681 167.212)
		(size 0.45)
		(drill 0.1)
		(layers "F.Cu" "B.Cu")
		(remove_unused_layers yes)
		(keep_end_layers yes)
		(zone_layer_connections)
		(net 738)
	)
	(segment
		(start 120.55 179.009)
		(end 120.006 179.553)
		(width 0.201)
		(layer "B.Cu")
		(net 738)
	)
	(segment
		(start 121.95 167.481)
		(end 121.95 170.15)
		(width 0.201)
		(layer "B.Cu")
		(net 738)
	)
	(segment
		(start 121.95 170.15)
		(end 120.55 171.55)
		(width 0.201)
		(layer "B.Cu")
		(net 738)
	)
	(segment
		(start 121.681 167.212)
		(end 121.95 167.481)
		(width 0.201)
		(layer "B.Cu")
		(net 738)
	)
	(segment
		(start 120.55 171.55)
		(end 120.55 179.009)
		(width 0.201)
		(layer "B.Cu")
		(net 738)
	)
	(segment
		(start 123.681 166.5925)
		(end 123.681 167.8325)
		(width 0.201)
		(layer "F.Cu")
		(net 739)
	)
	(segment
		(start 120.851 184.053)
		(end 120.185 184.053)
		(width 0.201)
		(layer "F.Cu")
		(net 739)
	)
	(segment
		(start 120.185 184.053)
		(end 119.686 184.552)
		(width 0.201)
		(layer "F.Cu")
		(net 739)
	)
	(via
		(at 119.686 184.552)
		(size 0.45)
		(drill 0.1)
		(layers "F.Cu" "B.Cu")
		(remove_unused_layers yes)
		(keep_end_layers yes)
		(zone_layer_connections)
		(net 739)
	)
	(via
		(at 123.681 167.212)
		(size 0.45)
		(drill 0.1)
		(layers "F.Cu" "B.Cu")
		(remove_unused_layers yes)
		(keep_end_layers yes)
		(zone_layer_connections)
		(net 739)
	)
	(segment
		(start 122.226 178.142)
		(end 122.226 183.022)
		(width 0.201)
		(layer "B.Cu")
		(net 739)
	)
	(segment
		(start 123.681 176.687)
		(end 122.226 178.142)
		(width 0.201)
		(layer "B.Cu")
		(net 739)
	)
	(segment
		(start 123.646 184.442)
		(end 123.646 185.723748)
		(width 0.201)
		(layer "B.Cu")
		(net 739)
	)
	(segment
		(start 123.681 167.212)
		(end 123.681 176.687)
		(width 0.201)
		(layer "B.Cu")
		(net 739)
	)
	(segment
		(start 120.536 185.402)
		(end 119.686 184.552)
		(width 0.201)
		(layer "B.Cu")
		(net 739)
	)
	(segment
		(start 122.077748 187.292)
		(end 120.876 187.292)
		(width 0.201)
		(layer "B.Cu")
		(net 739)
	)
	(segment
		(start 120.536 186.952)
		(end 120.536 185.402)
		(width 0.201)
		(layer "B.Cu")
		(net 739)
	)
	(segment
		(start 122.226 183.022)
		(end 123.646 184.442)
		(width 0.201)
		(layer "B.Cu")
		(net 739)
	)
	(segment
		(start 123.646 185.723748)
		(end 122.077748 187.292)
		(width 0.201)
		(layer "B.Cu")
		(net 739)
	)
	(segment
		(start 120.876 187.292)
		(end 120.536 186.952)
		(width 0.201)
		(layer "B.Cu")
		(net 739)
	)
	(segment
		(start 122.681 166.5925)
		(end 122.681 167.8325)
		(width 0.201)
		(layer "F.Cu")
		(net 740)
	)
	(segment
		(start 123.076 184.778)
		(end 123.076 185.692)
		(width 0.201)
		(layer "F.Cu")
		(net 740)
	)
	(via
		(at 123.076 185.692)
		(size 0.45)
		(drill 0.1)
		(layers "F.Cu" "B.Cu")
		(remove_unused_layers yes)
		(keep_end_layers yes)
		(zone_layer_connections)
		(net 740)
	)
	(via
		(at 122.681 167.212)
		(size 0.45)
		(drill 0.1)
		(layers "F.Cu" "B.Cu")
		(remove_unused_layers yes)
		(keep_end_layers yes)
		(zone_layer_connections)
		(net 740)
	)
	(segment
		(start 121.5115 172.3965)
		(end 122.681 171.227)
		(width 0.201)
		(layer "B.Cu")
		(net 740)
	)
	(segment
		(start 121.5115 180.2575)
		(end 121.5115 172.3965)
		(width 0.201)
		(layer "B.Cu")
		(net 740)
	)
	(segment
		(start 121.756 183.202)
		(end 121.756 180.502)
		(width 0.201)
		(layer "B.Cu")
		(net 740)
	)
	(segment
		(start 123.076 184.522)
		(end 121.756 183.202)
		(width 0.201)
		(layer "B.Cu")
		(net 740)
	)
	(segment
		(start 122.681 171.227)
		(end 122.681 167.212)
		(width 0.201)
		(layer "B.Cu")
		(net 740)
	)
	(segment
		(start 123.076 185.692)
		(end 123.076 184.522)
		(width 0.201)
		(layer "B.Cu")
		(net 740)
	)
	(segment
		(start 121.756 180.502)
		(end 121.5115 180.2575)
		(width 0.201)
		(layer "B.Cu")
		(net 740)
	)
	(segment
		(start 215.850001 181.845001)
		(end 216.895001 181.845001)
		(width 0.114)
		(layer "F.Cu")
		(net 741)
	)
	(via
		(at 215.850001 181.845001)
		(size 0.45)
		(drill 0.1)
		(layers "F.Cu" "B.Cu")
		(remove_unused_layers yes)
		(keep_end_layers yes)
		(zone_layer_connections)
		(net 741)
	)
	(segment
		(start 215 180.65)
		(end 215 180.875136)
		(width 0.15)
		(layer "B.Cu")
		(net 741)
	)
	(segment
		(start 215 180.875136)
		(end 215.850001 181.725137)
		(width 0.15)
		(layer "B.Cu")
		(net 741)
	)
	(segment
		(start 215.850001 181.725137)
		(end 215.850001 181.845001)
		(width 0.15)
		(layer "B.Cu")
		(net 741)
	)
	(segment
		(start 226.995001 183.940001)
		(end 227.590001 183.940001)
		(width 0.114)
		(layer "F.Cu")
		(net 742)
	)
	(segment
		(start 216.300001 183.945001)
		(end 216.895001 183.945001)
		(width 0.114)
		(layer "F.Cu")
		(net 742)
	)
	(via
		(at 216.300001 183.945001)
		(size 0.45)
		(drill 0.1)
		(layers "F.Cu" "B.Cu")
		(remove_unused_layers yes)
		(keep_end_layers yes)
		(zone_layer_connections)
		(net 742)
	)
	(via
		(at 226.995001 183.940001)
		(size 0.45)
		(drill 0.1)
		(layers "F.Cu" "B.Cu")
		(remove_unused_layers yes)
		(keep_end_layers yes)
		(zone_layer_connections)
		(net 742)
	)
	(segment
		(start 226.050002 184.885)
		(end 220.875 184.885)
		(width 0.1)
		(layer "In2.Cu")
		(net 742)
	)
	(segment
		(start 226.995001 183.940001)
		(end 226.050002 184.885)
		(width 0.1)
		(layer "In2.Cu")
		(net 742)
	)
	(segment
		(start 220.59 184.6)
		(end 220.875 184.885)
		(width 0.1)
		(layer "In2.Cu")
		(net 742)
	)
	(segment
		(start 217.675 184.6)
		(end 217.020001 183.945001)
		(width 0.1)
		(layer "In2.Cu")
		(net 742)
	)
	(segment
		(start 217.675 184.6)
		(end 220.59 184.6)
		(width 0.1)
		(layer "In2.Cu")
		(net 742)
	)
	(segment
		(start 217.020001 183.945001)
		(end 216.300001 183.945001)
		(width 0.1)
		(layer "In2.Cu")
		(net 742)
	)
	(via
		(at 222.215 183.05)
		(size 0.45)
		(drill 0.1)
		(layers "F.Cu" "B.Cu")
		(remove_unused_layers yes)
		(keep_end_layers yes)
		(zone_layer_connections)
		(net 743)
	)
	(via
		(at 232.905 183.05)
		(size 0.45)
		(drill 0.1)
		(layers "F.Cu" "B.Cu")
		(remove_unused_layers yes)
		(keep_end_layers yes)
		(zone_layer_connections)
		(net 743)
	)
	(segment
		(start 232.145 183.81)
		(end 228.765 183.81)
		(width 0.1)
		(layer "In6.Cu")
		(net 743)
	)
	(segment
		(start 222.825332 183.05)
		(end 222.215 183.05)
		(width 0.1)
		(layer "In6.Cu")
		(net 743)
	)
	(segment
		(start 228.135 184.44)
		(end 224.215332 184.44)
		(width 0.1)
		(layer "In6.Cu")
		(net 743)
	)
	(segment
		(start 224.215332 184.44)
		(end 222.825332 183.05)
		(width 0.1)
		(layer "In6.Cu")
		(net 743)
	)
	(segment
		(start 228.765 183.81)
		(end 228.135 184.44)
		(width 0.1)
		(layer "In6.Cu")
		(net 743)
	)
	(segment
		(start 232.905 183.05)
		(end 232.145 183.81)
		(width 0.1)
		(layer "In6.Cu")
		(net 743)
	)
	(segment
		(start 239.524499 156.7725)
		(end 239.524499 157.669499)
		(width 0.256)
		(layer "F.Cu")
		(net 745)
	)
	(segment
		(start 239.524499 157.669499)
		(end 239.523998 157.67)
		(width 0.256)
		(layer "F.Cu")
		(net 745)
	)
	(via
		(at 239.523998 157.67)
		(size 0.45)
		(drill 0.1)
		(layers "F.Cu" "B.Cu")
		(remove_unused_layers yes)
		(keep_end_layers yes)
		(zone_layer_connections)
		(net 745)
	)
	(segment
		(start 208.14 153.94)
		(end 208.64 153.94)
		(width 0.15)
		(layer "F.Cu")
		(net 746)
	)
	(segment
		(start 208.64 153.94)
		(end 208.7 154)
		(width 0.15)
		(layer "F.Cu")
		(net 746)
	)
	(segment
		(start 208.952598 154.180959)
		(end 208.966 154.167557)
		(width 0.15)
		(layer "F.Cu")
		(net 746)
	)
	(segment
		(start 208.771639 154)
		(end 208.952598 154.180959)
		(width 0.15)
		(layer "F.Cu")
		(net 746)
	)
	(segment
		(start 208.966 154.167557)
		(end 208.966 150.459)
		(width 0.15)
		(layer "F.Cu")
		(net 746)
	)
	(segment
		(start 194.0005 154.0005)
		(end 194.5 154.5)
		(width 0.256)
		(layer "F.Cu")
		(net 746)
	)
	(segment
		(start 208.966 150.459)
		(end 210.066071 149.358929)
		(width 0.15)
		(layer "F.Cu")
		(net 746)
	)
	(segment
		(start 208.7 154)
		(end 208.771639 154)
		(width 0.15)
		(layer "F.Cu")
		(net 746)
	)
	(segment
		(start 237.135499 186.255)
		(end 237.129499 186.261)
		(width 0.177)
		(layer "F.Cu")
		(net 746)
	)
	(segment
		(start 210.066071 149.358929)
		(end 210.806349 149.358929)
		(width 0.15)
		(layer "F.Cu")
		(net 746)
	)
	(segment
		(start 237.902499 186.255)
		(end 237.135499 186.255)
		(width 0.177)
		(layer "F.Cu")
		(net 746)
	)
	(via
		(at 237.129499 186.261)
		(size 0.45)
		(drill 0.1)
		(layers "F.Cu" "B.Cu")
		(remove_unused_layers yes)
		(keep_end_layers yes)
		(zone_layer_connections)
		(net 746)
	)
	(via
		(at 208.952598 154.180959)
		(size 0.45)
		(drill 0.1)
		(layers "F.Cu" "B.Cu")
		(remove_unused_layers yes)
		(keep_end_layers yes)
		(zone_layer_connections)
		(net 746)
	)
	(via
		(at 210.806349 149.358929)
		(size 0.45)
		(drill 0.1)
		(layers "F.Cu" "B.Cu")
		(remove_unused_layers yes)
		(keep_end_layers yes)
		(zone_layer_connections)
		(net 746)
	)
	(via
		(at 194.5 154.5)
		(size 0.45)
		(drill 0.1)
		(layers "F.Cu" "B.Cu")
		(remove_unused_layers yes)
		(keep_end_layers yes)
		(zone_layer_connections)
		(net 746)
	)
	(segment
		(start 237.541499 185.849)
		(end 237.129499 186.261)
		(width 0.177)
		(layer "B.Cu")
		(net 746)
	)
	(segment
		(start 237.939499 186.849)
		(end 237.939499 185.849)
		(width 0.15)
		(layer "B.Cu")
		(net 746)
	)
	(segment
		(start 237.939499 185.849)
		(end 237.541499 185.849)
		(width 0.177)
		(layer "B.Cu")
		(net 746)
	)
	(segment
		(start 235.724 182.224)
		(end 236.12983 182.224)
		(width 0.1)
		(layer "In4.Cu")
		(net 746)
	)
	(segment
		(start 208.622843 149.51)
		(end 209.54 149.51)
		(width 0.1)
		(layer "In4.Cu")
		(net 746)
	)
	(segment
		(start 204.487157 149.512843)
		(end 208.62 149.512843)
		(width 0.1)
		(layer "In4.Cu")
		(net 746)
	)
	(segment
		(start 236.2 183.399499)
		(end 236.2 185.863833)
		(width 0.1)
		(layer "In4.Cu")
		(net 746)
	)
	(segment
		(start 235.6 166.425)
		(end 235.6 182.1)
		(width 0.1)
		(layer "In4.Cu")
		(net 746)
	)
	(segment
		(start 231.475 150.15)
		(end 231.875 150.55)
		(width 0.1)
		(layer "In4.Cu")
		(net 746)
	)
	(segment
		(start 236.597167 186.261)
		(end 237.129499 186.261)
		(width 0.1)
		(layer "In4.Cu")
		(net 746)
	)
	(segment
		(start 231.875 150.55)
		(end 231.875 162.7)
		(width 0.1)
		(layer "In4.Cu")
		(net 746)
	)
	(segment
		(start 208.62 149.512843)
		(end 208.622843 149.51)
		(width 0.1)
		(layer "In4.Cu")
		(net 746)
	)
	(segment
		(start 236.12983 182.224)
		(end 236.349499 182.443669)
		(width 0.1)
		(layer "In4.Cu")
		(net 746)
	)
	(segment
		(start 209.54 149.51)
		(end 209.691071 149.358929)
		(width 0.1)
		(layer "In4.Cu")
		(net 746)
	)
	(segment
		(start 194.875 154.125)
		(end 194.875 153.55)
		(width 0.1)
		(layer "In4.Cu")
		(net 746)
	)
	(segment
		(start 194.5 154.5)
		(end 194.875 154.125)
		(width 0.1)
		(layer "In4.Cu")
		(net 746)
	)
	(segment
		(start 236.2 185.863833)
		(end 236.597167 186.261)
		(width 0.1)
		(layer "In4.Cu")
		(net 746)
	)
	(segment
		(start 201.7 152.3)
		(end 204.487157 149.512843)
		(width 0.1)
		(layer "In4.Cu")
		(net 746)
	)
	(segment
		(start 236.349499 182.443669)
		(end 236.349499 183.25)
		(width 0.1)
		(layer "In4.Cu")
		(net 746)
	)
	(segment
		(start 236.349499 183.25)
		(end 236.2 183.399499)
		(width 0.1)
		(layer "In4.Cu")
		(net 746)
	)
	(segment
		(start 196.125 152.3)
		(end 201.7 152.3)
		(width 0.1)
		(layer "In4.Cu")
		(net 746)
	)
	(segment
		(start 210.806349 149.358929)
		(end 211.59742 150.15)
		(width 0.1)
		(layer "In4.Cu")
		(net 746)
	)
	(segment
		(start 231.875 162.7)
		(end 235.6 166.425)
		(width 0.1)
		(layer "In4.Cu")
		(net 746)
	)
	(segment
		(start 194.875 153.55)
		(end 196.125 152.3)
		(width 0.1)
		(layer "In4.Cu")
		(net 746)
	)
	(segment
		(start 211.59742 150.15)
		(end 231.475 150.15)
		(width 0.1)
		(layer "In4.Cu")
		(net 746)
	)
	(segment
		(start 235.6 182.1)
		(end 235.724 182.224)
		(width 0.1)
		(layer "In4.Cu")
		(net 746)
	)
	(segment
		(start 209.691071 149.358929)
		(end 210.806349 149.358929)
		(width 0.1)
		(layer "In4.Cu")
		(net 746)
	)
	(segment
		(start 237.135499 182.505)
		(end 237.129499 182.511)
		(width 0.177)
		(layer "F.Cu")
		(net 747)
	)
	(segment
		(start 208.716 153.084)
		(end 208.360001 153.439999)
		(width 0.15)
		(layer "F.Cu")
		(net 747)
	)
	(segment
		(start 209.075 149.1)
		(end 209.1 149.125)
		(width 0.15)
		(layer "F.Cu")
		(net 747)
	)
	(segment
		(start 208.716 150.355446)
		(end 208.716 153.084)
		(width 0.15)
		(layer "F.Cu")
		(net 747)
	)
	(segment
		(start 209.1 149.971446)
		(end 208.716 150.355446)
		(width 0.15)
		(layer "F.Cu")
		(net 747)
	)
	(segment
		(start 194.0005 153.0005)
		(end 194.5 153.5)
		(width 0.256)
		(layer "F.Cu")
		(net 747)
	)
	(segment
		(start 208.360001 153.439999)
		(end 208.14 153.439999)
		(width 0.15)
		(layer "F.Cu")
		(net 747)
	)
	(segment
		(start 237.902499 182.505)
		(end 237.135499 182.505)
		(width 0.177)
		(layer "F.Cu")
		(net 747)
	)
	(segment
		(start 209.1 149.125)
		(end 209.1 149.971446)
		(width 0.15)
		(layer "F.Cu")
		(net 747)
	)
	(via
		(at 209.075 149.1)
		(size 0.45)
		(drill 0.1)
		(layers "F.Cu" "B.Cu")
		(remove_unused_layers yes)
		(keep_end_layers yes)
		(zone_layer_connections)
		(net 747)
	)
	(via
		(at 194.5 153.5)
		(size 0.45)
		(drill 0.1)
		(layers "F.Cu" "B.Cu")
		(remove_unused_layers yes)
		(keep_end_layers yes)
		(zone_layer_connections)
		(net 747)
	)
	(via
		(at 237.129499 182.511)
		(size 0.45)
		(drill 0.1)
		(layers "F.Cu" "B.Cu")
		(remove_unused_layers yes)
		(keep_end_layers yes)
		(zone_layer_connections)
		(net 747)
	)
	(segment
		(start 237.939499 182.499)
		(end 237.141499 182.499)
		(width 0.177)
		(layer "B.Cu")
		(net 747)
	)
	(segment
		(start 237.141499 182.499)
		(end 237.129499 182.511)
		(width 0.177)
		(layer "B.Cu")
		(net 747)
	)
	(segment
		(start 237.939499 181.449)
		(end 237.939499 182.499)
		(width 0.15)
		(layer "B.Cu")
		(net 747)
	)
	(segment
		(start 211.9 149.8)
		(end 211.083929 148.983929)
		(width 0.1)
		(layer "In4.Cu")
		(net 747)
	)
	(segment
		(start 208.55 149.3)
		(end 204.230331 149.3)
		(width 0.1)
		(layer "In4.Cu")
		(net 747)
	)
	(segment
		(start 211.083929 148.983929)
		(end 209.566071 148.983929)
		(width 0.1)
		(layer "In4.Cu")
		(net 747)
	)
	(segment
		(start 209.4 149.15)
		(end 208.7 149.15)
		(width 0.1)
		(layer "In4.Cu")
		(net 747)
	)
	(segment
		(start 209.566071 148.983929)
		(end 209.4 149.15)
		(width 0.1)
		(layer "In4.Cu")
		(net 747)
	)
	(segment
		(start 235.9 181.65)
		(end 235.9 165.725)
		(width 0.1)
		(layer "In4.Cu")
		(net 747)
	)
	(segment
		(start 232.7 150.45)
		(end 232.05 149.8)
		(width 0.1)
		(layer "In4.Cu")
		(net 747)
	)
	(segment
		(start 208.7 149.15)
		(end 208.55 149.3)
		(width 0.1)
		(layer "In4.Cu")
		(net 747)
	)
	(segment
		(start 232.05 149.8)
		(end 211.9 149.8)
		(width 0.1)
		(layer "In4.Cu")
		(net 747)
	)
	(segment
		(start 201.555331 151.975)
		(end 196.025 151.975)
		(width 0.1)
		(layer "In4.Cu")
		(net 747)
	)
	(segment
		(start 204.230331 149.3)
		(end 201.555331 151.975)
		(width 0.1)
		(layer "In4.Cu")
		(net 747)
	)
	(segment
		(start 237.129499 182.511)
		(end 236.761 182.511)
		(width 0.1)
		(layer "In4.Cu")
		(net 747)
	)
	(segment
		(start 235.9 165.725)
		(end 232.7 162.525)
		(width 0.1)
		(layer "In4.Cu")
		(net 747)
	)
	(segment
		(start 232.7 162.525)
		(end 232.7 150.45)
		(width 0.1)
		(layer "In4.Cu")
		(net 747)
	)
	(segment
		(start 236.761 182.511)
		(end 235.9 181.65)
		(width 0.1)
		(layer "In4.Cu")
		(net 747)
	)
	(segment
		(start 196.025 151.975)
		(end 194.5 153.5)
		(width 0.1)
		(layer "In4.Cu")
		(net 747)
	)
	(segment
		(start 226.545001 181.840001)
		(end 227.590001 181.840001)
		(width 0.114)
		(layer "F.Cu")
		(net 748)
	)
	(via
		(at 226.545001 181.840001)
		(size 0.45)
		(drill 0.1)
		(layers "F.Cu" "B.Cu")
		(remove_unused_layers yes)
		(keep_end_layers yes)
		(zone_layer_connections)
		(net 748)
	)
	(segment
		(start 227.859999 181.840001)
		(end 226.545001 181.840001)
		(width 0.114)
		(layer "B.Cu")
		(net 748)
	)
	(segment
		(start 227.9 181.8)
		(end 227.859999 181.840001)
		(width 0.114)
		(layer "B.Cu")
		(net 748)
	)
	(segment
		(start 212.3 140.2)
		(end 211.7 140.8)
		(width 0.1)
		(layer "F.Cu")
		(net 749)
	)
	(segment
		(start 255.32 169.6215)
		(end 255.32 168.553499)
		(width 0.182)
		(layer "F.Cu")
		(net 749)
	)
	(segment
		(start 231.15 156.8)
		(end 231.15 140.7)
		(width 0.1)
		(layer "F.Cu")
		(net 749)
	)
	(segment
		(start 240.700499 175.25)
		(end 241.272498 175.249999)
		(width 0.256)
		(layer "F.Cu")
		(net 749)
	)
	(segment
		(start 240.651499 182.505)
		(end 241.418499 182.505)
		(width 0.177)
		(layer "F.Cu")
		(net 749)
	)
	(segment
		(start 231.15 140.7)
		(end 229.55 139.1)
		(width 0.1)
		(layer "F.Cu")
		(net 749)
	)
	(segment
		(start 241.175 154.425)
		(end 241.0385 154.5615)
		(width 0.256)
		(layer "F.Cu")
		(net 749)
	)
	(segment
		(start 241.001 144.1)
		(end 240 144.1)
		(width 0.256)
		(layer "F.Cu")
		(net 749)
	)
	(segment
		(start 226.545001 181.040001)
		(end 227.590001 181.040001)
		(width 0.114)
		(layer "F.Cu")
		(net 749)
	)
	(segment
		(start 237.025999 162.675999)
		(end 231.15 156.8)
		(width 0.1)
		(layer "F.Cu")
		(net 749)
	)
	(segment
		(start 213.8 139.1)
		(end 212.7 140.2)
		(width 0.1)
		(layer "F.Cu")
		(net 749)
	)
	(segment
		(start 240.521499 153.275501)
		(end 241.175 153.929002)
		(width 0.256)
		(layer "F.Cu")
		(net 749)
	)
	(segment
		(start 212.7 140.2)
		(end 212.3 140.2)
		(width 0.1)
		(layer "F.Cu")
		(net 749)
	)
	(segment
		(start 215.850001 181.045001)
		(end 216.895001 181.045001)
		(width 0.114)
		(layer "F.Cu")
		(net 749)
	)
	(segment
		(start 240.700499 169.7)
		(end 241.272498 169.699999)
		(width 0.256)
		(layer "F.Cu")
		(net 749)
	)
	(segment
		(start 255.32 168.553499)
		(end 255.324499 168.549)
		(width 0.182)
		(layer "F.Cu")
		(net 749)
	)
	(segment
		(start 241.272498 169.699999)
		(end 241.273 169.7005)
		(width 0.256)
		(layer "F.Cu")
		(net 749)
	)
	(segment
		(start 241.0385 154.5615)
		(end 240.738499 154.5615)
		(width 0.256)
		(layer "F.Cu")
		(net 749)
	)
	(segment
		(start 237.026499 163.449001)
		(end 237.025999 163.4485)
		(width 0.256)
		(layer "F.Cu")
		(net 749)
	)
	(segment
		(start 229.55 139.1)
		(end 213.8 139.1)
		(width 0.1)
		(layer "F.Cu")
		(net 749)
	)
	(segment
		(start 241.272498 175.249999)
		(end 241.273 175.2505)
		(width 0.256)
		(layer "F.Cu")
		(net 749)
	)
	(segment
		(start 241.175 153.929002)
		(end 241.175 154.425)
		(width 0.256)
		(layer "F.Cu")
		(net 749)
	)
	(segment
		(start 237.923499 163.449)
		(end 237.026499 163.449001)
		(width 0.256)
		(layer "F.Cu")
		(net 749)
	)
	(segment
		(start 237.025999 163.4485)
		(end 237.025999 162.675999)
		(width 0.1)
		(layer "F.Cu")
		(net 749)
	)
	(via
		(at 255.324499 168.549)
		(size 0.45)
		(drill 0.1)
		(layers "F.Cu" "B.Cu")
		(remove_unused_layers yes)
		(keep_end_layers yes)
		(zone_layer_connections)
		(net 749)
	)
	(via
		(at 215.850001 181.045001)
		(size 0.45)
		(drill 0.1)
		(layers "F.Cu" "B.Cu")
		(remove_unused_layers yes)
		(keep_end_layers yes)
		(zone_layer_connections)
		(net 749)
	)
	(via
		(at 237.025999 163.4485)
		(size 0.45)
		(drill 0.1)
		(layers "F.Cu" "B.Cu")
		(remove_unused_layers yes)
		(keep_end_layers yes)
		(zone_layer_connections)
		(net 749)
	)
	(via
		(at 240.521499 153.275501)
		(size 0.45)
		(drill 0.1)
		(layers "F.Cu" "B.Cu")
		(remove_unused_layers yes)
		(keep_end_layers yes)
		(free yes)
		(zone_layer_connections)
		(net 749)
	)
	(via
		(at 241.273 169.7005)
		(size 0.45)
		(drill 0.1)
		(layers "F.Cu" "B.Cu")
		(remove_unused_layers yes)
		(keep_end_layers yes)
		(zone_layer_connections)
		(net 749)
	)
	(via
		(at 211.7 140.8)
		(size 0.45)
		(drill 0.1)
		(layers "F.Cu" "B.Cu")
		(net 749)
	)
	(via
		(at 241.418499 182.505)
		(size 0.45)
		(drill 0.1)
		(layers "F.Cu" "B.Cu")
		(remove_unused_layers yes)
		(keep_end_layers yes)
		(zone_layer_connections)
		(net 749)
	)
	(via
		(at 257.4 151.15)
		(size 0.45)
		(drill 0.1)
		(layers "F.Cu" "B.Cu")
		(remove_unused_layers yes)
		(keep_end_layers yes)
		(zone_layer_connections)
		(net 749)
	)
	(via
		(at 226.545001 181.040001)
		(size 0.45)
		(drill 0.1)
		(layers "F.Cu" "B.Cu")
		(remove_unused_layers yes)
		(keep_end_layers yes)
		(zone_layer_connections)
		(net 749)
	)
	(via
		(at 241.273 175.2505)
		(size 0.45)
		(drill 0.1)
		(layers "F.Cu" "B.Cu")
		(remove_unused_layers yes)
		(keep_end_layers yes)
		(zone_layer_connections)
		(net 749)
	)
	(via
		(at 240 144.1)
		(size 0.45)
		(drill 0.1)
		(layers "F.Cu" "B.Cu")
		(remove_unused_layers yes)
		(keep_end_layers yes)
		(zone_layer_connections)
		(net 749)
	)
	(segment
		(start 209.7045 138.8045)
		(end 211.7 140.8)
		(width 0.1)
		(layer "B.Cu")
		(net 749)
	)
	(segment
		(start 238.909499 181.449)
		(end 239.743499 181.449)
		(width 0.15)
		(layer "B.Cu")
		(net 749)
	)
	(segment
		(start 239.743499 181.449)
		(end 240.799499 182.505)
		(width 0.15)
		(layer "B.Cu")
		(net 749)
	)
	(segment
		(start 238.909499 181.449)
		(end 238.909499 179.449)
		(width 0.15)
		(layer "B.Cu")
		(net 749)
	)
	(segment
		(start 240.799499 182.505)
		(end 241.418499 182.505)
		(width 0.15)
		(layer "B.Cu")
		(net 749)
	)
	(segment
		(start 207.801 138.8045)
		(end 209.7045 138.8045)
		(width 0.1)
		(layer "B.Cu")
		(net 749)
	)
	(segment
		(start 237.05 166.25)
		(end 236.45 165.65)
		(width 0.1)
		(layer "In2.Cu")
		(net 749)
	)
	(segment
		(start 241.273 171.823)
		(end 240.75 171.3)
		(width 0.1)
		(layer "In2.Cu")
		(net 749)
	)
	(segment
		(start 215.865 181.06)
		(end 215.850001 181.045001)
		(width 0.114)
		(layer "In2.Cu")
		(net 749)
	)
	(segment
		(start 237.8225 166.25)
		(end 237.05 166.25)
		(width 0.1)
		(layer "In2.Cu")
		(net 749)
	)
	(segment
		(start 237.025999 163.4485)
		(end 237.615998 162.858501)
		(width 0.1)
		(layer "In2.Cu")
		(net 749)
	)
	(segment
		(start 226.545001 181.040001)
		(end 225.315 179.81)
		(width 0.114)
		(layer "In2.Cu")
		(net 749)
	)
	(segment
		(start 225.315 179.81)
		(end 222.24 179.81)
		(width 0.114)
		(layer "In2.Cu")
		(net 749)
	)
	(segment
		(start 237.615998 157.884002)
		(end 240.521499 154.978501)
		(width 0.1)
		(layer "In2.Cu")
		(net 749)
	)
	(segment
		(start 239.997 153.8)
		(end 237.175 153.8)
		(width 0.1)
		(layer "In2.Cu")
		(net 749)
	)
	(segment
		(start 240.85 179.4)
		(end 241.8 180.35)
		(width 0.1)
		(layer "In2.Cu")
		(net 749)
	)
	(segment
		(start 237.15 153.619669)
		(end 237.15 152.8)
		(width 0.1)
		(layer "In2.Cu")
		(net 749)
	)
	(segment
		(start 257.4 151.15)
		(end 257.424499 151.15)
		(width 0.1)
		(layer "In2.Cu")
		(net 749)
	)
	(segment
		(start 257.424499 151.15)
		(end 258.85 152.575501)
		(width 0.1)
		(layer "In2.Cu")
		(net 749)
	)
	(segment
		(start 241.8 180.35)
		(end 241.8 182.123499)
		(width 0.1)
		(layer "In2.Cu")
		(net 749)
	)
	(segment
		(start 236.45 164.024499)
		(end 237.025999 163.4485)
		(width 0.1)
		(layer "In2.Cu")
		(net 749)
	)
	(segment
		(start 240.521499 154.978501)
		(end 240.521499 153.275501)
		(width 0.1)
		(layer "In2.Cu")
		(net 749)
	)
	(segment
		(start 241.418499 182.505)
		(end 238.78 182.505)
		(width 0.1)
		(layer "In2.Cu")
		(net 749)
	)
	(segment
		(start 220.99 181.06)
		(end 215.865 181.06)
		(width 0.114)
		(layer "In2.Cu")
		(net 749)
	)
	(segment
		(start 226.825002 180.76)
		(end 237.035 180.76)
		(width 0.1)
		(layer "In2.Cu")
		(net 749)
	)
	(segment
		(start 239 150.95)
		(end 239 145.1)
		(width 0.1)
		(layer "In2.Cu")
		(net 749)
	)
	(segment
		(start 241.273 175.2505)
		(end 240.85 175.6735)
		(width 0.1)
		(layer "In2.Cu")
		(net 749)
	)
	(segment
		(start 240.521499 153.275501)
		(end 239.997 153.8)
		(width 0.1)
		(layer "In2.Cu")
		(net 749)
	)
	(segment
		(start 236.45 165.65)
		(end 236.45 164.024499)
		(width 0.1)
		(layer "In2.Cu")
		(net 749)
	)
	(segment
		(start 239 145.1)
		(end 240 144.1)
		(width 0.1)
		(layer "In2.Cu")
		(net 749)
	)
	(segment
		(start 237.15 152.8)
		(end 239 150.95)
		(width 0.1)
		(layer "In2.Cu")
		(net 749)
	)
	(segment
		(start 256.024499 164.899)
		(end 256.024499 167.699)
		(width 0.1)
		(layer "In2.Cu")
		(net 749)
	)
	(segment
		(start 240.85 175.6735)
		(end 240.85 179.4)
		(width 0.1)
		(layer "In2.Cu")
		(net 749)
	)
	(segment
		(start 256.024499 167.849)
		(end 255.324499 168.549)
		(width 0.1)
		(layer "In2.Cu")
		(net 749)
	)
	(segment
		(start 222.24 179.81)
		(end 220.99 181.06)
		(width 0.114)
		(layer "In2.Cu")
		(net 749)
	)
	(segment
		(start 237.175 153.8)
		(end 237.175 153.644669)
		(width 0.1)
		(layer "In2.Cu")
		(net 749)
	)
	(segment
		(start 240.75 170.2235)
		(end 241.273 169.7005)
		(width 0.1)
		(layer "In2.Cu")
		(net 749)
	)
	(segment
		(start 241.273 175.2505)
		(end 241.273 171.823)
		(width 0.1)
		(layer "In2.Cu")
		(net 749)
	)
	(segment
		(start 241.8 182.123499)
		(end 241.418499 182.505)
		(width 0.1)
		(layer "In2.Cu")
		(net 749)
	)
	(segment
		(start 241.273 169.7005)
		(end 237.8225 166.25)
		(width 0.1)
		(layer "In2.Cu")
		(net 749)
	)
	(segment
		(start 226.545001 181.040001)
		(end 226.825002 180.76)
		(width 0.1)
		(layer "In2.Cu")
		(net 749)
	)
	(segment
		(start 237.175 153.644669)
		(end 237.15 153.619669)
		(width 0.1)
		(layer "In2.Cu")
		(net 749)
	)
	(segment
		(start 240.75 171.3)
		(end 240.75 170.2235)
		(width 0.1)
		(layer "In2.Cu")
		(net 749)
	)
	(segment
		(start 256.024499 167.849)
		(end 256.024499 167.699)
		(width 0.1)
		(layer "In2.Cu")
		(net 749)
	)
	(segment
		(start 258.85 162.073499)
		(end 256.024499 164.899)
		(width 0.1)
		(layer "In2.Cu")
		(net 749)
	)
	(segment
		(start 258.85 152.575501)
		(end 258.85 162.073499)
		(width 0.1)
		(layer "In2.Cu")
		(net 749)
	)
	(segment
		(start 237.615998 162.858501)
		(end 237.615998 157.884002)
		(width 0.1)
		(layer "In2.Cu")
		(net 749)
	)
	(segment
		(start 238.78 182.505)
		(end 237.035 180.76)
		(width 0.1)
		(layer "In2.Cu")
		(net 749)
	)
	(segment
		(start 257.4 151.15)
		(end 257.8 150.75)
		(width 0.1)
		(layer "In4.Cu")
		(net 749)
	)
	(segment
		(start 256.6505 146.4755)
		(end 240.624169 146.4755)
		(width 0.1)
		(layer "In4.Cu")
		(net 749)
	)
	(segment
		(start 239.625 144.475)
		(end 240 144.1)
		(width 0.1)
		(layer "In4.Cu")
		(net 749)
	)
	(segment
		(start 239.625 145.476331)
		(end 239.625 144.475)
		(width 0.1)
		(layer "In4.Cu")
		(net 749)
	)
	(segment
		(start 240.624169 146.4755)
		(end 239.625 145.476331)
		(width 0.1)
		(layer "In4.Cu")
		(net 749)
	)
	(segment
		(start 257.8 150.75)
		(end 257.8 147.625)
		(width 0.1)
		(layer "In4.Cu")
		(net 749)
	)
	(segment
		(start 257.8 147.625)
		(end 256.6505 146.4755)
		(width 0.1)
		(layer "In4.Cu")
		(net 749)
	)
	(segment
		(start 221.885 177.037)
		(end 222.135 176.787)
		(width 0.15)
		(layer "B.Cu")
		(net 754)
	)
	(segment
		(start 221.885 177.435)
		(end 221.885 177.037)
		(width 0.15)
		(layer "B.Cu")
		(net 754)
	)
	(segment
		(start 232.290001 182.240002)
		(end 232.905 182.240002)
		(width 0.1)
		(layer "F.Cu")
		(net 755)
	)
	(segment
		(start 221.595001 182.245001)
		(end 222.21 182.245001)
		(width 0.1)
		(layer "F.Cu")
		(net 755)
	)
	(via
		(at 222.21 182.245001)
		(size 0.45)
		(drill 0.1)
		(layers "F.Cu" "B.Cu")
		(remove_unused_layers yes)
		(keep_end_layers yes)
		(zone_layer_connections)
		(net 755)
	)
	(via
		(at 232.905 182.240002)
		(size 0.45)
		(drill 0.1)
		(layers "F.Cu" "B.Cu")
		(remove_unused_layers yes)
		(keep_end_layers yes)
		(zone_layer_connections)
		(net 755)
	)
	(segment
		(start 220.835 180.14)
		(end 220.835 179.56)
		(width 0.15)
		(layer "B.Cu")
		(net 755)
	)
	(segment
		(start 221.905 181.21)
		(end 220.835 180.14)
		(width 0.15)
		(layer "B.Cu")
		(net 755)
	)
	(segment
		(start 220.835 179.56)
		(end 221.335 179.06)
		(width 0.15)
		(layer "B.Cu")
		(net 755)
	)
	(segment
		(start 222.135 182.170001)
		(end 222.21 182.245001)
		(width 0.256)
		(layer "B.Cu")
		(net 755)
	)
	(segment
		(start 221.335 179.06)
		(end 221.335 177.087)
		(width 0.15)
		(layer "B.Cu")
		(net 755)
	)
	(segment
		(start 222.135 181.44)
		(end 222.135 182.170001)
		(width 0.256)
		(layer "B.Cu")
		(net 755)
	)
	(segment
		(start 221.335 177.087)
		(end 221.635 176.787)
		(width 0.15)
		(layer "B.Cu")
		(net 755)
	)
	(segment
		(start 221.905 181.21)
		(end 222.135 181.44)
		(width 0.256)
		(layer "B.Cu")
		(net 755)
	)
	(segment
		(start 222.740331 182.245001)
		(end 222.775332 182.21)
		(width 0.1)
		(layer "In4.Cu")
		(net 755)
	)
	(segment
		(start 232.905 181.98)
		(end 232.905 182.240002)
		(width 0.1)
		(layer "In4.Cu")
		(net 755)
	)
	(segment
		(start 222.775332 182.21)
		(end 224.717842 182.21)
		(width 0.1)
		(layer "In4.Cu")
		(net 755)
	)
	(segment
		(start 231.485 180.56)
		(end 232.905 181.98)
		(width 0.1)
		(layer "In4.Cu")
		(net 755)
	)
	(segment
		(start 224.717842 182.21)
		(end 226.367842 180.56)
		(width 0.1)
		(layer "In4.Cu")
		(net 755)
	)
	(segment
		(start 222.21 182.245001)
		(end 222.740331 182.245001)
		(width 0.1)
		(layer "In4.Cu")
		(net 755)
	)
	(segment
		(start 226.367842 180.56)
		(end 231.485 180.56)
		(width 0.1)
		(layer "In4.Cu")
		(net 755)
	)
	(segment
		(start 222.86 178.395)
		(end 221.885 178.395)
		(width 0.256)
		(layer "B.Cu")
		(net 756)
	)
	(segment
		(start 221.885 179.305)
		(end 222.86 179.305)
		(width 0.256)
		(layer "B.Cu")
		(net 756)
	)
	(segment
		(start 222.86 179.305)
		(end 222.86 178.395)
		(width 0.256)
		(layer "B.Cu")
		(net 756)
	)
	(segment
		(start 175.9995 154.0005)
		(end 175.5 154.5)
		(width 0.256)
		(layer "F.Cu")
		(net 762)
	)
	(segment
		(start 160.81 158.984999)
		(end 160.81 157.949999)
		(width 0.256)
		(layer "F.Cu")
		(net 762)
	)
	(via
		(at 160.81 157.949999)
		(size 0.45)
		(drill 0.1)
		(layers "F.Cu" "B.Cu")
		(remove_unused_layers yes)
		(keep_end_layers yes)
		(zone_layer_connections)
		(net 762)
	)
	(via
		(at 175.5 154.5)
		(size 0.45)
		(drill 0.1)
		(layers "F.Cu" "B.Cu")
		(remove_unused_layers yes)
		(keep_end_layers yes)
		(zone_layer_connections)
		(net 762)
	)
	(segment
		(start 174.1 154.5)
		(end 170.9 157.7)
		(width 0.1)
		(layer "In2.Cu")
		(net 762)
	)
	(segment
		(start 167.345001 158.054999)
		(end 160.915 158.054999)
		(width 0.1)
		(layer "In2.Cu")
		(net 762)
	)
	(segment
		(start 170.9 157.7)
		(end 167.7 157.7)
		(width 0.1)
		(layer "In2.Cu")
		(net 762)
	)
	(segment
		(start 175.5 154.5)
		(end 174.1 154.5)
		(width 0.1)
		(layer "In2.Cu")
		(net 762)
	)
	(segment
		(start 160.915 158.054999)
		(end 160.81 157.949999)
		(width 0.1)
		(layer "In2.Cu")
		(net 762)
	)
	(segment
		(start 167.7 157.7)
		(end 167.345001 158.054999)
		(width 0.1)
		(layer "In2.Cu")
		(net 762)
	)
	(segment
		(start 159.285693 158.56145)
		(end 159.295321 158.584694)
		(width 0.1)
		(layer "F.Cu")
		(net 764)
	)
	(segment
		(start 159.210142 158.461653)
		(end 159.226103 158.481102)
		(width 0.1)
		(layer "F.Cu")
		(net 764)
	)
	(segment
		(start 158.08 154.923003)
		(end 158.094655 155.071801)
		(width 0.1)
		(layer "F.Cu")
		(net 764)
	)
	(segment
		(start 159.174677 158.395302)
		(end 159.184304 158.418546)
		(width 0.1)
		(layer "F.Cu")
		(net 764)
	)
	(segment
		(start 159.307533 158.633446)
		(end 159.31 158.658484)
		(width 0.1)
		(layer "F.Cu")
		(net 764)
	)
	(segment
		(start 159.162465 158.346549)
		(end 159.167374 158.371226)
		(width 0.1)
		(layer "F.Cu")
		(net 764)
	)
	(segment
		(start 158.080944 154.244142)
		(end 158.08 154.253738)
		(width 0.1)
		(layer "F.Cu")
		(net 764)
	)
	(segment
		(start 158.082824 154.234685)
		(end 158.080944 154.244142)
		(width 0.1)
		(layer "F.Cu")
		(net 764)
	)
	(segment
		(start 159.273833 158.539261)
		(end 159.285693 158.56145)
		(width 0.1)
		(layer "F.Cu")
		(net 764)
	)
	(segment
		(start 158.085623 154.225459)
		(end 158.082824 154.234685)
		(width 0.1)
		(layer "F.Cu")
		(net 764)
	)
	(segment
		(start 159.226103 158.481102)
		(end 159.243894 158.498893)
		(width 0.1)
		(layer "F.Cu")
		(net 764)
	)
	(segment
		(start 158.224444 155.499663)
		(end 158.294927 155.631526)
		(width 0.1)
		(layer "F.Cu")
		(net 764)
	)
	(segment
		(start 159.16 156.987623)
		(end 159.16 158.321511)
		(width 0.1)
		(layer "F.Cu")
		(net 764)
	)
	(segment
		(start 159.259855 158.518342)
		(end 159.273833 158.539261)
		(width 0.1)
		(layer "F.Cu")
		(net 764)
	)
	(segment
		(start 158.099215 154.200032)
		(end 158.093858 154.208049)
		(width 0.1)
		(layer "F.Cu")
		(net 764)
	)
	(segment
		(start 158.472848 155.871425)
		(end 158.856619 156.255196)
		(width 0.1)
		(layer "F.Cu")
		(net 764)
	)
	(segment
		(start 159.16 158.321511)
		(end 159.162465 158.346549)
		(width 0.1)
		(layer "F.Cu")
		(net 764)
	)
	(segment
		(start 159.243894 158.498893)
		(end 159.259855 158.518342)
		(width 0.1)
		(layer "F.Cu")
		(net 764)
	)
	(segment
		(start 159.196164 158.440735)
		(end 159.210142 158.461653)
		(width 0.1)
		(layer "F.Cu")
		(net 764)
	)
	(segment
		(start 159.167374 158.371226)
		(end 159.174677 158.395302)
		(width 0.1)
		(layer "F.Cu")
		(net 764)
	)
	(segment
		(start 158.123823 155.218446)
		(end 158.167226 155.361526)
		(width 0.1)
		(layer "F.Cu")
		(net 764)
	)
	(segment
		(start 158.08 154.253738)
		(end 158.08 154.923003)
		(width 0.1)
		(layer "F.Cu")
		(net 764)
	)
	(segment
		(start 158.167226 155.361526)
		(end 158.224444 155.499663)
		(width 0.1)
		(layer "F.Cu")
		(net 764)
	)
	(segment
		(start 159.302624 158.60877)
		(end 159.307533 158.633446)
		(width 0.1)
		(layer "F.Cu")
		(net 764)
	)
	(segment
		(start 158.094655 155.071801)
		(end 158.123823 155.218446)
		(width 0.1)
		(layer "F.Cu")
		(net 764)
	)
	(segment
		(start 158.089313 154.216552)
		(end 158.085623 154.225459)
		(width 0.1)
		(layer "F.Cu")
		(net 764)
	)
	(segment
		(start 158.377995 155.755846)
		(end 158.472848 155.871425)
		(width 0.1)
		(layer "F.Cu")
		(net 764)
	)
	(segment
		(start 159.184304 158.418546)
		(end 159.196164 158.440735)
		(width 0.1)
		(layer "F.Cu")
		(net 764)
	)
	(segment
		(start 158.137483 154.16043)
		(end 158.105332 154.192579)
		(width 0.1)
		(layer "F.Cu")
		(net 764)
	)
	(segment
		(start 159.31 158.658484)
		(end 159.31 158.984999)
		(width 0.1)
		(layer "F.Cu")
		(net 764)
	)
	(segment
		(start 158.294927 155.631526)
		(end 158.377995 155.755846)
		(width 0.1)
		(layer "F.Cu")
		(net 764)
	)
	(segment
		(start 159.295321 158.584694)
		(end 159.302624 158.60877)
		(width 0.1)
		(layer "F.Cu")
		(net 764)
	)
	(segment
		(start 158.105332 154.192579)
		(end 158.099215 154.200032)
		(width 0.1)
		(layer "F.Cu")
		(net 764)
	)
	(segment
		(start 158.093858 154.208049)
		(end 158.089313 154.216552)
		(width 0.1)
		(layer "F.Cu")
		(net 764)
	)
	(arc
		(start 158.856619 156.255196)
		(mid 159.081154 156.591236)
		(end 159.16 156.987623)
		(width 0.1)
		(layer "F.Cu")
		(net 764)
	)
	(segment
		(start 158.893893 158.481102)
		(end 158.876103 158.498893)
		(width 0.1)
		(layer "F.Cu")
		(net 765)
	)
	(segment
		(start 158.846164 158.539261)
		(end 158.834304 158.56145)
		(width 0.1)
		(layer "F.Cu")
		(net 765)
	)
	(segment
		(start 157.839178 156.993662)
		(end 157.843465 156.983314)
		(width 0.1)
		(layer "F.Cu")
		(net 765)
	)
	(segment
		(start 157.846716 156.972596)
		(end 157.848902 156.961611)
		(width 0.1)
		(layer "F.Cu")
		(net 765)
	)
	(segment
		(start 158.909854 158.461653)
		(end 158.893893 158.481102)
		(width 0.1)
		(layer "F.Cu")
		(net 765)
	)
	(segment
		(start 157.851972 155.974756)
		(end 157.855898 155.955016)
		(width 0.1)
		(layer "F.Cu")
		(net 765)
	)
	(segment
		(start 158.860142 158.518342)
		(end 158.846164 158.539261)
		(width 0.1)
		(layer "F.Cu")
		(net 765)
	)
	(segment
		(start 158.817373 158.608769)
		(end 158.812465 158.633446)
		(width 0.1)
		(layer "F.Cu")
		(net 765)
	)
	(segment
		(start 158.935693 158.418545)
		(end 158.923833 158.440734)
		(width 0.1)
		(layer "F.Cu")
		(net 765)
	)
	(segment
		(start 158.96 157.026735)
		(end 158.96 157.279999)
		(width 0.1)
		(layer "F.Cu")
		(net 765)
	)
	(segment
		(start 158.035477 155.799999)
		(end 158.053098 155.799999)
		(width 0.1)
		(layer "F.Cu")
		(net 765)
	)
	(segment
		(start 157.983794 155.810278)
		(end 158.000657 155.805163)
		(width 0.1)
		(layer "F.Cu")
		(net 765)
	)
	(segment
		(start 157.869443 155.917159)
		(end 157.87893 155.899408)
		(width 0.1)
		(layer "F.Cu")
		(net 765)
	)
	(segment
		(start 158.945321 158.395301)
		(end 158.935693 158.418545)
		(width 0.1)
		(layer "F.Cu")
		(net 765)
	)
	(segment
		(start 157.902882 155.867114)
		(end 157.923698 155.846298)
		(width 0.1)
		(layer "F.Cu")
		(net 765)
	)
	(segment
		(start 158.952625 158.371225)
		(end 158.945321 158.395301)
		(width 0.1)
		(layer "F.Cu")
		(net 765)
	)
	(segment
		(start 158.151255 155.835119)
		(end 158.164877 155.846298)
		(width 0.1)
		(layer "F.Cu")
		(net 765)
	)
	(segment
		(start 157.855898 155.955016)
		(end 157.861741 155.935755)
		(width 0.1)
		(layer "F.Cu")
		(net 765)
	)
	(segment
		(start 158.136603 155.825328)
		(end 158.151255 155.835119)
		(width 0.1)
		(layer "F.Cu")
		(net 765)
	)
	(segment
		(start 157.890113 155.882673)
		(end 157.902882 155.867114)
		(width 0.1)
		(layer "F.Cu")
		(net 765)
	)
	(segment
		(start 158.824677 158.584693)
		(end 158.817373 158.608769)
		(width 0.1)
		(layer "F.Cu")
		(net 765)
	)
	(segment
		(start 157.93732 155.835118)
		(end 157.951972 155.825328)
		(width 0.1)
		(layer "F.Cu")
		(net 765)
	)
	(segment
		(start 158.863528 157.57647)
		(end 158.863529 157.57647)
		(width 0.1)
		(layer "F.Cu")
		(net 765)
	)
	(segment
		(start 158.923833 158.440734)
		(end 158.909854 158.461653)
		(width 0.1)
		(layer "F.Cu")
		(net 765)
	)
	(segment
		(start 158.96 158.321511)
		(end 158.957533 158.346549)
		(width 0.1)
		(layer "F.Cu")
		(net 765)
	)
	(segment
		(start 157.87893 155.899408)
		(end 157.890113 155.882673)
		(width 0.1)
		(layer "F.Cu")
		(net 765)
	)
	(segment
		(start 158.121062 155.817022)
		(end 158.136603 155.825328)
		(width 0.1)
		(layer "F.Cu")
		(net 765)
	)
	(segment
		(start 157.833898 157.003539)
		(end 157.839178 156.993662)
		(width 0.1)
		(layer "F.Cu")
		(net 765)
	)
	(segment
		(start 157.923698 155.846298)
		(end 157.93732 155.835118)
		(width 0.1)
		(layer "F.Cu")
		(net 765)
	)
	(segment
		(start 158.000657 155.805163)
		(end 158.01794 155.801725)
		(width 0.1)
		(layer "F.Cu")
		(net 765)
	)
	(segment
		(start 157.82057 157.021511)
		(end 157.827675 157.012852)
		(width 0.1)
		(layer "F.Cu")
		(net 765)
	)
	(segment
		(start 158.767057 157.472941)
		(end 158.767057 157.479999)
		(width 0.1)
		(layer "F.Cu")
		(net 765)
	)
	(segment
		(start 158.053098 155.799999)
		(end 158.070635 155.801726)
		(width 0.1)
		(layer "F.Cu")
		(net 765)
	)
	(segment
		(start 158.834304 158.56145)
		(end 158.824677 158.584693)
		(width 0.1)
		(layer "F.Cu")
		(net 765)
	)
	(segment
		(start 157.848902 156.961611)
		(end 157.85 156.950464)
		(width 0.1)
		(layer "F.Cu")
		(net 765)
	)
	(segment
		(start 157.783223 157.058861)
		(end 157.82057 157.021511)
		(width 0.1)
		(layer "F.Cu")
		(net 765)
	)
	(segment
		(start 158.81 158.658484)
		(end 158.81 158.984999)
		(width 0.1)
		(layer "F.Cu")
		(net 765)
	)
	(segment
		(start 157.827675 157.012852)
		(end 157.833898 157.003539)
		(width 0.1)
		(layer "F.Cu")
		(net 765)
	)
	(segment
		(start 158.96 157.672941)
		(end 158.96 158.321511)
		(width 0.1)
		(layer "F.Cu")
		(net 765)
	)
	(segment
		(start 158.070635 155.801726)
		(end 158.087918 155.805163)
		(width 0.1)
		(layer "F.Cu")
		(net 765)
	)
	(segment
		(start 158.957533 158.346549)
		(end 158.952625 158.371225)
		(width 0.1)
		(layer "F.Cu")
		(net 765)
	)
	(segment
		(start 158.876103 158.498893)
		(end 158.860142 158.518342)
		(width 0.1)
		(layer "F.Cu")
		(net 765)
	)
	(segment
		(start 158.01794 155.801725)
		(end 158.035477 155.799999)
		(width 0.1)
		(layer "F.Cu")
		(net 765)
	)
	(segment
		(start 157.861741 155.935755)
		(end 157.869443 155.917159)
		(width 0.1)
		(layer "F.Cu")
		(net 765)
	)
	(segment
		(start 157.85 155.994787)
		(end 157.851972 155.974756)
		(width 0.1)
		(layer "F.Cu")
		(net 765)
	)
	(segment
		(start 157.967513 155.817021)
		(end 157.983794 155.810278)
		(width 0.1)
		(layer "F.Cu")
		(net 765)
	)
	(segment
		(start 157.843465 156.983314)
		(end 157.846716 156.972596)
		(width 0.1)
		(layer "F.Cu")
		(net 765)
	)
	(segment
		(start 157.951972 155.825328)
		(end 157.967513 155.817021)
		(width 0.1)
		(layer "F.Cu")
		(net 765)
	)
	(segment
		(start 158.164877 155.846298)
		(end 158.687542 156.368963)
		(width 0.1)
		(layer "F.Cu")
		(net 765)
	)
	(segment
		(start 157.85 156.950464)
		(end 157.85 155.994787)
		(width 0.1)
		(layer "F.Cu")
		(net 765)
	)
	(segment
		(start 158.863529 157.37647)
		(end 158.863528 157.37647)
		(width 0.1)
		(layer "F.Cu")
		(net 765)
	)
	(segment
		(start 158.087918 155.805163)
		(end 158.104781 155.810278)
		(width 0.1)
		(layer "F.Cu")
		(net 765)
	)
	(segment
		(start 158.104781 155.810278)
		(end 158.121062 155.817022)
		(width 0.1)
		(layer "F.Cu")
		(net 765)
	)
	(segment
		(start 158.812465 158.633446)
		(end 158.81 158.658484)
		(width 0.1)
		(layer "F.Cu")
		(net 765)
	)
	(arc
		(start 158.767057 157.479999)
		(mid 158.795313 157.548214)
		(end 158.863528 157.57647)
		(width 0.1)
		(layer "F.Cu")
		(net 765)
	)
	(arc
		(start 158.96 157.026735)
		(mid 158.88919 156.670751)
		(end 158.687542 156.368963)
		(width 0.1)
		(layer "F.Cu")
		(net 765)
	)
	(arc
		(start 158.863529 157.57647)
		(mid 158.931744 157.604726)
		(end 158.96 157.672941)
		(width 0.1)
		(layer "F.Cu")
		(net 765)
	)
	(arc
		(start 158.96 157.279999)
		(mid 158.931744 157.348214)
		(end 158.863529 157.37647)
		(width 0.1)
		(layer "F.Cu")
		(net 765)
	)
	(arc
		(start 158.863528 157.37647)
		(mid 158.795313 157.404726)
		(end 158.767057 157.472941)
		(width 0.1)
		(layer "F.Cu")
		(net 765)
	)
	(segment
		(start 175.999501 151.9995)
		(end 175.5 151.5)
		(width 0.256)
		(layer "F.Cu")
		(net 767)
	)
	(segment
		(start 156.995 163.799999)
		(end 156.29 163.799999)
		(width 0.256)
		(layer "F.Cu")
		(net 767)
	)
	(segment
		(start 156.29 163.799999)
		(end 155.77 164.319999)
		(width 0.256)
		(layer "F.Cu")
		(net 767)
	)
	(via
		(at 175.5 151.5)
		(size 0.45)
		(drill 0.1)
		(layers "F.Cu" "B.Cu")
		(remove_unused_layers yes)
		(keep_end_layers yes)
		(zone_layer_connections)
		(net 767)
	)
	(via
		(at 155.77 164.319999)
		(size 0.45)
		(drill 0.1)
		(layers "F.Cu" "B.Cu")
		(remove_unused_layers yes)
		(keep_end_layers yes)
		(zone_layer_connections)
		(net 767)
	)
	(segment
		(start 172.2 151.5)
		(end 175.5 151.5)
		(width 0.1)
		(layer "In2.Cu")
		(net 767)
	)
	(segment
		(start 155.77 164.319999)
		(end 155.77 159.61)
		(width 0.1)
		(layer "In2.Cu")
		(net 767)
	)
	(segment
		(start 167.2 156.5)
		(end 172.2 151.5)
		(width 0.1)
		(layer "In2.Cu")
		(net 767)
	)
	(segment
		(start 155.77 159.61)
		(end 158.88 156.5)
		(width 0.1)
		(layer "In2.Cu")
		(net 767)
	)
	(segment
		(start 158.88 156.5)
		(end 167.2 156.5)
		(width 0.1)
		(layer "In2.Cu")
		(net 767)
	)
	(segment
		(start 124.906 174.672)
		(end 125.796 173.782)
		(width 0.201)
		(layer "F.Cu")
		(net 768)
	)
	(segment
		(start 125.576 177.222)
		(end 124.906 176.552)
		(width 0.201)
		(layer "F.Cu")
		(net 768)
	)
	(segment
		(start 125.796 173.782)
		(end 131.536 173.782)
		(width 0.201)
		(layer "F.Cu")
		(net 768)
	)
	(segment
		(start 177.9995 151.9995)
		(end 177.5 151.5)
		(width 0.256)
		(layer "F.Cu")
		(net 768)
	)
	(segment
		(start 124.906 176.552)
		(end 124.906 174.672)
		(width 0.201)
		(layer "F.Cu")
		(net 768)
	)
	(segment
		(start 125.576 177.828)
		(end 125.576 177.222)
		(width 0.201)
		(layer "F.Cu")
		(net 768)
	)
	(segment
		(start 159.31 167.5)
		(end 159.31 164.614999)
		(width 0.256)
		(layer "F.Cu")
		(net 768)
	)
	(segment
		(start 132.206 172.612)
		(end 133.316 172.612)
		(width 0.201)
		(layer "F.Cu")
		(net 768)
	)
	(segment
		(start 159.66 167.85)
		(end 159.31 167.5)
		(width 0.256)
		(layer "F.Cu")
		(net 768)
	)
	(via
		(at 131.536 173.782)
		(size 0.45)
		(drill 0.1)
		(layers "F.Cu" "B.Cu")
		(remove_unused_layers yes)
		(keep_end_layers yes)
		(zone_layer_connections)
		(net 768)
	)
	(via
		(at 133.316 172.612)
		(size 0.45)
		(drill 0.1)
		(layers "F.Cu" "B.Cu")
		(remove_unused_layers yes)
		(keep_end_layers yes)
		(zone_layer_connections)
		(net 768)
	)
	(via
		(at 159.66 167.85)
		(size 0.45)
		(drill 0.1)
		(layers "F.Cu" "B.Cu")
		(remove_unused_layers yes)
		(keep_end_layers yes)
		(zone_layer_connections)
		(net 768)
	)
	(via
		(at 177.5 151.5)
		(size 0.45)
		(drill 0.1)
		(layers "F.Cu" "B.Cu")
		(remove_unused_layers yes)
		(keep_end_layers yes)
		(zone_layer_connections)
		(net 768)
	)
	(segment
		(start 133.64 173.87)
		(end 133.64 172.936)
		(width 0.201)
		(layer "B.Cu")
		(net 768)
	)
	(segment
		(start 133.64 172.936)
		(end 133.316 172.612)
		(width 0.201)
		(layer "B.Cu")
		(net 768)
	)
	(segment
		(start 159.28 157.71)
		(end 160.165001 156.824999)
		(width 0.1)
		(layer "In2.Cu")
		(net 768)
	)
	(segment
		(start 160.165001 156.824999)
		(end 167.765001 156.824999)
		(width 0.1)
		(layer "In2.Cu")
		(net 768)
	)
	(segment
		(start 159.66 168.34)
		(end 147.05 180.95)
		(width 0.1)
		(layer "In2.Cu")
		(net 768)
	)
	(segment
		(start 144.8 180.95)
		(end 142.65 183.1)
		(width 0.1)
		(layer "In2.Cu")
		(net 768)
	)
	(segment
		(start 131.536 173.514)
		(end 131.536 173.782)
		(width 0.1)
		(layer "In2.Cu")
		(net 768)
	)
	(segment
		(start 132.438 172.612)
		(end 131.536 173.514)
		(width 0.1)
		(layer "In2.Cu")
		(net 768)
	)
	(segment
		(start 177 152)
		(end 177.5 151.5)
		(width 0.1)
		(layer "In2.Cu")
		(net 768)
	)
	(segment
		(start 133.316 172.612)
		(end 132.438 172.612)
		(width 0.1)
		(layer "In2.Cu")
		(net 768)
	)
	(segment
		(start 159.66 167.85)
		(end 159.28 167.47)
		(width 0.1)
		(layer "In2.Cu")
		(net 768)
	)
	(segment
		(start 159.28 167.47)
		(end 159.28 157.71)
		(width 0.1)
		(layer "In2.Cu")
		(net 768)
	)
	(segment
		(start 140.5 183.1)
		(end 136.2 178.8)
		(width 0.1)
		(layer "In2.Cu")
		(net 768)
	)
	(segment
		(start 167.765001 156.824999)
		(end 172.59 152)
		(width 0.1)
		(layer "In2.Cu")
		(net 768)
	)
	(segment
		(start 133.316 175.016)
		(end 133.316 172.612)
		(width 0.1)
		(layer "In2.Cu")
		(net 768)
	)
	(segment
		(start 136.2 177.9)
		(end 133.316 175.016)
		(width 0.1)
		(layer "In2.Cu")
		(net 768)
	)
	(segment
		(start 172.59 152)
		(end 177 152)
		(width 0.1)
		(layer "In2.Cu")
		(net 768)
	)
	(segment
		(start 147.05 180.95)
		(end 144.8 180.95)
		(width 0.1)
		(layer "In2.Cu")
		(net 768)
	)
	(segment
		(start 142.65 183.1)
		(end 140.5 183.1)
		(width 0.1)
		(layer "In2.Cu")
		(net 768)
	)
	(segment
		(start 159.66 167.85)
		(end 159.66 168.34)
		(width 0.1)
		(layer "In2.Cu")
		(net 768)
	)
	(segment
		(start 136.2 178.8)
		(end 136.2 177.9)
		(width 0.1)
		(layer "In2.Cu")
		(net 768)
	)
	(segment
		(start 126.076 177.252)
		(end 125.246 176.422)
		(width 0.201)
		(layer "F.Cu")
		(net 769)
	)
	(segment
		(start 125.246 176.422)
		(end 125.246 174.952)
		(width 0.201)
		(layer "F.Cu")
		(net 769)
	)
	(segment
		(start 126.076 177.828)
		(end 126.076 177.252)
		(width 0.201)
		(layer "F.Cu")
		(net 769)
	)
	(segment
		(start 159.81 167.06)
		(end 160.05 167.3)
		(width 0.256)
		(layer "F.Cu")
		(net 769)
	)
	(segment
		(start 178.9995 151.9995)
		(end 178.5 151.5)
		(width 0.256)
		(layer "F.Cu")
		(net 769)
	)
	(segment
		(start 132.206 173.113)
		(end 132.926 173.113)
		(width 0.201)
		(layer "F.Cu")
		(net 769)
	)
	(segment
		(start 132.926 173.692)
		(end 132.926 173.113)
		(width 0.201)
		(layer "F.Cu")
		(net 769)
	)
	(segment
		(start 159.81 164.614999)
		(end 159.81 167.06)
		(width 0.256)
		(layer "F.Cu")
		(net 769)
	)
	(segment
		(start 125.976 174.222)
		(end 132.396 174.222)
		(width 0.201)
		(layer "F.Cu")
		(net 769)
	)
	(segment
		(start 132.396 174.222)
		(end 132.926 173.692)
		(width 0.201)
		(layer "F.Cu")
		(net 769)
	)
	(segment
		(start 125.246 174.952)
		(end 125.976 174.222)
		(width 0.201)
		(layer "F.Cu")
		(net 769)
	)
	(via
		(at 178.5 151.5)
		(size 0.45)
		(drill 0.1)
		(layers "F.Cu" "B.Cu")
		(remove_unused_layers yes)
		(keep_end_layers yes)
		(zone_layer_connections)
		(net 769)
	)
	(via
		(at 160.05 167.3)
		(size 0.45)
		(drill 0.1)
		(layers "F.Cu" "B.Cu")
		(remove_unused_layers yes)
		(keep_end_layers yes)
		(zone_layer_connections)
		(net 769)
	)
	(via
		(at 132.926 173.113)
		(size 0.45)
		(drill 0.1)
		(layers "F.Cu" "B.Cu")
		(remove_unused_layers yes)
		(keep_end_layers yes)
		(zone_layer_connections)
		(net 769)
	)
	(segment
		(start 132.63 173.409)
		(end 132.926 173.113)
		(width 0.201)
		(layer "B.Cu")
		(net 769)
	)
	(segment
		(start 132.63 173.87)
		(end 132.63 173.409)
		(width 0.201)
		(layer "B.Cu")
		(net 769)
	)
	(segment
		(start 178.15 151.5)
		(end 177.3 152.35)
		(width 0.1)
		(layer "In2.Cu")
		(net 769)
	)
	(segment
		(start 144.95 181.3)
		(end 142.845434 183.404566)
		(width 0.1)
		(layer "In2.Cu")
		(net 769)
	)
	(segment
		(start 160.355001 157.574999)
		(end 159.81 158.12)
		(width 0.1)
		(layer "In2.Cu")
		(net 769)
	)
	(segment
		(start 140.304566 183.404566)
		(end 135.049499 178.149499)
		(width 0.1)
		(layer "In2.Cu")
		(net 769)
	)
	(segment
		(start 147.45 181.3)
		(end 144.95 181.3)
		(width 0.1)
		(layer "In2.Cu")
		(net 769)
	)
	(segment
		(start 161.195001 157.574999)
		(end 160.355001 157.574999)
		(width 0.1)
		(layer "In2.Cu")
		(net 769)
	)
	(segment
		(start 177.3 152.35)
		(end 172.72 152.35)
		(width 0.1)
		(layer "In2.Cu")
		(net 769)
	)
	(segment
		(start 178.5 151.5)
		(end 178.15 151.5)
		(width 0.1)
		(layer "In2.Cu")
		(net 769)
	)
	(segment
		(start 135.049499 178.149499)
		(end 135.049499 177.149499)
		(width 0.1)
		(layer "In2.Cu")
		(net 769)
	)
	(segment
		(start 172.72 152.35)
		(end 167.97 157.1)
		(width 0.1)
		(layer "In2.Cu")
		(net 769)
	)
	(segment
		(start 159.81 158.12)
		(end 159.81 167.06)
		(width 0.1)
		(layer "In2.Cu")
		(net 769)
	)
	(segment
		(start 160.035 167.315)
		(end 160.035 168.715)
		(width 0.1)
		(layer "In2.Cu")
		(net 769)
	)
	(segment
		(start 135.049499 177.149499)
		(end 132.926 175.026)
		(width 0.1)
		(layer "In2.Cu")
		(net 769)
	)
	(segment
		(start 159.81 167.06)
		(end 160.05 167.3)
		(width 0.1)
		(layer "In2.Cu")
		(net 769)
	)
	(segment
		(start 142.845434 183.404566)
		(end 140.304566 183.404566)
		(width 0.1)
		(layer "In2.Cu")
		(net 769)
	)
	(segment
		(start 161.67 157.1)
		(end 161.195001 157.574999)
		(width 0.1)
		(layer "In2.Cu")
		(net 769)
	)
	(segment
		(start 132.926 175.026)
		(end 132.926 173.113)
		(width 0.1)
		(layer "In2.Cu")
		(net 769)
	)
	(segment
		(start 160.035 168.715)
		(end 147.45 181.3)
		(width 0.1)
		(layer "In2.Cu")
		(net 769)
	)
	(segment
		(start 167.97 157.1)
		(end 161.67 157.1)
		(width 0.1)
		(layer "In2.Cu")
		(net 769)
	)
	(segment
		(start 160.05 167.3)
		(end 160.035 167.315)
		(width 0.1)
		(layer "In2.Cu")
		(net 769)
	)
	(segment
		(start 245.202 185.251)
		(end 245.2 185.249)
		(width 0.182)
		(layer "F.Cu")
		(net 771)
	)
	(segment
		(start 180.9995 154.0005)
		(end 180.5 154.5)
		(width 0.256)
		(layer "F.Cu")
		(net 771)
	)
	(segment
		(start 245.88 185.251)
		(end 245.202 185.251)
		(width 0.182)
		(layer "F.Cu")
		(net 771)
	)
	(via
		(at 180.5 154.5)
		(size 0.45)
		(drill 0.1)
		(layers "F.Cu" "B.Cu")
		(remove_unused_layers yes)
		(keep_end_layers yes)
		(zone_layer_connections)
		(net 771)
	)
	(via
		(at 245.2 185.249)
		(size 0.45)
		(drill 0.1)
		(layers "F.Cu" "B.Cu")
		(remove_unused_layers yes)
		(keep_end_layers yes)
		(zone_layer_connections)
		(net 771)
	)
	(segment
		(start 246.95 186.299)
		(end 245.9 185.249)
		(width 0.182)
		(layer "B.Cu")
		(net 771)
	)
	(segment
		(start 245.249 185.298)
		(end 245.2 185.249)
		(width 0.182)
		(layer "B.Cu")
		(net 771)
	)
	(segment
		(start 245.9 185.249)
		(end 245.2 185.249)
		(width 0.182)
		(layer "B.Cu")
		(net 771)
	)
	(segment
		(start 246.995 186.299)
		(end 246.95 186.299)
		(width 0.182)
		(layer "B.Cu")
		(net 771)
	)
	(segment
		(start 180.5 154.5)
		(end 181 155)
		(width 0.1)
		(layer "In2.Cu")
		(net 771)
	)
	(segment
		(start 173 176.5)
		(end 183.5 176.5)
		(width 0.1)
		(layer "In2.Cu")
		(net 771)
	)
	(segment
		(start 245.2 185.7)
		(end 245.2 185.249)
		(width 0.1)
		(layer "In2.Cu")
		(net 771)
	)
	(segment
		(start 171 174.5)
		(end 173 176.5)
		(width 0.1)
		(layer "In2.Cu")
		(net 771)
	)
	(segment
		(start 223.015876 186.425)
		(end 223.190876 186.25)
		(width 0.1)
		(layer "In2.Cu")
		(net 771)
	)
	(segment
		(start 183.5 176.5)
		(end 193 186)
		(width 0.1)
		(layer "In2.Cu")
		(net 771)
	)
	(segment
		(start 220.375 186.425)
		(end 223.015876 186.425)
		(width 0.1)
		(layer "In2.Cu")
		(net 771)
	)
	(segment
		(start 227.16 186.51)
		(end 234.51 186.51)
		(width 0.1)
		(layer "In2.Cu")
		(net 771)
	)
	(segment
		(start 236 188)
		(end 242.9 188)
		(width 0.1)
		(layer "In2.Cu")
		(net 771)
	)
	(segment
		(start 219.885 185.935)
		(end 220.375 186.425)
		(width 0.1)
		(layer "In2.Cu")
		(net 771)
	)
	(segment
		(start 180.530331 163)
		(end 173.5 163)
		(width 0.1)
		(layer "In2.Cu")
		(net 771)
	)
	(segment
		(start 173.5 163)
		(end 171 165.5)
		(width 0.1)
		(layer "In2.Cu")
		(net 771)
	)
	(segment
		(start 226.9 186.25)
		(end 227.16 186.51)
		(width 0.1)
		(layer "In2.Cu")
		(net 771)
	)
	(segment
		(start 171 165.5)
		(end 171 174.5)
		(width 0.1)
		(layer "In2.Cu")
		(net 771)
	)
	(segment
		(start 211.665 185.935)
		(end 219.885 185.935)
		(width 0.1)
		(layer "In2.Cu")
		(net 771)
	)
	(segment
		(start 181 162.530331)
		(end 180.530331 163)
		(width 0.1)
		(layer "In2.Cu")
		(net 771)
	)
	(segment
		(start 234.51 186.51)
		(end 236 188)
		(width 0.1)
		(layer "In2.Cu")
		(net 771)
	)
	(segment
		(start 242.9 188)
		(end 245.2 185.7)
		(width 0.1)
		(layer "In2.Cu")
		(net 771)
	)
	(segment
		(start 181 155)
		(end 181 162.530331)
		(width 0.1)
		(layer "In2.Cu")
		(net 771)
	)
	(segment
		(start 223.190876 186.25)
		(end 226.9 186.25)
		(width 0.1)
		(layer "In2.Cu")
		(net 771)
	)
	(segment
		(start 211.6 186)
		(end 211.665 185.935)
		(width 0.1)
		(layer "In2.Cu")
		(net 771)
	)
	(segment
		(start 193 186)
		(end 211.6 186)
		(width 0.1)
		(layer "In2.Cu")
		(net 771)
	)
	(segment
		(start 176.999499 151.9995)
		(end 176.5 151.500001)
		(width 0.256)
		(layer "F.Cu")
		(net 772)
	)
	(segment
		(start 124.1995 163.989)
		(end 124.1995 164.417972)
		(width 0.1)
		(layer "F.Cu")
		(net 772)
	)
	(segment
		(start 124.1995 164.417972)
		(end 124.473467 164.691939)
		(width 0.1)
		(layer "F.Cu")
		(net 772)
	)
	(via
		(at 124.473467 164.691939)
		(size 0.45)
		(drill 0.1)
		(layers "F.Cu" "B.Cu")
		(remove_unused_layers yes)
		(keep_end_layers yes)
		(zone_layer_connections)
		(net 772)
	)
	(via
		(at 176.5 151.500001)
		(size 0.45)
		(drill 0.1)
		(layers "F.Cu" "B.Cu")
		(remove_unused_layers yes)
		(keep_end_layers yes)
		(zone_layer_connections)
		(net 772)
	)
	(segment
		(start 128.14 161.62)
		(end 126.26 163.5)
		(width 0.1)
		(layer "In2.Cu")
		(net 772)
	)
	(segment
		(start 131.88 161.62)
		(end 133.5 160)
		(width 0.1)
		(layer "In2.Cu")
		(net 772)
	)
	(segment
		(start 134.6 160)
		(end 139.19 155.41)
		(width 0.1)
		(layer "In2.Cu")
		(net 772)
	)
	(segment
		(start 125 163.5)
		(end 126.26 163.5)
		(width 0.1)
		(layer "In2.Cu")
		(net 772)
	)
	(segment
		(start 124.473467 164.691939)
		(end 124.473467 164.026533)
		(width 0.1)
		(layer "In2.Cu")
		(net 772)
	)
	(segment
		(start 133.5 160)
		(end 134.6 160)
		(width 0.1)
		(layer "In2.Cu")
		(net 772)
	)
	(segment
		(start 161.27 152.18)
		(end 164.1 149.35)
		(width 0.1)
		(layer "In2.Cu")
		(net 772)
	)
	(segment
		(start 164.1 149.35)
		(end 171.12 149.35)
		(width 0.1)
		(layer "In2.Cu")
		(net 772)
	)
	(segment
		(start 175.999999 151)
		(end 176.5 151.500001)
		(width 0.1)
		(layer "In2.Cu")
		(net 772)
	)
	(segment
		(start 124.473467 164.026533)
		(end 125 163.5)
		(width 0.1)
		(layer "In2.Cu")
		(net 772)
	)
	(segment
		(start 149.77 155.41)
		(end 153 152.18)
		(width 0.1)
		(layer "In2.Cu")
		(net 772)
	)
	(segment
		(start 172.77 151)
		(end 175.999999 151)
		(width 0.1)
		(layer "In2.Cu")
		(net 772)
	)
	(segment
		(start 139.19 155.41)
		(end 149.77 155.41)
		(width 0.1)
		(layer "In2.Cu")
		(net 772)
	)
	(segment
		(start 171.12 149.35)
		(end 172.77 151)
		(width 0.1)
		(layer "In2.Cu")
		(net 772)
	)
	(segment
		(start 153 152.18)
		(end 161.27 152.18)
		(width 0.1)
		(layer "In2.Cu")
		(net 772)
	)
	(segment
		(start 131.88 161.62)
		(end 128.14 161.62)
		(width 0.1)
		(layer "In2.Cu")
		(net 772)
	)
	(segment
		(start 201.5 154.5)
		(end 201.0005 154.0005)
		(width 0.256)
		(layer "F.Cu")
		(net 773)
	)
	(segment
		(start 241.001 142.099)
		(end 240 142.099)
		(width 0.256)
		(layer "F.Cu")
		(net 773)
	)
	(via
		(at 201.5 154.5)
		(size 0.45)
		(drill 0.1)
		(layers "F.Cu" "B.Cu")
		(remove_unused_layers yes)
		(keep_end_layers yes)
		(zone_layer_connections)
		(net 773)
	)
	(via
		(at 240 142.099)
		(size 0.45)
		(drill 0.1)
		(layers "F.Cu" "B.Cu")
		(remove_unused_layers yes)
		(keep_end_layers yes)
		(zone_layer_connections)
		(net 773)
	)
	(segment
		(start 201 154)
		(end 201.5 154.5)
		(width 0.256)
		(layer "B.Cu")
		(net 773)
	)
	(segment
		(start 209.394041 154.555959)
		(end 206.594041 154.555959)
		(width 0.1)
		(layer "In2.Cu")
		(net 773)
	)
	(segment
		(start 217.5 149.2)
		(end 216.85 149.2)
		(width 0.1)
		(layer "In2.Cu")
		(net 773)
	)
	(segment
		(start 218.425 148.275)
		(end 217.5 149.2)
		(width 0.1)
		(layer "In2.Cu")
		(net 773)
	)
	(segment
		(start 210.3 153.65)
		(end 209.394041 154.555959)
		(width 0.1)
		(layer "In2.Cu")
		(net 773)
	)
	(segment
		(start 218.425 147.075)
		(end 218.425 148.275)
		(width 0.1)
		(layer "In2.Cu")
		(net 773)
	)
	(segment
		(start 215.65 151.65)
		(end 214.55 152.75)
		(width 0.1)
		(layer "In2.Cu")
		(net 773)
	)
	(segment
		(start 204.05 154.85)
		(end 203.7 154.5)
		(width 0.1)
		(layer "In2.Cu")
		(net 773)
	)
	(segment
		(start 211.3 153.65)
		(end 210.3 153.65)
		(width 0.1)
		(layer "In2.Cu")
		(net 773)
	)
	(segment
		(start 235.7 142.099)
		(end 231.649 146.15)
		(width 0.1)
		(layer "In2.Cu")
		(net 773)
	)
	(segment
		(start 206.3 154.85)
		(end 204.05 154.85)
		(width 0.1)
		(layer "In2.Cu")
		(net 773)
	)
	(segment
		(start 214.55 152.75)
		(end 212.2 152.75)
		(width 0.1)
		(layer "In2.Cu")
		(net 773)
	)
	(segment
		(start 203.7 154.5)
		(end 201.5 154.5)
		(width 0.1)
		(layer "In2.Cu")
		(net 773)
	)
	(segment
		(start 231.649 146.15)
		(end 219.35 146.15)
		(width 0.1)
		(layer "In2.Cu")
		(net 773)
	)
	(segment
		(start 215.65 150.4)
		(end 215.65 151.65)
		(width 0.1)
		(layer "In2.Cu")
		(net 773)
	)
	(segment
		(start 219.35 146.15)
		(end 218.425 147.075)
		(width 0.1)
		(layer "In2.Cu")
		(net 773)
	)
	(segment
		(start 216.85 149.2)
		(end 215.65 150.4)
		(width 0.1)
		(layer "In2.Cu")
		(net 773)
	)
	(segment
		(start 206.594041 154.555959)
		(end 206.3 154.85)
		(width 0.1)
		(layer "In2.Cu")
		(net 773)
	)
	(segment
		(start 212.2 152.75)
		(end 211.3 153.65)
		(width 0.1)
		(layer "In2.Cu")
		(net 773)
	)
	(segment
		(start 240 142.099)
		(end 235.7 142.099)
		(width 0.1)
		(layer "In2.Cu")
		(net 773)
	)
	(segment
		(start 244.25 185.869)
		(end 244.368 185.751)
		(width 0.182)
		(layer "F.Cu")
		(net 774)
	)
	(segment
		(start 244.368 185.751)
		(end 245.88 185.751)
		(width 0.182)
		(layer "F.Cu")
		(net 774)
	)
	(segment
		(start 244.63 186.249)
		(end 244.25 185.869)
		(width 0.182)
		(layer "F.Cu")
		(net 774)
	)
	(segment
		(start 244.25 184.879)
		(end 244.25 185.869)
		(width 0.182)
		(layer "F.Cu")
		(net 774)
	)
	(segment
		(start 245.88 186.249)
		(end 244.63 186.249)
		(width 0.182)
		(layer "F.Cu")
		(net 774)
	)
	(segment
		(start 251.91 181.558)
		(end 251.95 181.598)
		(width 0.182)
		(layer "F.Cu")
		(net 775)
	)
	(segment
		(start 247.8 183.899)
		(end 247.8 185.499)
		(width 0.182)
		(layer "F.Cu")
		(net 775)
	)
	(segment
		(start 249.1 182.599)
		(end 247.8 183.899)
		(width 0.182)
		(layer "F.Cu")
		(net 775)
	)
	(segment
		(start 249.582 185.751)
		(end 249.8 185.969)
		(width 0.182)
		(layer "F.Cu")
		(net 775)
	)
	(segment
		(start 249.1 182.599)
		(end 250.101 181.598)
		(width 0.182)
		(layer "F.Cu")
		(net 775)
	)
	(segment
		(start 247.8 185.499)
		(end 248.052 185.751)
		(width 0.182)
		(layer "F.Cu")
		(net 775)
	)
	(segment
		(start 248.052 185.751)
		(end 248.629 185.751)
		(width 0.182)
		(layer "F.Cu")
		(net 775)
	)
	(segment
		(start 250.101 181.598)
		(end 250.95 181.598)
		(width 0.182)
		(layer "F.Cu")
		(net 775)
	)
	(segment
		(start 248.629 185.751)
		(end 249.582 185.751)
		(width 0.182)
		(layer "F.Cu")
		(net 775)
	)
	(segment
		(start 250.95 181.598)
		(end 251.95 181.598)
		(width 0.182)
		(layer "F.Cu")
		(net 775)
	)
	(via
		(at 249.1 182.599)
		(size 0.45)
		(drill 0.1)
		(layers "F.Cu" "B.Cu")
		(remove_unused_layers yes)
		(keep_end_layers yes)
		(zone_layer_connections)
		(net 775)
	)
	(segment
		(start 249.1 182.599)
		(end 249.1 182.769)
		(width 0.182)
		(layer "B.Cu")
		(net 775)
	)
	(segment
		(start 250.38 183.169)
		(end 250.05 183.169)
		(width 0.182)
		(layer "B.Cu")
		(net 775)
	)
	(segment
		(start 250.7 182.849)
		(end 250.38 183.169)
		(width 0.182)
		(layer "B.Cu")
		(net 775)
	)
	(segment
		(start 249.5 183.169)
		(end 250.05 183.169)
		(width 0.182)
		(layer "B.Cu")
		(net 775)
	)
	(segment
		(start 251.223 182.849)
		(end 250.7 182.849)
		(width 0.182)
		(layer "B.Cu")
		(net 775)
	)
	(segment
		(start 249.1 182.769)
		(end 249.5 183.169)
		(width 0.182)
		(layer "B.Cu")
		(net 775)
	)
	(segment
		(start 139.934 167.640499)
		(end 139.925499 167.649)
		(width 0.15)
		(layer "F.Cu")
		(net 776)
	)
	(segment
		(start 139.934 166.772)
		(end 139.934 167.640499)
		(width 0.15)
		(layer "F.Cu")
		(net 776)
	)
	(via
		(at 139.925499 167.649)
		(size 0.45)
		(drill 0.1)
		(layers "F.Cu" "B.Cu")
		(remove_unused_layers yes)
		(keep_end_layers yes)
		(zone_layer_connections)
		(net 776)
	)
	(segment
		(start 139.924499 166.499)
		(end 139.924499 167.648)
		(width 0.256)
		(layer "B.Cu")
		(net 776)
	)
	(segment
		(start 139.924499 167.648)
		(end 139.925499 167.649)
		(width 0.256)
		(layer "B.Cu")
		(net 776)
	)
	(segment
		(start 232.290001 183.940002)
		(end 232.835 183.940001)
		(width 0.1)
		(layer "F.Cu")
		(net 777)
	)
	(via
		(at 232.835 183.940001)
		(size 0.45)
		(drill 0.1)
		(layers "F.Cu" "B.Cu")
		(remove_unused_layers yes)
		(keep_end_layers yes)
		(zone_layer_connections)
		(net 777)
	)
	(segment
		(start 234.612313 183.362313)
		(end 234.612313 184.187687)
		(width 0.198)
		(layer "B.Cu")
		(net 777)
	)
	(segment
		(start 234.25 182.985)
		(end 234.25 183)
		(width 0.198)
		(layer "B.Cu")
		(net 777)
	)
	(segment
		(start 232.835 183.940001)
		(end 232.835 184.21)
		(width 0.15)
		(layer "B.Cu")
		(net 777)
	)
	(segment
		(start 234.25 183)
		(end 234.612313 183.362313)
		(width 0.198)
		(layer "B.Cu")
		(net 777)
	)
	(segment
		(start 234.075 184.725)
		(end 233.35 184.725)
		(width 0.198)
		(layer "B.Cu")
		(net 777)
	)
	(segment
		(start 234.612313 184.187687)
		(end 234.075 184.725)
		(width 0.198)
		(layer "B.Cu")
		(net 777)
	)
	(segment
		(start 232.835 184.21)
		(end 233.35 184.725)
		(width 0.15)
		(layer "B.Cu")
		(net 777)
	)
	(segment
		(start 180.9995 153.0005)
		(end 180.5 153.5)
		(width 0.256)
		(layer "F.Cu")
		(net 778)
	)
	(via
		(at 180.5 153.5)
		(size 0.45)
		(drill 0.1)
		(layers "F.Cu" "B.Cu")
		(remove_unused_layers yes)
		(keep_end_layers yes)
		(zone_layer_connections)
		(net 778)
	)
	(via
		(at 244.894913 184.24137)
		(size 0.45)
		(drill 0.1)
		(layers "F.Cu" "B.Cu")
		(remove_unused_layers yes)
		(keep_end_layers yes)
		(zone_layer_connections)
		(net 778)
	)
	(segment
		(start 244.894913 183.834087)
		(end 245.1 183.629)
		(width 0.182)
		(layer "B.Cu")
		(net 778)
	)
	(segment
		(start 245.522 184.051)
		(end 245.1 183.629)
		(width 0.182)
		(layer "B.Cu")
		(net 778)
	)
	(segment
		(start 246.123 184.051)
		(end 245.522 184.051)
		(width 0.182)
		(layer "B.Cu")
		(net 778)
	)
	(segment
		(start 244.894913 184.24137)
		(end 244.894913 183.834087)
		(width 0.182)
		(layer "B.Cu")
		(net 778)
	)
	(segment
		(start 183 177)
		(end 193.06 187.06)
		(width 0.1)
		(layer "In2.Cu")
		(net 778)
	)
	(segment
		(start 245.64137 184.24137)
		(end 244.894913 184.24137)
		(width 0.1)
		(layer "In2.Cu")
		(net 778)
	)
	(segment
		(start 180 161.530331)
		(end 179.530331 162)
		(width 0.1)
		(layer "In2.Cu")
		(net 778)
	)
	(segment
		(start 223.2 187.3)
		(end 231.35 187.3)
		(width 0.1)
		(layer "In2.Cu")
		(net 778)
	)
	(segment
		(start 173.5 162)
		(end 170.5 165)
		(width 0.1)
		(layer "In2.Cu")
		(net 778)
	)
	(segment
		(start 218.1 187.55)
		(end 222.95 187.55)
		(width 0.1)
		(layer "In2.Cu")
		(net 778)
	)
	(segment
		(start 170.5 165)
		(end 170.5 174.5)
		(width 0.1)
		(layer "In2.Cu")
		(net 778)
	)
	(segment
		(start 173 177)
		(end 183 177)
		(width 0.1)
		(layer "In2.Cu")
		(net 778)
	)
	(segment
		(start 235.1 187.6)
		(end 235.8 188.3)
		(width 0.1)
		(layer "In2.Cu")
		(net 778)
	)
	(segment
		(start 245.85 187.65)
		(end 245.85 184.45)
		(width 0.1)
		(layer "In2.Cu")
		(net 778)
	)
	(segment
		(start 179.530331 162)
		(end 173.5 162)
		(width 0.1)
		(layer "In2.Cu")
		(net 778)
	)
	(segment
		(start 193.06 187.06)
		(end 217.61 187.06)
		(width 0.1)
		(layer "In2.Cu")
		(net 778)
	)
	(segment
		(start 217.61 187.06)
		(end 218.1 187.55)
		(width 0.1)
		(layer "In2.Cu")
		(net 778)
	)
	(segment
		(start 180 154)
		(end 180 161.530331)
		(width 0.1)
		(layer "In2.Cu")
		(net 778)
	)
	(segment
		(start 222.95 187.55)
		(end 223.2 187.3)
		(width 0.1)
		(layer "In2.Cu")
		(net 778)
	)
	(segment
		(start 231.35 187.3)
		(end 231.65 187.6)
		(width 0.1)
		(layer "In2.Cu")
		(net 778)
	)
	(segment
		(start 245.2 188.3)
		(end 245.85 187.65)
		(width 0.1)
		(layer "In2.Cu")
		(net 778)
	)
	(segment
		(start 235.8 188.3)
		(end 245.2 188.3)
		(width 0.1)
		(layer "In2.Cu")
		(net 778)
	)
	(segment
		(start 170.5 174.5)
		(end 173 177)
		(width 0.1)
		(layer "In2.Cu")
		(net 778)
	)
	(segment
		(start 245.85 184.45)
		(end 245.64137 184.24137)
		(width 0.1)
		(layer "In2.Cu")
		(net 778)
	)
	(segment
		(start 180.5 153.5)
		(end 180 154)
		(width 0.1)
		(layer "In2.Cu")
		(net 778)
	)
	(segment
		(start 231.65 187.6)
		(end 235.1 187.6)
		(width 0.1)
		(layer "In2.Cu")
		(net 778)
	)
	(segment
		(start 179.9995 153.0005)
		(end 179.499999 153.5)
		(width 0.256)
		(layer "F.Cu")
		(net 779)
	)
	(via
		(at 179.499999 153.5)
		(size 0.45)
		(drill 0.1)
		(layers "F.Cu" "B.Cu")
		(remove_unused_layers yes)
		(keep_end_layers yes)
		(zone_layer_connections)
		(net 779)
	)
	(via
		(at 249.35 184.149)
		(size 0.45)
		(drill 0.1)
		(layers "F.Cu" "B.Cu")
		(remove_unused_layers yes)
		(keep_end_layers yes)
		(zone_layer_connections)
		(net 779)
	)
	(segment
		(start 251.223 184.151)
		(end 251.223 184.126)
		(width 0.182)
		(layer "B.Cu")
		(net 779)
	)
	(segment
		(start 249.37 184.129)
		(end 249.35 184.149)
		(width 0.182)
		(layer "B.Cu")
		(net 779)
	)
	(segment
		(start 250.072 184.151)
		(end 250.05 184.129)
		(width 0.182)
		(layer "B.Cu")
		(net 779)
	)
	(segment
		(start 250.05 184.129)
		(end 249.37 184.129)
		(width 0.182)
		(layer "B.Cu")
		(net 779)
	)
	(segment
		(start 251.223 184.151)
		(end 250.072 184.151)
		(width 0.182)
		(layer "B.Cu")
		(net 779)
	)
	(segment
		(start 193.2 188.2)
		(end 218.5 188.2)
		(width 0.1)
		(layer "In2.Cu")
		(net 779)
	)
	(segment
		(start 246.84 188.56)
		(end 249.35 186.05)
		(width 0.1)
		(layer "In2.Cu")
		(net 779)
	)
	(segment
		(start 170 174.5)
		(end 173 177.5)
		(width 0.1)
		(layer "In2.Cu")
		(net 779)
	)
	(segment
		(start 178.405331 161.125)
		(end 173.375 161.125)
		(width 0.1)
		(layer "In2.Cu")
		(net 779)
	)
	(segment
		(start 182.5 177.5)
		(end 193.2 188.2)
		(width 0.1)
		(layer "In2.Cu")
		(net 779)
	)
	(segment
		(start 178.95 154.049999)
		(end 178.95 160.580331)
		(width 0.1)
		(layer "In2.Cu")
		(net 779)
	)
	(segment
		(start 173.375 161.125)
		(end 170 164.5)
		(width 0.1)
		(layer "In2.Cu")
		(net 779)
	)
	(segment
		(start 218.5 188.2)
		(end 218.86 188.56)
		(width 0.1)
		(layer "In2.Cu")
		(net 779)
	)
	(segment
		(start 178.95 160.580331)
		(end 178.405331 161.125)
		(width 0.1)
		(layer "In2.Cu")
		(net 779)
	)
	(segment
		(start 179.499999 153.5)
		(end 178.95 154.049999)
		(width 0.1)
		(layer "In2.Cu")
		(net 779)
	)
	(segment
		(start 170 164.5)
		(end 170 174.5)
		(width 0.1)
		(layer "In2.Cu")
		(net 779)
	)
	(segment
		(start 218.86 188.56)
		(end 246.84 188.56)
		(width 0.1)
		(layer "In2.Cu")
		(net 779)
	)
	(segment
		(start 249.35 186.05)
		(end 249.35 184.149)
		(width 0.1)
		(layer "In2.Cu")
		(net 779)
	)
	(segment
		(start 173 177.5)
		(end 182.5 177.5)
		(width 0.1)
		(layer "In2.Cu")
		(net 779)
	)
	(segment
		(start 137.746 159.585)
		(end 137.460499 159.585)
		(width 0.15)
		(layer "F.Cu")
		(net 780)
	)
	(segment
		(start 137.074499 159.199)
		(end 137.074499 158.899)
		(width 0.15)
		(layer "F.Cu")
		(net 780)
	)
	(segment
		(start 139.571499 179.699)
		(end 139.948999 179.699)
		(width 0.201)
		(layer "F.Cu")
		(net 780)
	)
	(segment
		(start 137.460499 159.585)
		(end 137.074499 159.199)
		(width 0.15)
		(layer "F.Cu")
		(net 780)
	)
	(segment
		(start 139.948999 179.699)
		(end 140.124499 179.5235)
		(width 0.201)
		(layer "F.Cu")
		(net 780)
	)
	(via
		(at 140.124499 179.5235)
		(size 0.45)
		(drill 0.1)
		(layers "F.Cu" "B.Cu")
		(remove_unused_layers yes)
		(keep_end_layers yes)
		(zone_layer_connections)
		(net 780)
	)
	(via
		(at 137.074499 158.899)
		(size 0.45)
		(drill 0.1)
		(layers "F.Cu" "B.Cu")
		(remove_unused_layers yes)
		(keep_end_layers yes)
		(zone_layer_connections)
		(net 780)
	)
	(segment
		(start 141.324499 181.949)
		(end 141.624499 181.649)
		(width 0.15)
		(layer "In2.Cu")
		(net 780)
	)
	(segment
		(start 140.990185 179.949)
		(end 140.549999 179.949)
		(width 0.15)
		(layer "In2.Cu")
		(net 780)
	)
	(segment
		(start 137.124499 179.049)
		(end 140.024499 181.949)
		(width 0.15)
		(layer "In2.Cu")
		(net 780)
	)
	(segment
		(start 140.549999 179.949)
		(end 140.124499 179.5235)
		(width 0.15)
		(layer "In2.Cu")
		(net 780)
	)
	(segment
		(start 135.824499 171.949)
		(end 137.124499 173.249)
		(width 0.15)
		(layer "In2.Cu")
		(net 780)
	)
	(segment
		(start 137.074499 159.899)
		(end 135.824499 161.149)
		(width 0.15)
		(layer "In2.Cu")
		(net 780)
	)
	(segment
		(start 141.624499 181.649)
		(end 141.624499 180.583314)
		(width 0.15)
		(layer "In2.Cu")
		(net 780)
	)
	(segment
		(start 141.624499 180.583314)
		(end 140.990185 179.949)
		(width 0.15)
		(layer "In2.Cu")
		(net 780)
	)
	(segment
		(start 140.024499 181.949)
		(end 141.324499 181.949)
		(width 0.15)
		(layer "In2.Cu")
		(net 780)
	)
	(segment
		(start 137.074499 158.899)
		(end 137.074499 159.899)
		(width 0.15)
		(layer "In2.Cu")
		(net 780)
	)
	(segment
		(start 137.124499 173.249)
		(end 137.124499 179.049)
		(width 0.15)
		(layer "In2.Cu")
		(net 780)
	)
	(segment
		(start 135.824499 161.149)
		(end 135.824499 171.949)
		(width 0.15)
		(layer "In2.Cu")
		(net 780)
	)
	(segment
		(start 136.839499 165.084)
		(end 136.824499 165.099)
		(width 0.15)
		(layer "F.Cu")
		(net 781)
	)
	(segment
		(start 137.746 165.084)
		(end 136.839499 165.084)
		(width 0.15)
		(layer "F.Cu")
		(net 781)
	)
	(segment
		(start 137.524499 168.899)
		(end 137.524499 167.599)
		(width 0.15)
		(layer "F.Cu")
		(net 781)
	)
	(via
		(at 137.524499 167.599)
		(size 0.45)
		(drill 0.1)
		(layers "F.Cu" "B.Cu")
		(remove_unused_layers yes)
		(keep_end_layers yes)
		(zone_layer_connections)
		(net 781)
	)
	(via
		(at 136.824499 165.099)
		(size 0.45)
		(drill 0.1)
		(layers "F.Cu" "B.Cu")
		(remove_unused_layers yes)
		(keep_end_layers yes)
		(zone_layer_connections)
		(net 781)
	)
	(segment
		(start 136.824499 165.099)
		(end 137.524499 165.799)
		(width 0.15)
		(layer "B.Cu")
		(net 781)
	)
	(segment
		(start 137.524499 165.799)
		(end 137.524499 167.599)
		(width 0.15)
		(layer "B.Cu")
		(net 781)
	)
	(segment
		(start 252.68 183.894)
		(end 253.075 183.499)
		(width 0.182)
		(layer "B.Cu")
		(net 782)
	)
	(segment
		(start 252.68 185.298)
		(end 252.68 183.894)
		(width 0.182)
		(layer "B.Cu")
		(net 782)
	)
	(segment
		(start 252.68 187.338)
		(end 252.68 186.308)
		(width 0.182)
		(layer "B.Cu")
		(net 782)
	)
	(segment
		(start 252.68 186.308)
		(end 252.68 185.298)
		(width 0.182)
		(layer "B.Cu")
		(net 782)
	)
	(segment
		(start 111.018499 113.455)
		(end 110.21 114.263499)
		(width 0.15)
		(layer "F.Cu")
		(net 783)
	)
	(segment
		(start 120.893539 112.1)
		(end 121.05 112.256461)
		(width 0.182)
		(layer "F.Cu")
		(net 783)
	)
	(segment
		(start 120.3 112.1)
		(end 120.893539 112.1)
		(width 0.182)
		(layer "F.Cu")
		(net 783)
	)
	(segment
		(start 110.21 114.725)
		(end 110.233 114.748)
		(width 0.15)
		(layer "F.Cu")
		(net 783)
	)
	(segment
		(start 110.21 114.263499)
		(end 110.21 114.725)
		(width 0.15)
		(layer "F.Cu")
		(net 783)
	)
	(via
		(at 120.3 112.1)
		(size 0.45)
		(drill 0.1)
		(layers "F.Cu" "B.Cu")
		(remove_unused_layers yes)
		(keep_end_layers yes)
		(zone_layer_connections)
		(net 783)
	)
	(via
		(at 110.999834 113.475166)
		(size 0.45)
		(drill 0.1)
		(layers "F.Cu" "B.Cu")
		(remove_unused_layers yes)
		(keep_end_layers yes)
		(zone_layer_connections)
		(net 783)
	)
	(segment
		(start 110.25 115.3)
		(end 110.25 114.225)
		(width 0.182)
		(layer "B.Cu")
		(net 783)
	)
	(segment
		(start 114.6 116)
		(end 114.15 116.45)
		(width 0.182)
		(layer "B.Cu")
		(net 783)
	)
	(segment
		(start 119.609 112.791)
		(end 115.009 112.791)
		(width 0.182)
		(layer "B.Cu")
		(net 783)
	)
	(segment
		(start 111.4 116.45)
		(end 110.25 115.3)
		(width 0.182)
		(layer "B.Cu")
		(net 783)
	)
	(segment
		(start 120.3 112.1)
		(end 119.609 112.791)
		(width 0.182)
		(layer "B.Cu")
		(net 783)
	)
	(segment
		(start 114.6 113.2)
		(end 114.6 116)
		(width 0.182)
		(layer "B.Cu")
		(net 783)
	)
	(segment
		(start 114.15 116.45)
		(end 111.4 116.45)
		(width 0.182)
		(layer "B.Cu")
		(net 783)
	)
	(segment
		(start 115.009 112.791)
		(end 114.6 113.2)
		(width 0.182)
		(layer "B.Cu")
		(net 783)
	)
	(segment
		(start 110.25 114.225)
		(end 110.999834 113.475166)
		(width 0.182)
		(layer "B.Cu")
		(net 783)
	)
	(segment
		(start 111.061064 116.349)
		(end 112.525 114.885064)
		(width 0.182)
		(layer "F.Cu")
		(net 784)
	)
	(segment
		(start 112.525 112.109)
		(end 112.95 111.684)
		(width 0.182)
		(layer "F.Cu")
		(net 784)
	)
	(segment
		(start 106.318499 116.349)
		(end 105.12 115.150501)
		(width 0.15)
		(layer "F.Cu")
		(net 784)
	)
	(segment
		(start 112.95 111.684)
		(end 114.542 111.684)
		(width 0.182)
		(layer "F.Cu")
		(net 784)
	)
	(segment
		(start 106.318499 116.349)
		(end 111.061064 116.349)
		(width 0.182)
		(layer "F.Cu")
		(net 784)
	)
	(segment
		(start 114.542 111.684)
		(end 115.098 112.24)
		(width 0.182)
		(layer "F.Cu")
		(net 784)
	)
	(segment
		(start 105.12 115.150501)
		(end 105.12 114.725)
		(width 0.15)
		(layer "F.Cu")
		(net 784)
	)
	(segment
		(start 112.525 114.885064)
		(end 112.525 112.109)
		(width 0.182)
		(layer "F.Cu")
		(net 784)
	)
	(segment
		(start 116.851 110.745251)
		(end 116.851 110.727687)
		(width 0.182)
		(layer "F.Cu")
		(net 785)
	)
	(segment
		(start 110.55 110.425)
		(end 107.67 113.305)
		(width 0.182)
		(layer "F.Cu")
		(net 785)
	)
	(segment
		(start 116.851 110.727687)
		(end 116.548313 110.425)
		(width 0.182)
		(layer "F.Cu")
		(net 785)
	)
	(segment
		(start 116.548313 110.425)
		(end 110.55 110.425)
		(width 0.182)
		(layer "F.Cu")
		(net 785)
	)
	(segment
		(start 107.67 113.305)
		(end 107.67 114.725)
		(width 0.182)
		(layer "F.Cu")
		(net 785)
	)
	(segment
		(start 118.098 111.992251)
		(end 116.851 110.745251)
		(width 0.182)
		(layer "F.Cu")
		(net 785)
	)
	(segment
		(start 136.789499 165.584)
		(end 136.474499 165.899)
		(width 0.15)
		(layer "F.Cu")
		(net 786)
	)
	(segment
		(start 137.746 165.584)
		(end 136.789499 165.584)
		(width 0.15)
		(layer "F.Cu")
		(net 786)
	)
	(segment
		(start 137.024499 167.999)
		(end 137.024499 168.899)
		(width 0.15)
		(layer "F.Cu")
		(net 786)
	)
	(via
		(at 137.024499 167.999)
		(size 0.45)
		(drill 0.1)
		(layers "F.Cu" "B.Cu")
		(remove_unused_layers yes)
		(keep_end_layers yes)
		(zone_layer_connections)
		(net 786)
	)
	(via
		(at 136.474499 165.899)
		(size 0.45)
		(drill 0.1)
		(layers "F.Cu" "B.Cu")
		(remove_unused_layers yes)
		(keep_end_layers yes)
		(zone_layer_connections)
		(net 786)
	)
	(segment
		(start 137.024499 166.449)
		(end 137.024499 167.999)
		(width 0.15)
		(layer "B.Cu")
		(net 786)
	)
	(segment
		(start 136.474499 165.899)
		(end 137.024499 166.449)
		(width 0.15)
		(layer "B.Cu")
		(net 786)
	)
	(segment
		(start 137.746 166.084)
		(end 137.139499 166.084)
		(width 0.15)
		(layer "F.Cu")
		(net 787)
	)
	(segment
		(start 136.530499 166.693)
		(end 136.530499 168.899)
		(width 0.15)
		(layer "F.Cu")
		(net 787)
	)
	(segment
		(start 137.139499 166.084)
		(end 136.530499 166.693)
		(width 0.15)
		(layer "F.Cu")
		(net 787)
	)
	(segment
		(start 138.434 167.639499)
		(end 138.024499 168.049)
		(width 0.15)
		(layer "F.Cu")
		(net 788)
	)
	(segment
		(start 138.024499 168.049)
		(end 138.024499 168.899)
		(width 0.15)
		(layer "F.Cu")
		(net 788)
	)
	(segment
		(start 138.434 166.772)
		(end 138.434 167.639499)
		(width 0.15)
		(layer "F.Cu")
		(net 788)
	)
	(segment
		(start 145.621 164.584)
		(end 146.529499 164.584)
		(width 0.15)
		(layer "F.Cu")
		(net 789)
	)
	(segment
		(start 146.954499 164.159)
		(end 147.504499 164.159)
		(width 0.15)
		(layer "F.Cu")
		(net 789)
	)
	(segment
		(start 146.529499 164.584)
		(end 146.954499 164.159)
		(width 0.15)
		(layer "F.Cu")
		(net 789)
	)
	(segment
		(start 146.499499 164.084)
		(end 146.774499 163.809)
		(width 0.15)
		(layer "F.Cu")
		(net 790)
	)
	(segment
		(start 145.621 164.084)
		(end 146.499499 164.084)
		(width 0.15)
		(layer "F.Cu")
		(net 790)
	)
	(segment
		(start 146.774499 163.809)
		(end 147.504499 163.809)
		(width 0.15)
		(layer "F.Cu")
		(net 790)
	)
	(segment
		(start 146.864499 160.459)
		(end 146.641843 160.236344)
		(width 0.15)
		(layer "F.Cu")
		(net 791)
	)
	(segment
		(start 147.504499 160.459)
		(end 146.864499 160.459)
		(width 0.15)
		(layer "F.Cu")
		(net 791)
	)
	(segment
		(start 146.641843 160.236344)
		(end 146.641843 159.913471)
		(width 0.15)
		(layer "F.Cu")
		(net 791)
	)
	(segment
		(start 146.313372 159.585)
		(end 145.621 159.585)
		(width 0.15)
		(layer "F.Cu")
		(net 791)
	)
	(segment
		(start 146.641843 159.913471)
		(end 146.313372 159.585)
		(width 0.15)
		(layer "F.Cu")
		(net 791)
	)
	(segment
		(start 147.504499 160.109)
		(end 147.204499 160.109)
		(width 0.15)
		(layer "F.Cu")
		(net 792)
	)
	(segment
		(start 143.033499 157.9985)
		(end 143.432 158.397001)
		(width 0.15)
		(layer "F.Cu")
		(net 792)
	)
	(segment
		(start 142.973499 157.9985)
		(end 143.033499 157.9985)
		(width 0.15)
		(layer "F.Cu")
		(net 792)
	)
	(segment
		(start 147.204499 160.109)
		(end 146.434499 159.339)
		(width 0.15)
		(layer "F.Cu")
		(net 792)
	)
	(segment
		(start 143.432 158.397001)
		(end 143.432 158.8965)
		(width 0.15)
		(layer "F.Cu")
		(net 792)
	)
	(segment
		(start 146.434499 159.339)
		(end 146.434499 158.989)
		(width 0.15)
		(layer "F.Cu")
		(net 792)
	)
	(via
		(at 146.434499 158.989)
		(size 0.45)
		(drill 0.1)
		(layers "F.Cu" "B.Cu")
		(remove_unused_layers yes)
		(keep_end_layers yes)
		(zone_layer_connections)
		(net 792)
	)
	(via
		(at 142.973499 157.9985)
		(size 0.45)
		(drill 0.1)
		(layers "F.Cu" "B.Cu")
		(remove_unused_layers yes)
		(keep_end_layers yes)
		(zone_layer_connections)
		(net 792)
	)
	(segment
		(start 146.433499 158.9885)
		(end 143.963499 158.9885)
		(width 0.15)
		(layer "B.Cu")
		(net 792)
	)
	(segment
		(start 143.963499 158.9885)
		(end 142.973499 157.9985)
		(width 0.15)
		(layer "B.Cu")
		(net 792)
	)
	(segment
		(start 138.934 157.858501)
		(end 138.574499 157.499)
		(width 0.15)
		(layer "F.Cu")
		(net 793)
	)
	(segment
		(start 138.623499 179.148)
		(end 138.623499 178.15)
		(width 0.201)
		(layer "F.Cu")
		(net 793)
	)
	(segment
		(start 138.934 158.897)
		(end 138.934 157.858501)
		(width 0.15)
		(layer "F.Cu")
		(net 793)
	)
	(segment
		(start 138.623499 178.15)
		(end 138.624499 178.149)
		(width 0.201)
		(layer "F.Cu")
		(net 793)
	)
	(via
		(at 138.624499 178.149)
		(size 0.45)
		(drill 0.1)
		(layers "F.Cu" "B.Cu")
		(remove_unused_layers yes)
		(keep_end_layers yes)
		(zone_layer_connections)
		(net 793)
	)
	(via
		(at 138.574499 157.499)
		(size 0.45)
		(drill 0.1)
		(layers "F.Cu" "B.Cu")
		(remove_unused_layers yes)
		(keep_end_layers yes)
		(zone_layer_connections)
		(net 793)
	)
	(segment
		(start 139.224499 176.549)
		(end 138.624499 177.149)
		(width 0.15)
		(layer "In2.Cu")
		(net 793)
	)
	(segment
		(start 138.824499 172.949)
		(end 139.224499 173.349)
		(width 0.15)
		(layer "In2.Cu")
		(net 793)
	)
	(segment
		(start 138.624499 177.149)
		(end 138.624499 178.149)
		(width 0.15)
		(layer "In2.Cu")
		(net 793)
	)
	(segment
		(start 138.824499 158.449)
		(end 138.824499 172.949)
		(width 0.15)
		(layer "In2.Cu")
		(net 793)
	)
	(segment
		(start 138.574499 158.199)
		(end 138.824499 158.449)
		(width 0.15)
		(layer "In2.Cu")
		(net 793)
	)
	(segment
		(start 138.574499 157.499)
		(end 138.574499 158.199)
		(width 0.15)
		(layer "In2.Cu")
		(net 793)
	)
	(segment
		(start 139.224499 173.349)
		(end 139.224499 176.549)
		(width 0.15)
		(layer "In2.Cu")
		(net 793)
	)
	(segment
		(start 139.571499 180.096)
		(end 140.371499 180.096)
		(width 0.201)
		(layer "F.Cu")
		(net 794)
	)
	(segment
		(start 140.371499 180.096)
		(end 141.124499 180.849)
		(width 0.201)
		(layer "F.Cu")
		(net 794)
	)
	(segment
		(start 138.224499 158.049)
		(end 137.874499 158.049)
		(width 0.15)
		(layer "F.Cu")
		(net 794)
	)
	(segment
		(start 138.434 158.897)
		(end 138.434 158.258501)
		(width 0.15)
		(layer "F.Cu")
		(net 794)
	)
	(segment
		(start 138.434 158.258501)
		(end 138.224499 158.049)
		(width 0.15)
		(layer "F.Cu")
		(net 794)
	)
	(via
		(at 137.874499 158.049)
		(size 0.45)
		(drill 0.1)
		(layers "F.Cu" "B.Cu")
		(remove_unused_layers yes)
		(keep_end_layers yes)
		(zone_layer_connections)
		(net 794)
	)
	(via
		(at 141.124499 180.849)
		(size 0.45)
		(drill 0.1)
		(layers "F.Cu" "B.Cu")
		(remove_unused_layers yes)
		(keep_end_layers yes)
		(zone_layer_connections)
		(net 794)
	)
	(segment
		(start 138.124499 158.849)
		(end 138.124499 178.421088)
		(width 0.15)
		(layer "In2.Cu")
		(net 794)
	)
	(segment
		(start 140.155612 180.452201)
		(end 140.7277 180.452201)
		(width 0.15)
		(layer "In2.Cu")
		(net 794)
	)
	(segment
		(start 140.7277 180.452201)
		(end 141.124499 180.849)
		(width 0.15)
		(layer "In2.Cu")
		(net 794)
	)
	(segment
		(start 138.124499 178.421088)
		(end 140.155612 180.452201)
		(width 0.15)
		(layer "In2.Cu")
		(net 794)
	)
	(segment
		(start 137.874499 158.049)
		(end 137.874499 158.599)
		(width 0.15)
		(layer "In2.Cu")
		(net 794)
	)
	(segment
		(start 137.874499 158.599)
		(end 138.124499 158.849)
		(width 0.15)
		(layer "In2.Cu")
		(net 794)
	)
	(segment
		(start 241.425499 134.757)
		(end 243.23 134.757)
		(width 0.256)
		(layer "F.Cu")
		(net 796)
	)
	(segment
		(start 129.625 142.022851)
		(end 128.525 142.022851)
		(width 0.2)
		(layer "F.Cu")
		(net 797)
	)
	(segment
		(start 128.525 142.022851)
		(end 127.685702 142.022851)
		(width 0.2)
		(layer "F.Cu")
		(net 797)
	)
	(segment
		(start 140.308499 170.733)
		(end 140.308499 170.746501)
		(width 0.1)
		(layer "F.Cu")
		(net 797)
	)
	(segment
		(start 120.025 160.574)
		(end 120.025 161.275)
		(width 0.177)
		(layer "F.Cu")
		(net 797)
	)
	(segment
		(start 134.124499 169.679)
		(end 133.539 169.679)
		(width 0.182)
		(layer "F.Cu")
		(net 797)
	)
	(segment
		(start 199.0005 154.0005)
		(end 199.5 154.5)
		(width 0.256)
		(layer "F.Cu")
		(net 797)
	)
	(segment
		(start 139.674499 170.733)
		(end 140.308499 170.733)
		(width 0.15)
		(layer "F.Cu")
		(net 797)
	)
	(segment
		(start 138.962149 144.485)
		(end 138.102149 144.485)
		(width 0.2)
		(layer "F.Cu")
		(net 797)
	)
	(segment
		(start 118.58 155.65)
		(end 119.35 155.65)
		(width 0.1)
		(layer "F.Cu")
		(net 797)
	)
	(segment
		(start 133.539 169.679)
		(end 133.53 169.67)
		(width 0.182)
		(layer "F.Cu")
		(net 797)
	)
	(segment
		(start 123.6995 163.989)
		(end 123.6995 164.65)
		(width 0.1)
		(layer "F.Cu")
		(net 797)
	)
	(segment
		(start 177.9995 145.9995)
		(end 177.5 145.5)
		(width 0.256)
		(layer "F.Cu")
		(net 797)
	)
	(segment
		(start 186.9995 147.9995)
		(end 186.5 147.5)
		(width 0.256)
		(layer "F.Cu")
		(net 797)
	)
	(segment
		(start 209.9 154.435)
		(end 210.885498 154.434999)
		(width 0.256)
		(layer "F.Cu")
		(net 797)
	)
	(segment
		(start 117.088 112.242921)
		(end 117.042921 112.242921)
		(width 0.1)
		(layer "F.Cu")
		(net 797)
	)
	(segment
		(start 113.325 112.1)
		(end 113.945079 112.1)
		(width 0.256)
		(layer "F.Cu")
		(net 797)
	)
	(segment
		(start 189.0005 147.9995)
		(end 189.5 147.499999)
		(width 0.256)
		(layer "F.Cu")
		(net 797)
	)
	(segment
		(start 136.416328 147.740829)
		(end 136.424499 147.749)
		(width 0.15)
		(layer "F.Cu")
		(net 797)
	)
	(segment
		(start 187.9995 151.9995)
		(end 187.5 151.5)
		(width 0.256)
		(layer "F.Cu")
		(net 797)
	)
	(segment
		(start 210.885498 154.434999)
		(end 210.899998 154.420499)
		(width 0.256)
		(layer "F.Cu")
		(net 797)
	)
	(segment
		(start 250.95 182.558)
		(end 250.359 182.558)
		(width 0.182)
		(layer "F.Cu")
		(net 797)
	)
	(segment
		(start 221.72 152.85)
		(end 223.342 152.85)
		(width 0.4)
		(layer "F.Cu")
		(net 797)
	)
	(segment
		(start 181.9995 147.9995)
		(end 181.499999 147.5)
		(width 0.256)
		(layer "F.Cu")
		(net 797)
	)
	(segment
		(start 208.241 149.9)
		(end 207.6005 149.9)
		(width 0.4)
		(layer "F.Cu")
		(net 797)
	)
	(segment
		(start 129.663851 141.985)
		(end 129.625 142.023851)
		(width 0.256)
		(layer "F.Cu")
		(net 797)
	)
	(segment
		(start 120.025 161.275)
		(end 120.2 161.45)
		(width 0.177)
		(layer "F.Cu")
		(net 797)
	)
	(segment
		(start 196.0005 155.0005)
		(end 196.5 155.5)
		(width 0.256)
		(layer "F.Cu")
		(net 797)
	)
	(segment
		(start 119.35 155.65)
		(end 119.65 155.95)
		(width 0.1)
		(layer "F.Cu")
		(net 797)
	)
	(segment
		(start 165.101 153.498999)
		(end 164.6 153.999999)
		(width 0.4)
		(layer "F.Cu")
		(net 797)
	)
	(segment
		(start 195.0005 157.0005)
		(end 195.5 157.5)
		(width 0.256)
		(layer "F.Cu")
		(net 797)
	)
	(segment
		(start 245.637 177.55)
		(end 244.826499 177.55)
		(width 0.1)
		(layer "F.Cu")
		(net 797)
	)
	(segment
		(start 113.945079 112.1)
		(end 114.098 112.252921)
		(width 0.256)
		(layer "F.Cu")
		(net 797)
	)
	(segment
		(start 131.176 141.985)
		(end 129.663851 141.985)
		(width 0.256)
		(layer "F.Cu")
		(net 797)
	)
	(segment
		(start 168.1 153.5)
		(end 167.6 154)
		(width 0.4)
		(layer "F.Cu")
		(net 797)
	)
	(segment
		(start 187.9995 147.9995)
		(end 187.5 147.5)
		(width 0.256)
		(layer "F.Cu")
		(net 797)
	)
	(segment
		(start 250.359 182.558)
		(end 250.2 182.399)
		(width 0.182)
		(layer "F.Cu")
		(net 797)
	)
	(segment
		(start 117.042921 112.242921)
		(end 116.5 111.7)
		(width 0.114)
		(layer "F.Cu")
		(net 797)
	)
	(segment
		(start 207.6005 149.9)
		(end 207.591 149.8905)
		(width 0.4)
		(layer "F.Cu")
		(net 797)
	)
	(segment
		(start 139.036324 144.410825)
		(end 138.962149 144.485)
		(width 0.2)
		(layer "F.Cu")
		(net 797)
	)
	(segment
		(start 139.402499 170.393)
		(end 139.674499 170.665)
		(width 0.256)
		(layer "F.Cu")
		(net 797)
	)
	(segment
		(start 250.861 182.499)
		(end 250.92 182.558)
		(width 0.182)
		(layer "F.Cu")
		(net 797)
	)
	(segment
		(start 244.826499 177.55)
		(end 244.825499 177.549)
		(width 0.1)
		(layer "F.Cu")
		(net 797)
	)
	(segment
		(start 178.9995 148.999501)
		(end 178.5 148.5)
		(width 0.256)
		(layer "F.Cu")
		(net 797)
	)
	(segment
		(start 136.416328 146.672157)
		(end 136.416328 147.740829)
		(width 0.256)
		(layer "F.Cu")
		(net 797)
	)
	(segment
		(start 120.2 161.73)
		(end 120.2 161.45)
		(width 0.177)
		(layer "F.Cu")
		(net 797)
	)
	(segment
		(start 140.308499 170.746501)
		(end 140.305 170.75)
		(width 0.1)
		(layer "F.Cu")
		(net 797)
	)
	(segment
		(start 190.0005 147.9995)
		(end 190.5 147.5)
		(width 0.256)
		(layer "F.Cu")
		(net 797)
	)
	(segment
		(start 166.1 150.5)
		(end 165.6 150)
		(width 0.4)
		(layer "F.Cu")
		(net 797)
	)
	(segment
		(start 120.62 162.15)
		(end 120.2 161.73)
		(width 0.177)
		(layer "F.Cu")
		(net 797)
	)
	(segment
		(start 138.524499 170.393)
		(end 139.402499 170.393)
		(width 0.256)
		(layer "F.Cu")
		(net 797)
	)
	(segment
		(start 116.65 111.7)
		(end 116.5 111.7)
		(width 0.1)
		(layer "F.Cu")
		(net 797)
	)
	(segment
		(start 191.0005 147.9995)
		(end 191.5 147.5)
		(width 0.256)
		(layer "F.Cu")
		(net 797)
	)
	(via
		(at 136.424499 147.749)
		(size 0.45)
		(drill 0.1)
		(layers "F.Cu" "B.Cu")
		(remove_unused_layers yes)
		(keep_end_layers yes)
		(zone_layer_connections "In8.Cu")
		(net 797)
	)
	(via
		(at 210.899998 154.420499)
		(size 0.45)
		(drill 0.1)
		(layers "F.Cu" "B.Cu")
		(remove_unused_layers yes)
		(keep_end_layers yes)
		(zone_layer_connections "In8.Cu")
		(net 797)
	)
	(via
		(at 221.72 152.85)
		(size 0.45)
		(drill 0.1)
		(layers "F.Cu" "B.Cu")
		(remove_unused_layers yes)
		(keep_end_layers yes)
		(zone_layer_connections "In8.Cu")
		(net 797)
	)
	(via
		(at 244.775 175.375)
		(size 0.45)
		(drill 0.1)
		(layers "F.Cu" "B.Cu")
		(remove_unused_layers yes)
		(keep_end_layers yes)
		(zone_layer_connections "In8.Cu")
		(net 797)
	)
	(via
		(at 195.5 157.5)
		(size 0.45)
		(drill 0.1)
		(layers "F.Cu" "B.Cu")
		(remove_unused_layers yes)
		(keep_end_layers yes)
		(zone_layer_connections "In8.Cu")
		(net 797)
	)
	(via
		(at 178.5 152.5)
		(size 0.45)
		(drill 0.1)
		(layers "F.Cu" "B.Cu")
		(remove_unused_layers yes)
		(keep_end_layers yes)
		(zone_layer_connections "In8.Cu")
		(net 797)
	)
	(via
		(at 187.5 147.5)
		(size 0.45)
		(drill 0.1)
		(layers "F.Cu" "B.Cu")
		(remove_unused_layers yes)
		(keep_end_layers yes)
		(zone_layer_connections "In8.Cu")
		(net 797)
	)
	(via
		(at 230.08 144.84)
		(size 0.45)
		(drill 0.1)
		(layers "F.Cu" "B.Cu")
		(remove_unused_layers yes)
		(keep_end_layers yes)
		(zone_layer_connections "In8.Cu")
		(net 797)
	)
	(via
		(at 243.8 178.2)
		(size 0.45)
		(drill 0.1)
		(layers "F.Cu" "B.Cu")
		(remove_unused_layers yes)
		(keep_end_layers yes)
		(free yes)
		(zone_layer_connections "In8.Cu")
		(net 797)
	)
	(via
		(at 186.5 147.5)
		(size 0.45)
		(drill 0.1)
		(layers "F.Cu" "B.Cu")
		(remove_unused_layers yes)
		(keep_end_layers yes)
		(zone_layer_connections "In8.Cu")
		(net 797)
	)
	(via
		(at 127.685702 142.022851)
		(size 0.45)
		(drill 0.1)
		(layers "F.Cu" "B.Cu")
		(remove_unused_layers yes)
		(keep_end_layers yes)
		(zone_layer_connections "In8.Cu")
		(net 797)
	)
	(via
		(at 196.5 155.5)
		(size 0.45)
		(drill 0.1)
		(layers "F.Cu" "B.Cu")
		(remove_unused_layers yes)
		(keep_end_layers yes)
		(zone_layer_connections "In8.Cu")
		(net 797)
	)
	(via
		(at 140.5 142.6)
		(size 0.45)
		(drill 0.1)
		(layers "F.Cu" "B.Cu")
		(remove_unused_layers yes)
		(keep_end_layers yes)
		(zone_layer_connections "In8.Cu")
		(net 797)
	)
	(via
		(at 140.305 170.75)
		(size 0.45)
		(drill 0.1)
		(layers "F.Cu" "B.Cu")
		(remove_unused_layers yes)
		(keep_end_layers yes)
		(zone_layer_connections "In8.Cu")
		(net 797)
	)
	(via
		(at 207.591 149.8905)
		(size 0.45)
		(drill 0.1)
		(layers "F.Cu" "B.Cu")
		(remove_unused_layers yes)
		(keep_end_layers yes)
		(zone_layer_connections "In8.Cu")
		(net 797)
	)
	(via
		(at 133.53 169.67)
		(size 0.45)
		(drill 0.1)
		(layers "F.Cu" "B.Cu")
		(remove_unused_layers yes)
		(keep_end_layers yes)
		(zone_layer_connections "In8.Cu")
		(net 797)
	)
	(via
		(at 245.475 175.2)
		(size 0.45)
		(drill 0.1)
		(layers "F.Cu" "B.Cu")
		(remove_unused_layers yes)
		(keep_end_layers yes)
		(zone_layer_connections "In8.Cu")
		(net 797)
	)
	(via
		(at 245.74 176.01)
		(size 0.45)
		(drill 0.1)
		(layers "F.Cu" "B.Cu")
		(remove_unused_layers yes)
		(keep_end_layers yes)
		(zone_layer_connections "In8.Cu")
		(net 797)
	)
	(via
		(at 244.7 176.23)
		(size 0.45)
		(drill 0.1)
		(layers "F.Cu" "B.Cu")
		(remove_unused_layers yes)
		(keep_end_layers yes)
		(zone_layer_connections "In8.Cu")
		(net 797)
	)
	(via
		(at 125.5 141.8)
		(size 0.45)
		(drill 0.1)
		(layers "F.Cu" "B.Cu")
		(remove_unused_layers yes)
		(keep_end_layers yes)
		(zone_layer_connections "In8.Cu")
		(net 797)
	)
	(via
		(at 143.5 149)
		(size 0.45)
		(drill 0.1)
		(layers "F.Cu" "B.Cu")
		(remove_unused_layers yes)
		(keep_end_layers yes)
		(zone_layer_connections "In8.Cu")
		(net 797)
	)
	(via
		(at 243.8 175.19)
		(size 0.45)
		(drill 0.1)
		(layers "F.Cu" "B.Cu")
		(remove_unused_layers yes)
		(keep_end_layers yes)
		(zone_layer_connections "In8.Cu")
		(net 797)
	)
	(via
		(at 181.499999 147.5)
		(size 0.45)
		(drill 0.1)
		(layers "F.Cu" "B.Cu")
		(remove_unused_layers yes)
		(keep_end_layers yes)
		(zone_layer_connections "In8.Cu")
		(net 797)
	)
	(via
		(at 191.5 147.5)
		(size 0.45)
		(drill 0.1)
		(layers "F.Cu" "B.Cu")
		(remove_unused_layers yes)
		(keep_end_layers yes)
		(zone_layer_connections "In8.Cu")
		(net 797)
	)
	(via
		(at 189.5 147.499999)
		(size 0.45)
		(drill 0.1)
		(layers "F.Cu" "B.Cu")
		(remove_unused_layers yes)
		(keep_end_layers yes)
		(zone_layer_connections "In8.Cu")
		(net 797)
	)
	(via
		(at 144.324499 148.849)
		(size 0.45)
		(drill 0.1)
		(layers "F.Cu" "B.Cu")
		(remove_unused_layers yes)
		(keep_end_layers yes)
		(zone_layer_connections "In8.Cu")
		(net 797)
	)
	(via
		(at 243.8 175.92)
		(size 0.45)
		(drill 0.1)
		(layers "F.Cu" "B.Cu")
		(remove_unused_layers yes)
		(keep_end_layers yes)
		(zone_layer_connections "In8.Cu")
		(net 797)
	)
	(via
		(at 125.5 142.35)
		(size 0.45)
		(drill 0.1)
		(layers "F.Cu" "B.Cu")
		(remove_unused_layers yes)
		(keep_end_layers yes)
		(zone_layer_connections "In8.Cu")
		(net 797)
	)
	(via
		(at 165.6 150)
		(size 0.45)
		(drill 0.1)
		(layers "F.Cu" "B.Cu")
		(remove_unused_layers yes)
		(keep_end_layers yes)
		(zone_layer_connections "In8.Cu")
		(net 797)
	)
	(via
		(at 120.2 161.45)
		(size 0.45)
		(drill 0.1)
		(layers "F.Cu" "B.Cu")
		(remove_unused_layers yes)
		(keep_end_layers yes)
		(zone_layer_connections "In8.Cu")
		(net 797)
	)
	(via
		(at 139.036324 144.410825)
		(size 0.45)
		(drill 0.1)
		(layers "F.Cu" "B.Cu")
		(remove_unused_layers yes)
		(keep_end_layers yes)
		(zone_layer_connections "In8.Cu")
		(net 797)
	)
	(via
		(at 178.5 148.5)
		(size 0.45)
		(drill 0.1)
		(layers "F.Cu" "B.Cu")
		(remove_unused_layers yes)
		(keep_end_layers yes)
		(zone_layer_connections "In8.Cu")
		(net 797)
	)
	(via
		(at 177.5 145.5)
		(size 0.45)
		(drill 0.1)
		(layers "F.Cu" "B.Cu")
		(remove_unused_layers yes)
		(keep_end_layers yes)
		(zone_layer_connections "In8.Cu")
		(net 797)
	)
	(via
		(at 133.824499 152.9005)
		(size 0.45)
		(drill 0.1)
		(layers "F.Cu" "B.Cu")
		(remove_unused_layers yes)
		(keep_end_layers yes)
		(zone_layer_connections "In8.Cu")
		(net 797)
	)
	(via
		(at 113.325 112.1)
		(size 0.45)
		(drill 0.1)
		(layers "F.Cu" "B.Cu")
		(remove_unused_layers yes)
		(keep_end_layers yes)
		(zone_layer_connections)
		(net 797)
	)
	(via
		(at 138.74 147.5)
		(size 0.45)
		(drill 0.1)
		(layers "F.Cu" "B.Cu")
		(remove_unused_layers yes)
		(keep_end_layers yes)
		(zone_layer_connections "In8.Cu")
		(net 797)
	)
	(via
		(at 119.65 155.95)
		(size 0.45)
		(drill 0.1)
		(layers "F.Cu" "B.Cu")
		(remove_unused_layers yes)
		(keep_end_layers yes)
		(zone_layer_connections "In8.Cu")
		(net 797)
	)
	(via
		(at 220.395 152.373999)
		(size 0.45)
		(drill 0.1)
		(layers "F.Cu" "B.Cu")
		(remove_unused_layers yes)
		(keep_end_layers yes)
		(zone_layer_connections "In8.Cu")
		(net 797)
	)
	(via
		(at 187.5 151.5)
		(size 0.45)
		(drill 0.1)
		(layers "F.Cu" "B.Cu")
		(remove_unused_layers yes)
		(keep_end_layers yes)
		(zone_layer_connections "In8.Cu")
		(net 797)
	)
	(via
		(at 164.6 153.999999)
		(size 0.45)
		(drill 0.1)
		(layers "F.Cu" "B.Cu")
		(remove_unused_layers yes)
		(keep_end_layers yes)
		(zone_layer_connections "In8.Cu")
		(net 797)
	)
	(via
		(at 123.6995 164.65)
		(size 0.45)
		(drill 0.1)
		(layers "F.Cu" "B.Cu")
		(remove_unused_layers yes)
		(keep_end_layers yes)
		(zone_layer_connections "In8.Cu")
		(net 797)
	)
	(via
		(at 234.69 135.24)
		(size 0.45)
		(drill 0.1)
		(layers "F.Cu" "B.Cu")
		(remove_unused_layers yes)
		(keep_end_layers yes)
		(zone_layer_connections)
		(net 797)
	)
	(via
		(at 250.2 182.399)
		(size 0.45)
		(drill 0.1)
		(layers "F.Cu" "B.Cu")
		(remove_unused_layers yes)
		(keep_end_layers yes)
		(zone_layer_connections)
		(net 797)
	)
	(via
		(at 190.5 147.5)
		(size 0.45)
		(drill 0.1)
		(layers "F.Cu" "B.Cu")
		(remove_unused_layers yes)
		(keep_end_layers yes)
		(zone_layer_connections "In8.Cu")
		(net 797)
	)
	(via
		(at 220.395 153.865001)
		(size 0.45)
		(drill 0.1)
		(layers "F.Cu" "B.Cu")
		(remove_unused_layers yes)
		(keep_end_layers yes)
		(zone_layer_connections "In8.Cu")
		(net 797)
	)
	(via
		(at 116.5 111.7)
		(size 0.45)
		(drill 0.1)
		(layers "F.Cu" "B.Cu")
		(remove_unused_layers yes)
		(keep_end_layers yes)
		(zone_layer_connections)
		(net 797)
	)
	(via
		(at 167.6 154)
		(size 0.45)
		(drill 0.1)
		(layers "F.Cu" "B.Cu")
		(remove_unused_layers yes)
		(keep_end_layers yes)
		(zone_layer_connections "In8.Cu")
		(net 797)
	)
	(via
		(at 199.5 154.5)
		(size 0.45)
		(drill 0.1)
		(layers "F.Cu" "B.Cu")
		(remove_unused_layers yes)
		(keep_end_layers yes)
		(zone_layer_connections "In8.Cu")
		(net 797)
	)
	(via
		(at 243.81 177.44)
		(size 0.45)
		(drill 0.1)
		(layers "F.Cu" "B.Cu")
		(remove_unused_layers yes)
		(keep_end_layers yes)
		(zone_layer_connections "In8.Cu")
		(net 797)
	)
	(segment
		(start 140.499 142.599)
		(end 140.5 142.6)
		(width 0.1)
		(layer "B.Cu")
		(net 797)
	)
	(segment
		(start 191.5 147.5)
		(end 191.5 147.498)
		(width 0.256)
		(layer "B.Cu")
		(net 797)
	)
	(segment
		(start 196.01 157.98)
		(end 195.98 157.98)
		(width 0.256)
		(layer "B.Cu")
		(net 797)
	)
	(segment
		(start 191.5 147.498)
		(end 191.002 147)
		(width 0.256)
		(layer "B.Cu")
		(net 797)
	)
	(segment
		(start 180.998 147)
		(end 180.999999 147)
		(width 0.256)
		(layer "B.Cu")
		(net 797)
	)
	(segment
		(start 123.6995 164.65)
		(end 123.6995 164.0705)
		(width 0.1)
		(layer "B.Cu")
		(net 797)
	)
	(segment
		(start 195.998 156.998)
		(end 196 157)
		(width 0.256)
		(layer "B.Cu")
		(net 797)
	)
	(segment
		(start 197 156.999)
		(end 196.001 156.999)
		(width 0.256)
		(layer "B.Cu")
		(net 797)
	)
	(segment
		(start 167.6 154.48)
		(end 167.62 154.5)
		(width 0.4)
		(layer "B.Cu")
		(net 797)
	)
	(segment
		(start 144.324499 148.440499)
		(end 144.324499 148.849)
		(width 0.256)
		(layer "B.Cu")
		(net 797)
	)
	(segment
		(start 137.525 149.565)
		(end 137.5 149.54)
		(width 0.256)
		(layer "B.Cu")
		(net 797)
	)
	(segment
		(start 188.4 147.5)
		(end 187.5 147.5)
		(width 0.4)
		(layer "B.Cu")
		(net 797)
	)
	(segment
		(start 125.5 142.35)
		(end 125.5 142.422149)
		(width 0.2)
		(layer "B.Cu")
		(net 797)
	)
	(segment
		(start 119.65 131.6)
		(end 121.175 130.075)
		(width 0.256)
		(layer "B.Cu")
		(net 797)
	)
	(segment
		(start 113.725 111.7)
		(end 116.5 111.7)
		(width 0.256)
		(layer "B.Cu")
		(net 797)
	)
	(segment
		(start 187.5 147.5)
		(end 187.498 147.5)
		(width 0.256)
		(layer "B.Cu")
		(net 797)
	)
	(segment
		(start 140.124499 142.249)
		(end 140.474499 142.599)
		(width 0.256)
		(layer "B.Cu")
		(net 797)
	)
	(segment
		(start 121.1 114.15)
		(end 121.1 111.829681)
		(width 0.256)
		(layer "B.Cu")
		(net 797)
	)
	(segment
		(start 164.03 154.016)
		(end 163.141 154.016)
		(width 0.4)
		(layer "B.Cu")
		(net 797)
	)
	(segment
		(start 188.6 147.5)
		(end 189.5 147.499999)
		(width 0.4)
		(layer "B.Cu")
		(net 797)
	)
	(segment
		(start 187.498 147.5)
		(end 187 147.002)
		(width 0.256)
		(layer "B.Cu")
		(net 797)
	)
	(segment
		(start 120.125 161.375)
		(end 120.2 161.45)
		(width 0.182)
		(layer "B.Cu")
		(net 797)
	)
	(segment
		(start 177 145)
		(end 177.5 145.5)
		(width 0.256)
		(layer "B.Cu")
		(net 797)
	)
	(segment
		(start 200 154)
		(end 199.5 154.5)
		(width 0.256)
		(layer "B.Cu")
		(net 797)
	)
	(segment
		(start 138.740499 144.115)
		(end 139.036324 144.410825)
		(width 0.256)
		(layer "B.Cu")
		(net 797)
	)
	(segment
		(start 195.98 157.98)
		(end 195.5 157.5)
		(width 0.256)
		(layer "B.Cu")
		(net 797)
	)
	(segment
		(start 207.94 150.49)
		(end 207.89 150.49)
		(width 0.4)
		(layer "B.Cu")
		(net 797)
	)
	(segment
		(start 125.5 141.8)
		(end 124.13 141.8)
		(width 0.256)
		(layer "B.Cu")
		(net 797)
	)
	(segment
		(start 211.426 154.299)
		(end 212.395 153.33)
		(width 0.182)
		(layer "B.Cu")
		(net 797)
	)
	(segment
		(start 188.5 147.6)
		(end 188.6 147.5)
		(width 0.4)
		(layer "B.Cu")
		(net 797)
	)
	(segment
		(start 119.65 137.32)
		(end 119.65 131.6)
		(width 0.256)
		(layer "B.Cu")
		(net 797)
	)
	(segment
		(start 190.502 147.5)
		(end 191.002 147)
		(width 0.256)
		(layer "B.Cu")
		(net 797)
	)
	(segment
		(start 234.685 135.245)
		(end 234.69 135.24)
		(width 0.198)
		(layer "B.Cu")
		(net 797)
	)
	(segment
		(start 186.5 147.498)
		(end 187 146.998)
		(width 0.256)
		(layer "B.Cu")
		(net 797)
	)
	(segment
		(start 139.709499 142.249)
		(end 140.124499 142.249)
		(width 0.256)
		(layer "B.Cu")
		(net 797)
	)
	(segment
		(start 211.421499 154.420499)
		(end 211.426 154.425)
		(width 0.256)
		(layer "B.Cu")
		(net 797)
	)
	(segment
		(start 167.615 154.5)
		(end 167.615 155.55)
		(width 0.4)
		(layer "B.Cu")
		(net 797)
	)
	(segment
		(start 138.740499 143.649)
		(end 138.740499 144.115)
		(width 0.256)
		(layer "B.Cu")
		(net 797)
	)
	(segment
		(start 187.5 151.5)
		(end 187.5 151.498)
		(width 0.256)
		(layer "B.Cu")
		(net 797)
	)
	(segment
		(start 190 147)
		(end 190.5 147.5)
		(width 0.256)
		(layer "B.Cu")
		(net 797)
	)
	(segment
		(start 163.141 154.016)
		(end 162.725 153.6)
		(width 0.4)
		(layer "B.Cu")
		(net 797)
	)
	(segment
		(start 140.474499 142.599)
		(end 140.499 142.599)
		(width 0.1)
		(layer "B.Cu")
		(net 797)
	)
	(segment
		(start 207.591 150.191)
		(end 207.591 149.8905)
		(width 0.4)
		(layer "B.Cu")
		(net 797)
	)
	(segment
		(start 123.6995 164.0705)
		(end 123.72 164.05)
		(width 0.1)
		(layer "B.Cu")
		(net 797)
	)
	(segment
		(start 120.570319 111.3)
		(end 116.9 111.3)
		(width 0.256)
		(layer "B.Cu")
		(net 797)
	)
	(segment
		(start 136.433171 147.740328)
		(end 136.424499 147.749)
		(width 0.256)
		(layer "B.Cu")
		(net 797)
	)
	(segment
		(start 195.998 156)
		(end 195.998 156.998)
		(width 0.256)
		(layer "B.Cu")
		(net 797)
	)
	(segment
		(start 178.5 148.502)
		(end 178 149.002)
		(width 0.256)
		(layer "B.Cu")
		(net 797)
	)
	(segment
		(start 178.5 152.5)
		(end 177.9 152.5)
		(width 0.4)
		(layer "B.Cu")
		(net 797)
	)
	(segment
		(start 125.5 142.422149)
		(end 125.84 142.762149)
		(width 0.2)
		(layer "B.Cu")
		(net 797)
	)
	(segment
		(start 195.5 157.5)
		(end 195.498 157.5)
		(width 0.256)
		(layer "B.Cu")
		(net 797)
	)
	(segment
		(start 138.149 143.649)
		(end 138.740499 143.649)
		(width 0.256)
		(layer "B.Cu")
		(net 797)
	)
	(segment
		(start 119.7 118.1)
		(end 119.7 115.55)
		(width 0.256)
		(layer "B.Cu")
		(net 797)
	)
	(segment
		(start 136.433171 142.914)
		(end 137.414 142.914)
		(width 0.256)
		(layer "B.Cu")
		(net 797)
	)
	(segment
		(start 196.001 156.999)
		(end 196 157)
		(width 0.256)
		(layer "B.Cu")
		(net 797)
	)
	(segment
		(start 186.5 147.5)
		(end 186.5 147.498)
		(width 0.256)
		(layer "B.Cu")
		(net 797)
	)
	(segment
		(start 135.433171 146.937992)
		(end 136.433171 146.937992)
		(width 0.4)
		(layer "B.Cu")
		(net 797)
	)
	(segment
		(start 211.426 154.425)
		(end 211.426 154.299)
		(width 0.182)
		(layer "B.Cu")
		(net 797)
	)
	(segment
		(start 116.9 111.3)
		(end 116.5 111.7)
		(width 0.256)
		(layer "B.Cu")
		(net 797)
	)
	(segment
		(start 142.75 149.565)
		(end 137.525 149.565)
		(width 0.256)
		(layer "B.Cu")
		(net 797)
	)
	(segment
		(start 199.5 154.5)
		(end 200 155)
		(width 0.256)
		(layer "B.Cu")
		(net 797)
	)
	(segment
		(start 190 146.998)
		(end 190 147)
		(width 0.256)
		(layer "B.Cu")
		(net 797)
	)
	(segment
		(start 189.5 147.499999)
		(end 189.5 147.498)
		(width 0.256)
		(layer "B.Cu")
		(net 797)
	)
	(segment
		(start 121.1 111.829681)
		(end 120.570319 111.3)
		(width 0.256)
		(layer "B.Cu")
		(net 797)
	)
	(segment
		(start 190.5 147.5)
		(end 190.502 147.5)
		(width 0.256)
		(layer "B.Cu")
		(net 797)
	)
	(segment
		(start 195.498 157.5)
		(end 194.998 158)
		(width 0.256)
		(layer "B.Cu")
		(net 797)
	)
	(segment
		(start 120.125 159.93)
		(end 120.125 161.375)
		(width 0.182)
		(layer "B.Cu")
		(net 797)
	)
	(segment
		(start 186.5 147.5)
		(end 186.497999 147.5)
		(width 0.256)
		(layer "B.Cu")
		(net 797)
	)
	(segment
		(start 207.89 150.49)
		(end 207.591 150.191)
		(width 0.4)
		(layer "B.Cu")
		(net 797)
	)
	(segment
		(start 165.6 150.424)
		(end 165.616 150.44)
		(width 0.4)
		(layer "B.Cu")
		(net 797)
	)
	(segment
		(start 180.999999 147)
		(end 181.499999 147.5)
		(width 0.256)
		(layer "B.Cu")
		(net 797)
	)
	(segment
		(start 121.175 130.075)
		(end 121.175 119.575)
		(width 0.256)
		(layer "B.Cu")
		(net 797)
	)
	(segment
		(start 143.315 149)
		(end 142.75 149.565)
		(width 0.256)
		(layer "B.Cu")
		(net 797)
	)
	(segment
		(start 143.5 149)
		(end 143.315 149)
		(width 0.256)
		(layer "B.Cu")
		(net 797)
	)
	(segment
		(start 187.5 151.498)
		(end 187 150.998)
		(width 0.256)
		(layer "B.Cu")
		(net 797)
	)
	(segment
		(start 220.395 151.85)
		(end 220.395 152.373999)
		(width 0.256)
		(layer "B.Cu")
		(net 797)
	)
	(segment
		(start 195.998 156)
		(end 196 156)
		(width 0.256)
		(layer "B.Cu")
		(net 797)
	)
	(segment
		(start 196 157)
		(end 195.5 157.5)
		(width 0.201)
		(layer "B.Cu")
		(net 797)
	)
	(segment
		(start 119.7 115.55)
		(end 121.1 114.15)
		(width 0.256)
		(layer "B.Cu")
		(net 797)
	)
	(segment
		(start 124.13 141.8)
		(end 119.65 137.32)
		(width 0.256)
		(layer "B.Cu")
		(net 797)
	)
	(segment
		(start 136.433171 146.937992)
		(end 136.433171 147.740328)
		(width 0.256)
		(layer "B.Cu")
		(net 797)
	)
	(segment
		(start 164.6 153.999999)
		(end 164.046 154)
		(width 0.4)
		(layer "B.Cu")
		(net 797)
	)
	(segment
		(start 121.175 119.575)
		(end 119.7 118.1)
		(width 0.256)
		(layer "B.Cu")
		(net 797)
	)
	(segment
		(start 138.74 147.5)
		(end 138.74 148.17)
		(width 0.2)
		(layer "B.Cu")
		(net 797)
	)
	(segment
		(start 113.325 112.1)
		(end 113.725 111.7)
		(width 0.256)
		(layer "B.Cu")
		(net 797)
	)
	(segment
		(start 176.998 145)
		(end 177 145)
		(width 0.256)
		(layer "B.Cu")
		(net 797)
	)
	(segment
		(start 220.395 154.389)
		(end 220.395 153.865001)
		(width 0.256)
		(layer "B.Cu")
		(net 797)
	)
	(segment
		(start 187.5 151.5)
		(end 187.5 152.25)
		(width 0.4)
		(layer "B.Cu")
		(net 797)
	)
	(segment
		(start 125.84 141.46)
		(end 125.5 141.8)
		(width 0.2)
		(layer "B.Cu")
		(net 797)
	)
	(segment
		(start 189.5 147.498)
		(end 190 146.998)
		(width 0.256)
		(layer "B.Cu")
		(net 797)
	)
	(segment
		(start 186.497999 147.5)
		(end 185.997999 147)
		(width 0.256)
		(layer "B.Cu")
		(net 797)
	)
	(segment
		(start 137.414 142.914)
		(end 138.149 143.649)
		(width 0.256)
		(layer "B.Cu")
		(net 797)
	)
	(segment
		(start 196 156)
		(end 196.5 155.5)
		(width 0.256)
		(layer "B.Cu")
		(net 797)
	)
	(segment
		(start 188.5 147.6)
		(end 188.4 147.5)
		(width 0.4)
		(layer "B.Cu")
		(net 797)
	)
	(segment
		(start 164.046 154)
		(end 164.03 154.016)
		(width 0.4)
		(layer "B.Cu")
		(net 797)
	)
	(segment
		(start 125.84 141.262149)
		(end 125.84 141.46)
		(width 0.2)
		(layer "B.Cu")
		(net 797)
	)
	(segment
		(start 144.054 148.17)
		(end 144.324499 148.440499)
		(width 0.256)
		(layer "B.Cu")
		(net 797)
	)
	(segment
		(start 234.06 135.245)
		(end 234.685 135.245)
		(width 0.198)
		(layer "B.Cu")
		(net 797)
	)
	(segment
		(start 167.6 153.484)
		(end 167.6 154.48)
		(width 0.4)
		(layer "B.Cu")
		(net 797)
	)
	(segment
		(start 212.395 153.33)
		(end 212.395 153.15)
		(width 0.182)
		(layer "B.Cu")
		(net 797)
	)
	(segment
		(start 178.5 148.5)
		(end 178.5 148.502)
		(width 0.256)
		(layer "B.Cu")
		(net 797)
	)
	(segment
		(start 210.899998 154.420499)
		(end 211.421499 154.420499)
		(width 0.256)
		(layer "B.Cu")
		(net 797)
	)
	(segment
		(start 187.5 152.25)
		(end 187.225 152.525)
		(width 0.4)
		(layer "B.Cu")
		(net 797)
	)
	(segment
		(start 200.001 154)
		(end 200 154)
		(width 0.256)
		(layer "B.Cu")
		(net 797)
	)
	(segment
		(start 165.6 150)
		(end 165.6 150.424)
		(width 0.4)
		(layer "B.Cu")
		(net 797)
	)
	(segment
		(start 134.440499 152.9005)
		(end 133.824499 152.9005)
		(width 0.256)
		(layer "B.Cu")
		(net 797)
	)
	(segment
		(start 249.126 181.325)
		(end 250.2 182.399)
		(width 0.256)
		(layer "In2.Cu")
		(net 797)
	)
	(segment
		(start 243.8 178.2)
		(end 243.8 179.425)
		(width 0.256)
		(layer "In2.Cu")
		(net 797)
	)
	(segment
		(start 243.8 179.425)
		(end 245.7 181.325)
		(width 0.256)
		(layer "In2.Cu")
		(net 797)
	)
	(segment
		(start 245.7 181.325)
		(end 249.126 181.325)
		(width 0.256)
		(layer "In2.Cu")
		(net 797)
	)
	(segment
		(start 234.69 135.24)
		(end 234.69 140.23)
		(width 0.4)
		(layer "In6.Cu")
		(net 797)
	)
	(segment
		(start 234.69 140.23)
		(end 230.08 144.84)
		(width 0.4)
		(layer "In6.Cu")
		(net 797)
	)
	(segment
		(start 181.9995 151.9995)
		(end 181.5 151.500001)
		(width 0.256)
		(layer "F.Cu")
		(net 798)
	)
	(via
		(at 181.5 151.500001)
		(size 0.45)
		(drill 0.1)
		(layers "F.Cu" "B.Cu")
		(remove_unused_layers yes)
		(keep_end_layers yes)
		(zone_layer_connections)
		(net 798)
	)
	(segment
		(start 182.9995 151.9995)
		(end 182.5 151.5)
		(width 0.256)
		(layer "F.Cu")
		(net 799)
	)
	(via
		(at 182.5 151.5)
		(size 0.45)
		(drill 0.1)
		(layers "F.Cu" "B.Cu")
		(remove_unused_layers yes)
		(keep_end_layers yes)
		(zone_layer_connections)
		(net 799)
	)
	(segment
		(start 183.9995 151.9995)
		(end 183.5 151.5)
		(width 0.256)
		(layer "F.Cu")
		(net 800)
	)
	(via
		(at 183.5 151.5)
		(size 0.45)
		(drill 0.1)
		(layers "F.Cu" "B.Cu")
		(remove_unused_layers yes)
		(keep_end_layers yes)
		(zone_layer_connections)
		(net 800)
	)
	(segment
		(start 183.9995 150.9995)
		(end 183.5 150.5)
		(width 0.256)
		(layer "F.Cu")
		(net 801)
	)
	(via
		(at 183.5 150.5)
		(size 0.45)
		(drill 0.1)
		(layers "F.Cu" "B.Cu")
		(remove_unused_layers yes)
		(keep_end_layers yes)
		(zone_layer_connections)
		(net 801)
	)
	(segment
		(start 243.531 114.731)
		(end 243.5 114.7)
		(width 0.201)
		(layer "F.Cu")
		(net 802)
	)
	(segment
		(start 243.531 116.4)
		(end 243.531 114.731)
		(width 0.201)
		(layer "F.Cu")
		(net 802)
	)
	(via
		(at 249.7 112.35)
		(size 0.45)
		(drill 0.1)
		(layers "F.Cu" "B.Cu")
		(remove_unused_layers yes)
		(keep_end_layers yes)
		(zone_layer_connections)
		(net 802)
	)
	(segment
		(start 251.525 102.1)
		(end 251.625 102)
		(width 0.201)
		(layer "F.Cu")
		(net 803)
	)
	(segment
		(start 249.875 102.1)
		(end 251.525 102.1)
		(width 0.201)
		(layer "F.Cu")
		(net 803)
	)
	(segment
		(start 243.531 101.6)
		(end 249.375 101.6)
		(width 0.201)
		(layer "F.Cu")
		(net 803)
	)
	(segment
		(start 249.375 101.6)
		(end 249.875 102.1)
		(width 0.201)
		(layer "F.Cu")
		(net 803)
	)
	(via
		(at 252.375 102.275)
		(size 0.45)
		(drill 0.1)
		(layers "F.Cu" "B.Cu")
		(net 803)
	)
	(via
		(at 251.625 102)
		(size 0.45)
		(drill 0.1)
		(layers "F.Cu" "B.Cu")
		(net 803)
	)
	(via
		(at 252.5 103)
		(size 0.45)
		(drill 0.1)
		(layers "F.Cu" "B.Cu")
		(net 803)
	)
	(segment
		(start 242.571 116.54)
		(end 243.531 117.5)
		(width 0.201)
		(layer "F.Cu")
		(net 804)
	)
	(segment
		(start 242.571 116.4)
		(end 242.571 116.54)
		(width 0.201)
		(layer "F.Cu")
		(net 804)
	)
	(segment
		(start 241.926 101.6)
		(end 241.901 101.575)
		(width 0.201)
		(layer "F.Cu")
		(net 805)
	)
	(segment
		(start 242.571 101.6)
		(end 241.926 101.6)
		(width 0.201)
		(layer "F.Cu")
		(net 805)
	)
	(via
		(at 241.901 101.575)
		(size 0.45)
		(drill 0.1)
		(layers "F.Cu" "B.Cu")
		(net 805)
	)
	(segment
		(start 241.901 101.575)
		(end 241.926 101.6)
		(width 0.201)
		(layer "B.Cu")
		(net 805)
	)
	(segment
		(start 241.926 101.6)
		(end 242.57 101.6)
		(width 0.201)
		(layer "B.Cu")
		(net 805)
	)
	(segment
		(start 251.124 117.176)
		(end 248.243 117.176)
		(width 0.198)
		(layer "F.Cu")
		(net 806)
	)
	(segment
		(start 251.2 117.1)
		(end 251.124 117.176)
		(width 0.198)
		(layer "F.Cu")
		(net 806)
	)
	(via
		(at 251.2 117.1)
		(size 0.45)
		(drill 0.1)
		(layers "F.Cu" "B.Cu")
		(net 806)
	)
	(segment
		(start 251.19 117.11)
		(end 250.51 117.11)
		(width 0.198)
		(layer "B.Cu")
		(net 806)
	)
	(segment
		(start 251.2 117.1)
		(end 251.19 117.11)
		(width 0.198)
		(layer "B.Cu")
		(net 806)
	)
	(segment
		(start 251.2 118.4)
		(end 251.2 117.1)
		(width 0.198)
		(layer "B.Cu")
		(net 806)
	)
	(segment
		(start 250.375 119.225)
		(end 251.2 118.4)
		(width 0.198)
		(layer "B.Cu")
		(net 806)
	)
	(segment
		(start 250.51 117.11)
		(end 250.375 117.245)
		(width 0.198)
		(layer "B.Cu")
		(net 806)
	)
	(segment
		(start 256.4135 101.7795)
		(end 257.1955 101.7795)
		(width 0.4)
		(layer "F.Cu")
		(net 807)
	)
	(via
		(at 257.1955 101.7795)
		(size 0.45)
		(drill 0.1)
		(layers "F.Cu" "B.Cu")
		(remove_unused_layers yes)
		(keep_end_layers yes)
		(zone_layer_connections)
		(net 807)
	)
	(segment
		(start 256.515 117.11)
		(end 259.1 114.525)
		(width 0.198)
		(layer "B.Cu")
		(net 807)
	)
	(segment
		(start 255.5 117.11)
		(end 255.44 117.11)
		(width 0.198)
		(layer "B.Cu")
		(net 807)
	)
	(segment
		(start 255.5 117.11)
		(end 256.515 117.11)
		(width 0.198)
		(layer "B.Cu")
		(net 807)
	)
	(segment
		(start 255.25 118)
		(end 255.25 117.3)
		(width 0.198)
		(layer "B.Cu")
		(net 807)
	)
	(segment
		(start 254.23 117.11)
		(end 255 117.11)
		(width 0.198)
		(layer "B.Cu")
		(net 807)
	)
	(segment
		(start 255 117.11)
		(end 255.06 117.11)
		(width 0.198)
		(layer "B.Cu")
		(net 807)
	)
	(segment
		(start 255.44 117.11)
		(end 255.25 117.3)
		(width 0.198)
		(layer "B.Cu")
		(net 807)
	)
	(segment
		(start 255 117.11)
		(end 255.25 117.11)
		(width 0.198)
		(layer "B.Cu")
		(net 807)
	)
	(segment
		(start 255.25 117.11)
		(end 255.5 117.11)
		(width 0.198)
		(layer "B.Cu")
		(net 807)
	)
	(segment
		(start 255.25 117.3)
		(end 255.25 117.11)
		(width 0.198)
		(layer "B.Cu")
		(net 807)
	)
	(segment
		(start 259.1 103.425)
		(end 257.4545 101.7795)
		(width 0.198)
		(layer "B.Cu")
		(net 807)
	)
	(segment
		(start 255.06 117.11)
		(end 255.25 117.3)
		(width 0.198)
		(layer "B.Cu")
		(net 807)
	)
	(segment
		(start 254.05 119.2)
		(end 255.25 118)
		(width 0.198)
		(layer "B.Cu")
		(net 807)
	)
	(segment
		(start 257.4545 101.7795)
		(end 257.1955 101.7795)
		(width 0.198)
		(layer "B.Cu")
		(net 807)
	)
	(segment
		(start 259.1 114.525)
		(end 259.1 103.425)
		(width 0.198)
		(layer "B.Cu")
		(net 807)
	)
	(segment
		(start 254.05 117.29)
		(end 254.23 117.11)
		(width 0.198)
		(layer "B.Cu")
		(net 807)
	)
	(segment
		(start 254.05 119.225)
		(end 254.05 119.2)
		(width 0.198)
		(layer "B.Cu")
		(net 807)
	)
	(segment
		(start 199.5 150.5)
		(end 199.0005 150.999501)
		(width 0.256)
		(layer "F.Cu")
		(net 808)
	)
	(via
		(at 249.4 120.5)
		(size 0.45)
		(drill 0.1)
		(layers "F.Cu" "B.Cu")
		(remove_unused_layers yes)
		(keep_end_layers yes)
		(zone_layer_connections)
		(net 808)
	)
	(via
		(at 213.07 149.11)
		(size 0.45)
		(drill 0.1)
		(layers "F.Cu" "B.Cu")
		(remove_unused_layers yes)
		(keep_end_layers yes)
		(zone_layer_connections)
		(net 808)
	)
	(via
		(at 213.34 140.91)
		(size 0.45)
		(drill 0.1)
		(layers "F.Cu" "B.Cu")
		(remove_unused_layers yes)
		(keep_end_layers yes)
		(zone_layer_connections)
		(net 808)
	)
	(via
		(at 199.5 150.5)
		(size 0.45)
		(drill 0.1)
		(layers "F.Cu" "B.Cu")
		(remove_unused_layers yes)
		(keep_end_layers yes)
		(zone_layer_connections)
		(net 808)
	)
	(segment
		(start 249.4 120.5)
		(end 250.199 120.5)
		(width 0.198)
		(layer "B.Cu")
		(net 808)
	)
	(segment
		(start 250.199 120.5)
		(end 251.025 121.326)
		(width 0.198)
		(layer "B.Cu")
		(net 808)
	)
	(segment
		(start 251.025 122.055)
		(end 250.855 122.225)
		(width 0.198)
		(layer "B.Cu")
		(net 808)
	)
	(segment
		(start 251.025 121.326)
		(end 251.025 122.055)
		(width 0.198)
		(layer "B.Cu")
		(net 808)
	)
	(segment
		(start 234.72 119.53)
		(end 213.34 140.91)
		(width 0.1)
		(layer "In6.Cu")
		(net 808)
	)
	(segment
		(start 200 151.219669)
		(end 200 151.530331)
		(width 0.1)
		(layer "In6.Cu")
		(net 808)
	)
	(segment
		(start 199.5 150.5)
		(end 199.5 150.719669)
		(width 0.1)
		(layer "In6.Cu")
		(net 808)
	)
	(segment
		(start 200.709669 152.24)
		(end 202.52 152.24)
		(width 0.1)
		(layer "In6.Cu")
		(net 808)
	)
	(segment
		(start 248.5 121.3)
		(end 246.73 119.53)
		(width 0.1)
		(layer "In6.Cu")
		(net 808)
	)
	(segment
		(start 200 151.530331)
		(end 200.709669 152.24)
		(width 0.1)
		(layer "In6.Cu")
		(net 808)
	)
	(segment
		(start 210.422805 150.272805)
		(end 208.657195 150.272805)
		(width 0.1)
		(layer "In6.Cu")
		(net 808)
	)
	(segment
		(start 202.52 152.24)
		(end 204.16 150.6)
		(width 0.1)
		(layer "In6.Cu")
		(net 808)
	)
	(segment
		(start 248.6 121.3)
		(end 248.5 121.3)
		(width 0.1)
		(layer "In6.Cu")
		(net 808)
	)
	(segment
		(start 208.657195 150.272805)
		(end 208.33 150.6)
		(width 0.1)
		(layer "In6.Cu")
		(net 808)
	)
	(segment
		(start 199.5 150.719669)
		(end 200 151.219669)
		(width 0.1)
		(layer "In6.Cu")
		(net 808)
	)
	(segment
		(start 204.16 150.6)
		(end 208.33 150.6)
		(width 0.1)
		(layer "In6.Cu")
		(net 808)
	)
	(segment
		(start 211.585609 149.11)
		(end 213.07 149.11)
		(width 0.1)
		(layer "In6.Cu")
		(net 808)
	)
	(segment
		(start 210.422805 150.272805)
		(end 211.585609 149.11)
		(width 0.1)
		(layer "In6.Cu")
		(net 808)
	)
	(segment
		(start 246.73 119.53)
		(end 234.72 119.53)
		(width 0.1)
		(layer "In6.Cu")
		(net 808)
	)
	(segment
		(start 249.4 120.5)
		(end 248.6 121.3)
		(width 0.1)
		(layer "In6.Cu")
		(net 808)
	)
	(segment
		(start 213.07 149.11)
		(end 213.07 141.18)
		(width 0.1)
		(layer "In9.Cu")
		(net 808)
	)
	(segment
		(start 213.07 141.18)
		(end 213.34 140.91)
		(width 0.1)
		(layer "In9.Cu")
		(net 808)
	)
	(segment
		(start 199.0005 151.999499)
		(end 199.5 151.5)
		(width 0.256)
		(layer "F.Cu")
		(net 809)
	)
	(via
		(at 211.48 143.06)
		(size 0.45)
		(drill 0.1)
		(layers "F.Cu" "B.Cu")
		(remove_unused_layers yes)
		(keep_end_layers yes)
		(zone_layer_connections)
		(net 809)
	)
	(via
		(at 199.5 151.5)
		(size 0.45)
		(drill 0.1)
		(layers "F.Cu" "B.Cu")
		(remove_unused_layers yes)
		(keep_end_layers yes)
		(zone_layer_connections)
		(net 809)
	)
	(via
		(at 254.7 120.6)
		(size 0.45)
		(drill 0.1)
		(layers "F.Cu" "B.Cu")
		(remove_unused_layers yes)
		(keep_end_layers yes)
		(zone_layer_connections)
		(net 809)
	)
	(via
		(at 213.97 149.12)
		(size 0.45)
		(drill 0.1)
		(layers "F.Cu" "B.Cu")
		(remove_unused_layers yes)
		(keep_end_layers yes)
		(zone_layer_connections)
		(net 809)
	)
	(segment
		(start 254.7 121.326)
		(end 254.7 122.055)
		(width 0.198)
		(layer "B.Cu")
		(net 809)
	)
	(segment
		(start 254.7 122.055)
		(end 254.53 122.225)
		(width 0.198)
		(layer "B.Cu")
		(net 809)
	)
	(segment
		(start 254.7 120.6)
		(end 254.7 121.326)
		(width 0.198)
		(layer "B.Cu")
		(net 809)
	)
	(segment
		(start 208.8125 150.6775)
		(end 209.99 150.6775)
		(width 0.1)
		(layer "In6.Cu")
		(net 809)
	)
	(segment
		(start 210.297 150.9845)
		(end 211.1655 150.9845)
		(width 0.1)
		(layer "In6.Cu")
		(net 809)
	)
	(segment
		(start 204.539169 150.93)
		(end 208.56 150.93)
		(width 0.1)
		(layer "In6.Cu")
		(net 809)
	)
	(segment
		(start 213.38 149.71)
		(end 213.97 149.12)
		(width 0.1)
		(layer "In6.Cu")
		(net 809)
	)
	(segment
		(start 248.42 122.27)
		(end 246.62 120.47)
		(width 0.1)
		(layer "In6.Cu")
		(net 809)
	)
	(segment
		(start 253.03 122.27)
		(end 248.42 122.27)
		(width 0.1)
		(layer "In6.Cu")
		(net 809)
	)
	(segment
		(start 246.62 120.47)
		(end 236.02 120.47)
		(width 0.1)
		(layer "In6.Cu")
		(net 809)
	)
	(segment
		(start 202.929169 152.54)
		(end 204.539169 150.93)
		(width 0.1)
		(layer "In6.Cu")
		(net 809)
	)
	(segment
		(start 212.44 149.71)
		(end 213.38 149.71)
		(width 0.1)
		(layer "In6.Cu")
		(net 809)
	)
	(segment
		(start 213.43 143.06)
		(end 211.48 143.06)
		(width 0.1)
		(layer "In6.Cu")
		(net 809)
	)
	(segment
		(start 254.7 120.6)
		(end 253.03 122.27)
		(width 0.1)
		(layer "In6.Cu")
		(net 809)
	)
	(segment
		(start 199.5 151.5)
		(end 200.54 152.54)
		(width 0.1)
		(layer "In6.Cu")
		(net 809)
	)
	(segment
		(start 236.02 120.47)
		(end 213.43 143.06)
		(width 0.1)
		(layer "In6.Cu")
		(net 809)
	)
	(segment
		(start 211.1655 150.9845)
		(end 212.44 149.71)
		(width 0.1)
		(layer "In6.Cu")
		(net 809)
	)
	(segment
		(start 209.99 150.6775)
		(end 210.297 150.9845)
		(width 0.1)
		(layer "In6.Cu")
		(net 809)
	)
	(segment
		(start 208.56 150.93)
		(end 208.8125 150.6775)
		(width 0.1)
		(layer "In6.Cu")
		(net 809)
	)
	(segment
		(start 200.54 152.54)
		(end 202.929169 152.54)
		(width 0.1)
		(layer "In6.Cu")
		(net 809)
	)
	(segment
		(start 211.48 143.06)
		(end 212.33 143.91)
		(width 0.1)
		(layer "In9.Cu")
		(net 809)
	)
	(segment
		(start 213.56 149.84)
		(end 213.97 149.43)
		(width 0.1)
		(layer "In9.Cu")
		(net 809)
	)
	(segment
		(start 212.61 149.84)
		(end 213.56 149.84)
		(width 0.1)
		(layer "In9.Cu")
		(net 809)
	)
	(segment
		(start 213.97 149.43)
		(end 213.97 149.12)
		(width 0.1)
		(layer "In9.Cu")
		(net 809)
	)
	(segment
		(start 212.33 143.91)
		(end 212.33 149.56)
		(width 0.1)
		(layer "In9.Cu")
		(net 809)
	)
	(segment
		(start 212.33 149.56)
		(end 212.61 149.84)
		(width 0.1)
		(layer "In9.Cu")
		(net 809)
	)
	(segment
		(start 126.576 176.772)
		(end 126.306 176.502)
		(width 0.201)
		(layer "F.Cu")
		(net 810)
	)
	(segment
		(start 127.076 185.9825)
		(end 127.231 186.1375)
		(width 0.201)
		(layer "F.Cu")
		(net 810)
	)
	(segment
		(start 120.9755 171.775)
		(end 120.975 171.7745)
		(width 0.4)
		(layer "F.Cu")
		(net 810)
	)
	(segment
		(start 120.975 171.7745)
		(end 120.975 171.255)
		(width 0.4)
		(layer "F.Cu")
		(net 810)
	)
	(segment
		(start 121.576 184.778)
		(end 121.576 185.9825)
		(width 0.201)
		(layer "F.Cu")
		(net 810)
	)
	(segment
		(start 121.086 176.862)
		(end 121.086 176.512)
		(width 0.201)
		(layer "F.Cu")
		(net 810)
	)
	(segment
		(start 125.786 176.022)
		(end 125.826 176.022)
		(width 0.256)
		(layer "F.Cu")
		(net 810)
	)
	(segment
		(start 120 171.255)
		(end 120 171.8)
		(width 0.4)
		(layer "F.Cu")
		(net 810)
	)
	(segment
		(start 127.076 184.778)
		(end 127.076 185.9825)
		(width 0.201)
		(layer "F.Cu")
		(net 810)
	)
	(segment
		(start 122.076 177.828)
		(end 122.076 176.512)
		(width 0.201)
		(layer "F.Cu")
		(net 810)
	)
	(segment
		(start 121.576 185.9825)
		(end 121.421 186.1375)
		(width 0.201)
		(layer "F.Cu")
		(net 810)
	)
	(segment
		(start 120 171.255)
		(end 120.975 171.255)
		(width 0.4)
		(layer "F.Cu")
		(net 810)
	)
	(segment
		(start 121.576 177.352)
		(end 121.086 176.862)
		(width 0.201)
		(layer "F.Cu")
		(net 810)
	)
	(segment
		(start 120.096 176.512)
		(end 120.096 177.132)
		(width 0.256)
		(layer "F.Cu")
		(net 810)
	)
	(segment
		(start 127.231 186.792)
		(end 127.231 186.1375)
		(width 0.256)
		(layer "F.Cu")
		(net 810)
	)
	(segment
		(start 121.576 177.828)
		(end 121.576 177.352)
		(width 0.201)
		(layer "F.Cu")
		(net 810)
	)
	(segment
		(start 121.421 186.792)
		(end 121.421 186.1375)
		(width 0.256)
		(layer "F.Cu")
		(net 810)
	)
	(segment
		(start 125.746 176.072)
		(end 125.876 176.072)
		(width 0.256)
		(layer "F.Cu")
		(net 810)
	)
	(segment
		(start 120.096 176.512)
		(end 122.076 176.512)
		(width 0.256)
		(layer "F.Cu")
		(net 810)
	)
	(segment
		(start 125.876 176.072)
		(end 126.306 176.502)
		(width 0.256)
		(layer "F.Cu")
		(net 810)
	)
	(segment
		(start 126.576 177.828)
		(end 126.576 176.772)
		(width 0.201)
		(layer "F.Cu")
		(net 810)
	)
	(segment
		(start 120.096 176.512)
		(end 119.446 176.512)
		(width 0.256)
		(layer "F.Cu")
		(net 810)
	)
	(via
		(at 127.231 186.792)
		(size 0.45)
		(drill 0.1)
		(layers "F.Cu" "B.Cu")
		(remove_unused_layers yes)
		(keep_end_layers yes)
		(zone_layer_connections "In8.Cu")
		(net 810)
	)
	(via
		(at 120.9755 171.775)
		(size 0.45)
		(drill 0.1)
		(layers "F.Cu" "B.Cu")
		(net 810)
	)
	(via
		(at 120.096 177.132)
		(size 0.45)
		(drill 0.1)
		(layers "F.Cu" "B.Cu")
		(remove_unused_layers yes)
		(keep_end_layers yes)
		(zone_layer_connections "In8.Cu")
		(net 810)
	)
	(via
		(at 120 171.8)
		(size 0.45)
		(drill 0.1)
		(layers "F.Cu" "B.Cu")
		(net 810)
	)
	(via
		(at 125.746 176.072)
		(size 0.45)
		(drill 0.1)
		(layers "F.Cu" "B.Cu")
		(remove_unused_layers yes)
		(keep_end_layers yes)
		(zone_layer_connections "In8.Cu")
		(net 810)
	)
	(via
		(at 121.421 186.792)
		(size 0.45)
		(drill 0.1)
		(layers "F.Cu" "B.Cu")
		(remove_unused_layers yes)
		(keep_end_layers yes)
		(zone_layer_connections "In8.Cu")
		(net 810)
	)
	(via
		(at 119.446 176.512)
		(size 0.45)
		(drill 0.1)
		(layers "F.Cu" "B.Cu")
		(remove_unused_layers yes)
		(keep_end_layers yes)
		(zone_layer_connections "In8.Cu")
		(net 810)
	)
	(segment
		(start 243.05 118.9)
		(end 242.3 119.65)
		(width 0.6)
		(layer "F.Cu")
		(net 811)
	)
	(segment
		(start 243.4 118.9)
		(end 243.05 118.9)
		(width 0.6)
		(layer "F.Cu")
		(net 811)
	)
	(segment
		(start 242.3 119.65)
		(end 242.3 120.15)
		(width 0.6)
		(layer "F.Cu")
		(net 811)
	)
	(segment
		(start 242.03 120.42)
		(end 240.875 120.42)
		(width 0.6)
		(layer "F.Cu")
		(net 811)
	)
	(segment
		(start 242.3 120.15)
		(end 242.03 120.42)
		(width 0.6)
		(layer "F.Cu")
		(net 811)
	)
	(via
		(at 242.4 120.095)
		(size 0.45)
		(drill 0.1)
		(layers "F.Cu" "B.Cu")
		(net 811)
	)
	(segment
		(start 241.73 120.765)
		(end 241.25 120.765)
		(width 0.4)
		(layer "B.Cu")
		(net 811)
	)
	(segment
		(start 241.11 122.14)
		(end 241.11 120.905)
		(width 0.4)
		(layer "B.Cu")
		(net 811)
	)
	(segment
		(start 242.4 120.095)
		(end 241.73 120.765)
		(width 0.4)
		(layer "B.Cu")
		(net 811)
	)
	(segment
		(start 241.11 120.905)
		(end 241.25 120.765)
		(width 0.4)
		(layer "B.Cu")
		(net 811)
	)
	(segment
		(start 241.03 122.22)
		(end 241.11 122.14)
		(width 0.4)
		(layer "B.Cu")
		(net 811)
	)
	(segment
		(start 197.0005 149.999499)
		(end 197.5 149.5)
		(width 0.256)
		(layer "F.Cu")
		(net 812)
	)
	(via
		(at 231.8 135.69)
		(size 0.45)
		(drill 0.1)
		(layers "F.Cu" "B.Cu")
		(net 812)
	)
	(via
		(at 197.5 149.5)
		(size 0.45)
		(drill 0.1)
		(layers "F.Cu" "B.Cu")
		(remove_unused_layers yes)
		(keep_end_layers yes)
		(zone_layer_connections)
		(net 812)
	)
	(via
		(at 245.132843 122.982843)
		(size 0.45)
		(drill 0.1)
		(layers "F.Cu" "B.Cu")
		(net 812)
	)
	(segment
		(start 245.51 122.055)
		(end 245.34 122.225)
		(width 0.4)
		(layer "B.Cu")
		(net 812)
	)
	(segment
		(start 245.51 121.326)
		(end 245.51 122.055)
		(width 0.4)
		(layer "B.Cu")
		(net 812)
	)
	(segment
		(start 245.132843 122.982843)
		(end 245.34 122.775686)
		(width 0.182)
		(layer "B.Cu")
		(net 812)
	)
	(segment
		(start 245.34 122.775686)
		(end 245.34 122.225)
		(width 0.182)
		(layer "B.Cu")
		(net 812)
	)
	(segment
		(start 245.132843 122.982843)
		(end 242.265686 125.85)
		(width 0.1)
		(layer "In6.Cu")
		(net 812)
	)
	(segment
		(start 242.265686 125.85)
		(end 237.65 125.85)
		(width 0.1)
		(layer "In6.Cu")
		(net 812)
	)
	(segment
		(start 237.65 125.85)
		(end 231.8 131.7)
		(width 0.1)
		(layer "In6.Cu")
		(net 812)
	)
	(segment
		(start 231.8 131.7)
		(end 231.8 135.69)
		(width 0.1)
		(layer "In6.Cu")
		(net 812)
	)
	(segment
		(start 203.42 148.44)
		(end 216.17 135.69)
		(width 0.1)
		(layer "In9.Cu")
		(net 812)
	)
	(segment
		(start 198.03 148.97)
		(end 202.89 148.97)
		(width 0.1)
		(layer "In9.Cu")
		(net 812)
	)
	(segment
		(start 197.5 149.5)
		(end 198.03 148.97)
		(width 0.1)
		(layer "In9.Cu")
		(net 812)
	)
	(segment
		(start 216.17 135.69)
		(end 231.8 135.69)
		(width 0.1)
		(layer "In9.Cu")
		(net 812)
	)
	(segment
		(start 202.89 148.97)
		(end 203.42 148.44)
		(width 0.1)
		(layer "In9.Cu")
		(net 812)
	)
	(segment
		(start 245.85 118.65)
		(end 246.1375 118.9375)
		(width 0.201)
		(layer "F.Cu")
		(net 813)
	)
	(segment
		(start 246.1375 118.9375)
		(end 246.1375 119.814)
		(width 0.201)
		(layer "F.Cu")
		(net 813)
	)
	(via
		(at 245.85 118.65)
		(size 0.45)
		(drill 0.1)
		(layers "F.Cu" "B.Cu")
		(net 813)
	)
	(segment
		(start 245.275 119.225)
		(end 244.86 119.225)
		(width 0.182)
		(layer "B.Cu")
		(net 813)
	)
	(segment
		(start 244.38 117.11)
		(end 244.38 118.745)
		(width 0.182)
		(layer "B.Cu")
		(net 813)
	)
	(segment
		(start 245.85 118.65)
		(end 245.275 119.225)
		(width 0.182)
		(layer "B.Cu")
		(net 813)
	)
	(segment
		(start 244.38 118.745)
		(end 244.86 119.225)
		(width 0.182)
		(layer "B.Cu")
		(net 813)
	)
	(segment
		(start 118.71 140.45)
		(end 116.8 140.45)
		(width 0.4)
		(layer "F.Cu")
		(net 818)
	)
	(segment
		(start 116.8 140.45)
		(end 116.48 140.13)
		(width 0.4)
		(layer "F.Cu")
		(net 818)
	)
	(segment
		(start 118.715 140.455)
		(end 118.71 140.45)
		(width 0.4)
		(layer "F.Cu")
		(net 818)
	)
	(segment
		(start 116.48 140.13)
		(end 116.48 139.563)
		(width 0.4)
		(layer "F.Cu")
		(net 818)
	)
	(segment
		(start 119.43 140.455)
		(end 118.715 140.455)
		(width 0.4)
		(layer "F.Cu")
		(net 818)
	)
	(via
		(at 118.71 140.45)
		(size 0.45)
		(drill 0.1)
		(layers "F.Cu" "B.Cu")
		(remove_unused_layers yes)
		(keep_end_layers yes)
		(zone_layer_connections)
		(net 818)
	)
	(segment
		(start 118.66 140.5)
		(end 118.71 140.45)
		(width 0.198)
		(layer "B.Cu")
		(net 818)
	)
	(segment
		(start 117.6 140.5)
		(end 118.66 140.5)
		(width 0.198)
		(layer "B.Cu")
		(net 818)
	)
	(segment
		(start 239.027499 153.8475)
		(end 239.027499 152.950501)
		(width 0.256)
		(layer "F.Cu")
		(net 819)
	)
	(segment
		(start 239.027499 152.950501)
		(end 239.028 152.95)
		(width 0.256)
		(layer "F.Cu")
		(net 819)
	)
	(segment
		(start 256.24 148.15)
		(end 256.399 148.15)
		(width 0.1)
		(layer "F.Cu")
		(net 819)
	)
	(segment
		(start 256.399 148.15)
		(end 256.401 148.148)
		(width 0.1)
		(layer "F.Cu")
		(net 819)
	)
	(via
		(at 256.401 148.148)
		(size 0.45)
		(drill 0.1)
		(layers "F.Cu" "B.Cu")
		(remove_unused_layers yes)
		(keep_end_layers yes)
		(zone_layer_connections)
		(net 819)
	)
	(via
		(at 239.028 152.95)
		(size 0.45)
		(drill 0.1)
		(layers "F.Cu" "B.Cu")
		(remove_unused_layers yes)
		(keep_end_layers yes)
		(zone_layer_connections)
		(net 819)
	)
	(segment
		(start 256.208578 147.4)
		(end 244.141422 147.4)
		(width 0.1)
		(layer "In4.Cu")
		(net 819)
	)
	(segment
		(start 239 152.922)
		(end 239.028 152.95)
		(width 0.1)
		(layer "In4.Cu")
		(net 819)
	)
	(segment
		(start 256.576 147.767422)
		(end 256.208578 147.4)
		(width 0.1)
		(layer "In4.Cu")
		(net 819)
	)
	(segment
		(start 239 152.541422)
		(end 239 152.922)
		(width 0.1)
		(layer "In4.Cu")
		(net 819)
	)
	(segment
		(start 256.576 147.973)
		(end 256.576 147.767422)
		(width 0.1)
		(layer "In4.Cu")
		(net 819)
	)
	(segment
		(start 256.401 148.148)
		(end 256.576 147.973)
		(width 0.1)
		(layer "In4.Cu")
		(net 819)
	)
	(segment
		(start 244.141422 147.4)
		(end 239 152.541422)
		(width 0.1)
		(layer "In4.Cu")
		(net 819)
	)
	(segment
		(start 198 159)
		(end 198.4995 159.4995)
		(width 0.256)
		(layer "F.Cu")
		(net 820)
	)
	(segment
		(start 183.9995 159.0005)
		(end 183.5 159.5)
		(width 0.256)
		(layer "F.Cu")
		(net 820)
	)
	(segment
		(start 194.0005 159.0005)
		(end 194.5 159.500001)
		(width 0.256)
		(layer "F.Cu")
		(net 820)
	)
	(segment
		(start 187.9995 159.0005)
		(end 187.5 159.5)
		(width 0.256)
		(layer "F.Cu")
		(net 820)
	)
	(segment
		(start 196.0005 159.0005)
		(end 196.5 159.5)
		(width 0.256)
		(layer "F.Cu")
		(net 820)
	)
	(segment
		(start 185.9995 159.0005)
		(end 185.5 159.500001)
		(width 0.256)
		(layer "F.Cu")
		(net 820)
	)
	(via
		(at 245 165.625)
		(size 0.45)
		(drill 0.1)
		(layers "F.Cu" "B.Cu")
		(remove_unused_layers yes)
		(keep_end_layers yes)
		(zone_layer_connections "In8.Cu")
		(net 820)
	)
	(via
		(at 187.5 159.5)
		(size 0.45)
		(drill 0.1)
		(layers "F.Cu" "B.Cu")
		(remove_unused_layers yes)
		(keep_end_layers yes)
		(zone_layer_connections "In8.Cu")
		(net 820)
	)
	(via
		(at 246.7 165.65)
		(size 0.45)
		(drill 0.1)
		(layers "F.Cu" "B.Cu")
		(remove_unused_layers yes)
		(keep_end_layers yes)
		(zone_layer_connections "In8.Cu")
		(net 820)
	)
	(via
		(at 244.775 165.1)
		(size 0.45)
		(drill 0.1)
		(layers "F.Cu" "B.Cu")
		(remove_unused_layers yes)
		(keep_end_layers yes)
		(zone_layer_connections "In8.Cu")
		(net 820)
	)
	(via
		(at 245.4 165.125)
		(size 0.45)
		(drill 0.1)
		(layers "F.Cu" "B.Cu")
		(remove_unused_layers yes)
		(keep_end_layers yes)
		(zone_layer_connections "In8.Cu")
		(net 820)
	)
	(via
		(at 185.5 159.500001)
		(size 0.45)
		(drill 0.1)
		(layers "F.Cu" "B.Cu")
		(remove_unused_layers yes)
		(keep_end_layers yes)
		(zone_layer_connections "In8.Cu")
		(net 820)
	)
	(via
		(at 198.4995 159.4995)
		(size 0.45)
		(drill 0.1)
		(layers "F.Cu" "B.Cu")
		(remove_unused_layers yes)
		(keep_end_layers yes)
		(zone_layer_connections "In8.Cu")
		(net 820)
	)
	(via
		(at 246.6 165.125)
		(size 0.45)
		(drill 0.1)
		(layers "F.Cu" "B.Cu")
		(remove_unused_layers yes)
		(keep_end_layers yes)
		(zone_layer_connections "In8.Cu")
		(net 820)
	)
	(via
		(at 194.5 159.500001)
		(size 0.45)
		(drill 0.1)
		(layers "F.Cu" "B.Cu")
		(remove_unused_layers yes)
		(keep_end_layers yes)
		(zone_layer_connections "In8.Cu")
		(net 820)
	)
	(via
		(at 188.5 160.5)
		(size 0.45)
		(drill 0.1)
		(layers "F.Cu" "B.Cu")
		(remove_unused_layers yes)
		(keep_end_layers yes)
		(zone_layer_connections "In8.Cu")
		(net 820)
	)
	(via
		(at 246.2 165.625)
		(size 0.45)
		(drill 0.1)
		(layers "F.Cu" "B.Cu")
		(remove_unused_layers yes)
		(keep_end_layers yes)
		(zone_layer_connections "In8.Cu")
		(net 820)
	)
	(via
		(at 183.5 159.5)
		(size 0.45)
		(drill 0.1)
		(layers "F.Cu" "B.Cu")
		(remove_unused_layers yes)
		(keep_end_layers yes)
		(zone_layer_connections "In8.Cu")
		(net 820)
	)
	(via
		(at 246 165.125)
		(size 0.45)
		(drill 0.1)
		(layers "F.Cu" "B.Cu")
		(remove_unused_layers yes)
		(keep_end_layers yes)
		(zone_layer_connections "In8.Cu")
		(net 820)
	)
	(via
		(at 245.6 165.625)
		(size 0.45)
		(drill 0.1)
		(layers "F.Cu" "B.Cu")
		(remove_unused_layers yes)
		(keep_end_layers yes)
		(zone_layer_connections "In8.Cu")
		(net 820)
	)
	(via
		(at 196.5 159.5)
		(size 0.45)
		(drill 0.1)
		(layers "F.Cu" "B.Cu")
		(remove_unused_layers yes)
		(keep_end_layers yes)
		(zone_layer_connections "In8.Cu")
		(net 820)
	)
	(segment
		(start 187 160.002)
		(end 187 160)
		(width 0.256)
		(layer "B.Cu")
		(net 820)
	)
	(segment
		(start 187 160)
		(end 187.5 159.5)
		(width 0.256)
		(layer "B.Cu")
		(net 820)
	)
	(segment
		(start 188.5 160.5)
		(end 188.5 159.9)
		(width 0.4)
		(layer "B.Cu")
		(net 820)
	)
	(segment
		(start 186 160.002)
		(end 186 160.000001)
		(width 0.256)
		(layer "B.Cu")
		(net 820)
	)
	(segment
		(start 184 159)
		(end 183.5 159.5)
		(width 0.256)
		(layer "B.Cu")
		(net 820)
	)
	(segment
		(start 198.4995 159.4995)
		(end 198.4995 159.4985)
		(width 0.256)
		(layer "B.Cu")
		(net 820)
	)
	(segment
		(start 194.997999 159.002002)
		(end 194.5 159.500001)
		(width 0.256)
		(layer "B.Cu")
		(net 820)
	)
	(segment
		(start 188.1 159.5)
		(end 188.5 159.9)
		(width 0.4)
		(layer "B.Cu")
		(net 820)
	)
	(segment
		(start 196.5 159.5)
		(end 197 159)
		(width 0.256)
		(layer "B.Cu")
		(net 820)
	)
	(segment
		(start 198.4995 159.4985)
		(end 198.998 159)
		(width 0.256)
		(layer "B.Cu")
		(net 820)
	)
	(segment
		(start 194.997999 159)
		(end 194.997999 159.002002)
		(width 0.256)
		(layer "B.Cu")
		(net 820)
	)
	(segment
		(start 186 160.000001)
		(end 185.5 159.500001)
		(width 0.256)
		(layer "B.Cu")
		(net 820)
	)
	(segment
		(start 187.5 159.5)
		(end 188.1 159.5)
		(width 0.4)
		(layer "B.Cu")
		(net 820)
	)
	(segment
		(start 118.114999 125.327487)
		(end 119.904896 125.327487)
		(width 0.4)
		(layer "B.Cu")
		(net 821)
	)
	(segment
		(start 119.9 125.307383)
		(end 119.91 125.317383)
		(width 0.2)
		(layer "B.Cu")
		(net 821)
	)
	(segment
		(start 118.164999 125.377487)
		(end 118.114999 125.327487)
		(width 0.2)
		(layer "B.Cu")
		(net 821)
	)
	(segment
		(start 119.904896 125.327487)
		(end 119.91 125.322383)
		(width 0.4)
		(layer "B.Cu")
		(net 821)
	)
	(segment
		(start 115.574999 126.597487)
		(end 113.994398 126.597487)
		(width 0.4)
		(layer "B.Cu")
		(net 822)
	)
	(segment
		(start 113.994398 126.597487)
		(end 113.991885 126.6)
		(width 0.198)
		(layer "B.Cu")
		(net 822)
	)
	(segment
		(start 106.895 121.85)
		(end 106.895 121.058488)
		(width 0.256)
		(layer "B.Cu")
		(net 823)
	)
	(segment
		(start 106.895 121.058488)
		(end 105.156999 119.320487)
		(width 0.256)
		(layer "B.Cu")
		(net 823)
	)
	(segment
		(start 105.906 129.234)
		(end 105.208 129.932)
		(width 0.256)
		(layer "B.Cu")
		(net 824)
	)
	(segment
		(start 105.208 129.932)
		(end 105.208 130.061487)
		(width 0.256)
		(layer "B.Cu")
		(net 824)
	)
	(segment
		(start 106.874499 129.234)
		(end 105.906 129.234)
		(width 0.256)
		(layer "B.Cu")
		(net 824)
	)
	(segment
		(start 204.75 138.0445)
		(end 203.79 138.0445)
		(width 0.256)
		(layer "B.Cu")
		(net 825)
	)
	(segment
		(start 205.7 138.1525)
		(end 204.858 138.1525)
		(width 0.256)
		(layer "B.Cu")
		(net 825)
	)
	(segment
		(start 203.79 138.0445)
		(end 203.73 138.1045)
		(width 0.256)
		(layer "B.Cu")
		(net 825)
	)
	(segment
		(start 204.858 138.1525)
		(end 204.75 138.0445)
		(width 0.256)
		(layer "B.Cu")
		(net 825)
	)
	(segment
		(start 200.501 136.301)
		(end 201.2645 137.0645)
		(width 0.4)
		(layer "B.Cu")
		(net 826)
	)
	(segment
		(start 195.5 136.301)
		(end 196.5 136.301)
		(width 0.4)
		(layer "B.Cu")
		(net 826)
	)
	(segment
		(start 184 136.301)
		(end 195.5 136.301)
		(width 0.4)
		(layer "B.Cu")
		(net 826)
	)
	(segment
		(start 201.2645 137.0645)
		(end 202.77 137.0645)
		(width 0.4)
		(layer "B.Cu")
		(net 826)
	)
	(segment
		(start 196.5 136.301)
		(end 200.501 136.301)
		(width 0.4)
		(layer "B.Cu")
		(net 826)
	)
	(segment
		(start 183 136.301)
		(end 184 136.301)
		(width 0.4)
		(layer "B.Cu")
		(net 826)
	)
	(segment
		(start 202.77 137.0645)
		(end 202.77 138.1045)
		(width 0.4)
		(layer "B.Cu")
		(net 826)
	)
	(segment
		(start 203.73 136.0045)
		(end 204.75 136.0045)
		(width 0.256)
		(layer "B.Cu")
		(net 827)
	)
	(segment
		(start 203.73 137.0645)
		(end 203.73 136.0045)
		(width 0.256)
		(layer "B.Cu")
		(net 827)
	)
	(zone
		(net 1)
		(net_name "GND")
		(layer "F.Cu")
		(hatch edge 0.5)
		(priority 38)
		(connect_pads yes
			(clearance 0.15)
		)
		(min_thickness 0.25)
		(filled_areas_thickness no)
		(fill yes
			(thermal_gap 0.5)
			(thermal_bridge_width 0.5)
		)
		(polygon
			(pts
				(xy 263.85 112.15) (xy 253.9 112.15) (xy 251.4 114.65) (xy 251.4 116.05) (xy 251.285 116.165) (xy 250.08 116.165)
				(xy 250.08 116.755) (xy 250.175 116.85) (xy 251.45 116.85) (xy 251.45 118) (xy 249.8 119.65) (xy 249.8 120.45)
				(xy 250 120.65) (xy 251 120.65) (xy 255.2 116.45) (xy 263.6 116.45) (xy 263.85 116.2)
			)
		)
	)
	(zone
		(net 151)
		(net_name "+3V3")
		(layer "F.Cu")
		(hatch edge 0.5)
		(priority 42)
		(connect_pads yes
			(clearance 0.12)
		)
		(min_thickness 0.25)
		(filled_areas_thickness no)
		(fill yes
			(thermal_gap 0.5)
			(thermal_bridge_width 0.5)
		)
		(polygon
			(pts
				(xy 255.9185 102.235) (xy 257.24 102.235) (xy 257.6705 101.8045) (xy 258.0455 101.8045) (xy 258.0455 103.8045)
				(xy 257.89 103.96) (xy 255.9185 103.96)
			)
		)
	)
	(zone
		(net 324)
		(net_name "/Supply/12V_PCIE_fused")
		(layer "F.Cu")
		(hatch edge 0.508)
		(priority 3)
		(connect_pads yes
			(clearance 0.2)
		)
		(min_thickness 0.2)
		(filled_areas_thickness no)
		(fill yes
			(thermal_gap 0.3)
			(thermal_bridge_width 0.3)
		)
		(polygon
			(pts
				(xy 148.324499 190.149) (xy 148.788999 190.6135) (xy 151.124499 190.6135) (xy 151.524499 191.049)
				(xy 152.659999 191.049) (xy 152.659999 193.749) (xy 151.624499 193.749) (xy 151.024499 193.1135)
				(xy 148.424499 193.1135) (xy 148.124499 192.8135) (xy 145.024499 192.8135) (xy 145.024499 188.949)
				(xy 148.324499 188.949)
			)
		)
	)
	(zone
		(net 1)
		(net_name "GND")
		(layer "F.Cu")
		(hatch edge 0.5)
		(priority 29)
		(connect_pads yes
			(clearance 0.12)
		)
		(min_thickness 0.25)
		(filled_areas_thickness no)
		(fill yes
			(thermal_gap 0.5)
			(thermal_bridge_width 0.5)
		)
		(polygon
			(pts
				(xy 255.05 127.375) (xy 255.05 130.45) (xy 252.425 130.45) (xy 252.425 127.375)
			)
		)
	)
	(zone
		(net 553)
		(net_name "+0V85")
		(layer "F.Cu")
		(hatch edge 0.5)
		(priority 15)
		(connect_pads yes
			(clearance 0.12)
		)
		(min_thickness 0.25)
		(filled_areas_thickness no)
		(fill yes
			(thermal_gap 0.5)
			(thermal_bridge_width 0.5)
		)
		(polygon
			(pts
				(xy 232.85 167.925) (xy 203.92 167.925) (xy 202.51 166.515) (xy 202.51 153.189824) (xy 203.490633 152.205)
				(xy 205.953178 152.205) (xy 205.962506 157.642651) (xy 207.025183 158.687896) (xy 224.752939 158.6751)
				(xy 224.738908 163.838144) (xy 225.058015 164.156521) (xy 232.85 164.15439)
			)
		)
	)
	(zone
		(net 35)
		(net_name "VDC")
		(layer "F.Cu")
		(hatch edge 0.508)
		(priority 3)
		(connect_pads yes
			(clearance 0.12)
		)
		(min_thickness 0.254)
		(filled_areas_thickness no)
		(fill yes
			(thermal_gap 0.508)
			(thermal_bridge_width 0.508)
		)
		(polygon
			(pts
				(xy 264.025 155.325) (xy 257.925 155.325) (xy 257.925 154.025) (xy 260.025 154.025) (xy 260.025 153.425)
				(xy 261.125 153.425) (xy 261.125 147.15) (xy 264.025 147.15)
			)
		)
	)
	(zone
		(net 207)
		(net_name "Net-(C216-Pad2)")
		(layer "F.Cu")
		(hatch edge 0.5)
		(priority 8)
		(connect_pads yes
			(clearance 0.12)
		)
		(min_thickness 0.25)
		(filled_areas_thickness no)
		(fill yes
			(thermal_gap 0.5)
			(thermal_bridge_width 0.5)
		)
		(polygon
			(pts
				(xy 229.215001 182.075001) (xy 230.715001 182.075001) (xy 230.82 181.970002) (xy 230.82 179.855)
				(xy 231.22 179.455) (xy 231.22 178.765) (xy 231.339854 178.645065) (xy 233.698296 178.644998) (xy 233.79305 178.55351)
				(xy 233.7932 178.135032) (xy 233.701152 178.04502) (xy 231.43082 178.045401) (xy 231.15 177.766295)
				(xy 231.15 175.905) (xy 227.19 175.905) (xy 227.19 178.494627) (xy 227.492247 178.796874) (xy 227.802088 178.797088)
				(xy 228.006353 179.001353) (xy 228.007305 179.535568) (xy 228.398192 179.926806) (xy 228.91 179.925349)
				(xy 229.07 180.085) (xy 229.07 181.93)
			)
		)
	)
	(zone
		(net 1)
		(net_name "GND")
		(layer "F.Cu")
		(hatch edge 0.5)
		(priority 12)
		(connect_pads yes
			(clearance 0.12)
		)
		(min_thickness 0.1)
		(filled_areas_thickness no)
		(fill yes
			(thermal_gap 0.5)
			(thermal_bridge_width 0.5)
		)
		(polygon
			(pts
				(xy 221.145001 181.345001) (xy 222.079999 181.345001) (xy 222.5 180.925) (xy 222.98 180.925) (xy 223.03 180.975)
				(xy 223.03 181.455) (xy 222.98 181.505) (xy 222.56 181.505) (xy 222.52 181.545) (xy 221.18 181.545)
				(xy 221.14 181.505) (xy 221.14 181.350002)
			)
		)
	)
	(zone
		(net 1)
		(net_name "GND")
		(layer "F.Cu")
		(hatch edge 0.5)
		(priority 17)
		(connect_pads yes
			(clearance 0.12)
		)
		(min_thickness 0.25)
		(filled_areas_thickness no)
		(fill yes
			(thermal_gap 0.5)
			(thermal_bridge_width 0.5)
		)
		(polygon
			(pts
				(xy 232.94 167.93) (xy 235.505 167.93) (xy 235.615 168.04) (xy 235.615 184.104) (xy 233.76 184.104)
				(xy 233.76 182.108355) (xy 234.356234 181.51) (xy 234.350229 178.047975) (xy 231.575 178.05) (xy 231.225 177.7)
				(xy 231.225 175.925) (xy 233.085 175.925) (xy 233.085 171.08) (xy 232.94 170.935)
			)
		)
	)
	(zone
		(net 802)
		(net_name "/DDR5 RDIMM/VIN_BULK")
		(layer "F.Cu")
		(hatch edge 0.508)
		(priority 37)
		(connect_pads yes
			(clearance 0.12)
		)
		(min_thickness 0.2)
		(filled_areas_thickness no)
		(fill yes
			(thermal_gap 0.3)
			(thermal_bridge_width 0.32)
		)
		(polygon
			(pts
				(xy 251.366 105.1) (xy 251.366 107.273) (xy 250.516 108.123) (xy 250.516 111.450832) (xy 248.33704 113.675)
				(xy 242.658801 113.675) (xy 242.65619 116.057756) (xy 250.746381 116.032614) (xy 250.744314 114.589936)
				(xy 253.42 111.903587) (xy 253.42 105.745) (xy 252.775 105.1)
			)
		)
	)
	(zone
		(net 1)
		(net_name "GND")
		(layer "F.Cu")
		(hatch edge 0.5)
		(priority 14)
		(connect_pads yes
			(clearance 0.12)
		)
		(min_thickness 0.1)
		(filled_areas_thickness no)
		(fill yes
			(thermal_gap 0.5)
			(thermal_bridge_width 0.5)
		)
		(polygon
			(pts
				(xy 220.6301 177.810133) (xy 220.639271 175.93) (xy 222.185539 175.93) (xy 222.176424 170.928576)
				(xy 222.185 170.888529) (xy 222.185 167.925) (xy 226.335 167.925) (xy 226.335 170.92) (xy 225.37 171.885)
				(xy 225.37 175.8928) (xy 227.130346 175.890706) (xy 227.134737 178.719994) (xy 225.584839 178.720013)
				(xy 225.587438 180.252438) (xy 226.2 180.865) (xy 226.2 183.775) (xy 226.9 184.475) (xy 228.11 184.475)
				(xy 228.12 184.485) (xy 228.12 188.31) (xy 228.11 188.325) (xy 223.18 188.325) (xy 223.18 181.935)
				(xy 223.68 181.435) (xy 223.68 180.255) (xy 223.215001 179.790001) (xy 223.215001 177.98) (xy 220.805 177.98)
			)
		)
	)
	(zone
		(net 37)
		(net_name "/Supply/DC-DC AUX, MGT/1V8_local")
		(layer "F.Cu")
		(hatch edge 0.508)
		(priority 4)
		(connect_pads yes
			(clearance 0.12)
		)
		(min_thickness 0.254)
		(filled_areas_thickness no)
		(fill yes
			(thermal_gap 0.508)
			(thermal_bridge_width 0.508)
		)
		(polygon
			(pts
				(xy 251.22 173.872) (xy 251.52 174.072) (xy 253.22 174.072) (xy 253.22 175.372) (xy 251.62 175.372)
				(xy 249.92 178.572) (xy 248.82 178.572) (xy 247.22 178.572) (xy 247.224499 176.699) (xy 247.024499 176.499)
				(xy 246.324499 176.499) (xy 246.32 173.872)
			)
		)
	)
	(zone
		(net 820)
		(net_name "+0V9_MGTAVCC")
		(layer "F.Cu")
		(hatch edge 0.508)
		(priority 1)
		(connect_pads yes
			(clearance 0.12)
		)
		(min_thickness 0.254)
		(filled_areas_thickness no)
		(fill yes
			(thermal_gap 0.508)
			(thermal_bridge_width 0.508)
		)
		(polygon
			(pts
				(xy 243.434499 164.149) (xy 256.375499 164.149) (xy 256.375499 166.666) (xy 243.434499 166.666)
			)
		)
	)
	(zone
		(net 224)
		(net_name "/Supply/DC-DC VCCINT/0V85_REG1")
		(layer "F.Cu")
		(hatch edge 0.5)
		(priority 13)
		(connect_pads yes
			(clearance 0.12)
		)
		(min_thickness 0.1)
		(filled_areas_thickness no)
		(fill yes
			(thermal_gap 0.5)
			(thermal_bridge_width 0.5)
		)
		(polygon
			(pts
				(xy 225.4 175.8) (xy 232.91 175.8) (xy 232.91 171.135) (xy 232.85 171.075) (xy 232.85 167.925) (xy 226.425 167.925)
				(xy 226.425 170.9) (xy 225.4 171.925)
			)
		)
	)
	(zone
		(net 35)
		(net_name "VDC")
		(layer "F.Cu")
		(hatch edge 0.508)
		(priority 3)
		(connect_pads yes
			(clearance 0.12)
		)
		(min_thickness 0.254)
		(filled_areas_thickness no)
		(fill yes
			(thermal_gap 0.508)
			(thermal_bridge_width 0.508)
		)
		(polygon
			(pts
				(xy 264.025 172.825) (xy 257.925 172.825) (xy 257.925 171.525) (xy 260.025 171.525) (xy 260.024499 171.299)
				(xy 261.125 170.199) (xy 261.125 165.325) (xy 264.025 165.325)
			)
		)
	)
	(zone
		(net 35)
		(net_name "VDC")
		(layer "F.Cu")
		(hatch edge 0.508)
		(priority 4)
		(connect_pads yes
			(clearance 0.2)
		)
		(min_thickness 0.254)
		(filled_areas_thickness no)
		(fill yes
			(thermal_gap 0.3)
			(thermal_bridge_width 0.3)
		)
		(polygon
			(pts
				(xy 152.174499 186.749) (xy 152.724499 187.299) (xy 152.724499 190.449) (xy 151.774499 190.449)
				(xy 151.374499 190.099) (xy 149.174499 190.099) (xy 149.174499 188.875) (xy 145.025 188.875) (xy 145.025 188.775)
				(xy 145.025 187.125) (xy 147.925 184.175) (xy 152.174499 184.175)
			)
		)
	)
	(zone
		(net 1)
		(net_name "GND")
		(layer "F.Cu")
		(hatch edge 0.508)
		(priority 27)
		(connect_pads yes
			(clearance 0.12)
		)
		(min_thickness 0.254)
		(filled_areas_thickness no)
		(fill yes
			(thermal_gap 0.508)
			(thermal_bridge_width 0.508)
		)
		(polygon
			(pts
				(xy 224.75 158.425) (xy 224.75 155.75) (xy 224.575 155.575) (xy 206.075 155.575) (xy 206.075 157.425)
				(xy 207.075 158.425)
			)
		)
	)
	(zone
		(net 1)
		(net_name "GND")
		(layer "F.Cu")
		(hatch edge 0.508)
		(priority 1)
		(connect_pads yes
			(clearance 0.15)
		)
		(min_thickness 0.254)
		(filled_areas_thickness no)
		(fill yes
			(thermal_gap 0.508)
			(thermal_bridge_width 0.508)
		)
		(polygon
			(pts
				(xy 242.601751 115.97) (xy 244.524499 115.97) (xy 244.524499 122.074) (xy 242.749499 122.074) (xy 242.749499 130.949)
				(xy 237.449499 130.949) (xy 237.449499 114.581609) (xy 237.449499 113.681716) (xy 242.591754 113.680599)
			)
		)
	)
	(zone
		(net 323)
		(net_name "/Supply/12V_aux_fused")
		(layer "F.Cu")
		(hatch edge 0.5)
		(priority 54)
		(connect_pads yes
			(clearance 0.15)
		)
		(min_thickness 0.25)
		(filled_areas_thickness no)
		(fill yes
			(thermal_gap 0.5)
			(thermal_bridge_width 0.5)
		)
		(polygon
			(pts
				(xy 249.27 124.5) (xy 251.9 124.5) (xy 252.05 124.65) (xy 252.05 126.55) (xy 251.9 126.7) (xy 249.9 126.7)
				(xy 249.85 126.65) (xy 249.3 126.65) (xy 248.8 127.15) (xy 244.2199 127.15) (xy 242.949499 125.879599)
				(xy 242.949499 122.6) (xy 244.15 122.6) (xy 245.7 124.15) (xy 248.92 124.15)
			)
		)
	)
	(zone
		(net 38)
		(net_name "+3V3_AON")
		(layer "F.Cu")
		(hatch edge 0.508)
		(priority 1)
		(connect_pads yes
			(clearance 0.1)
		)
		(min_thickness 0.254)
		(filled_areas_thickness no)
		(fill yes
			(thermal_gap 0.508)
			(thermal_bridge_width 0.508)
		)
		(polygon
			(pts
				(xy 257.262998 128.724) (xy 255.132998 128.724) (xy 255.132998 127.409) (xy 257.262998 127.409)
			)
		)
	)
	(zone
		(net 1)
		(net_name "GND")
		(layer "F.Cu")
		(hatch edge 0.508)
		(priority 2)
		(connect_pads yes
			(clearance 0.2)
		)
		(min_thickness 0.254)
		(filled_areas_thickness no)
		(fill yes
			(thermal_gap 0.3)
			(thermal_bridge_width 0.3)
		)
		(polygon
			(pts
				(xy 158.543667 184.12948) (xy 158.51224 188.859225) (xy 157.124499 190.249) (xy 157.124499 194.099)
				(xy 156.424499 194.099) (xy 155.824499 194.699) (xy 155.825 196.725) (xy 148.324499 196.725) (xy 148.324499 195.799)
				(xy 149.224499 194.899) (xy 149.224499 193.249) (xy 150.924499 193.249) (xy 151.624499 193.925)
				(xy 152.725 193.925) (xy 152.724499 190.549) (xy 154.675491 190.549) (xy 154.67764 189.303049) (xy 153.174499 189.299)
				(xy 153.177799 187.630238) (xy 152.274799 186.699) (xy 152.272781 184.124051) (xy 152.325 184.125)
			)
		)
	)
	(zone
		(net 46)
		(net_name "/Supply/DC-DC IO/5V_local")
		(layer "F.Cu")
		(hatch edge 0.508)
		(priority 2)
		(connect_pads yes
			(clearance 0.12)
		)
		(min_thickness 0.254)
		(filled_areas_thickness no)
		(fill yes
			(thermal_gap 0.508)
			(thermal_bridge_width 0.508)
		)
		(polygon
			(pts
				(xy 251.193 154.121) (xy 251.493 153.921) (xy 253.193 153.921) (xy 253.193 152.621) (xy 251.593 152.621)
				(xy 249.893 149.421) (xy 247.174499 149.421) (xy 247.179999 151.349) (xy 247.024499 151.499) (xy 246.249499 151.499)
				(xy 246.249499 154.121)
			)
		)
	)
	(zone
		(net 151)
		(net_name "+3V3")
		(layer "F.Cu")
		(hatch edge 0.508)
		(priority 4)
		(connect_pads yes
			(clearance 0.12)
		)
		(min_thickness 0.254)
		(filled_areas_thickness no)
		(fill yes
			(thermal_gap 0.508)
			(thermal_bridge_width 0.508)
		)
		(polygon
			(pts
				(xy 246.174499 155.293) (xy 246.174499 159.099) (xy 245.574499 159.099) (xy 245.374499 159.299)
				(xy 245.374499 161.109) (xy 243.407499 161.109) (xy 243.407499 155.293)
			)
		)
	)
	(zone
		(net 163)
		(net_name "/Supply/DC-DC VCCINT/V_{CC}")
		(layer "F.Cu")
		(hatch edge 0.5)
		(priority 11)
		(connect_pads yes
			(clearance 0.12)
		)
		(min_thickness 0.1)
		(filled_areas_thickness no)
		(fill yes
			(thermal_gap 0.5)
			(thermal_bridge_width 0.5)
		)
		(polygon
			(pts
				(xy 231.840001 180.940001) (xy 232.595 180.940001) (xy 232.875 180.660001) (xy 232.875 180.200001)
				(xy 233.120001 179.955) (xy 233.67 179.955) (xy 233.735 180.02) (xy 233.735 180.7) (xy 233.625 180.81)
				(xy 233.275 180.81) (xy 232.944999 181.140001) (xy 231.840001 181.140001)
			)
		)
	)
	(zone
		(net 0)
		(net_name "")
		(layer "F.Cu")
		(hatch edge 0.5)
		(connect_pads yes
			(clearance 0)
		)
		(min_thickness 0.25)
		(filled_areas_thickness no)
		(keepout
			(tracks allowed)
			(vias allowed)
			(pads allowed)
			(copperpour not_allowed)
			(footprints allowed)
		)
		(placement
			(enabled no)
			(sheetname "")
		)
		(fill
			(thermal_gap 0.5)
			(thermal_bridge_width 0.5)
		)
		(polygon
			(pts
				(xy 213.65 174.5) (xy 213.630225 174.147872) (xy 213.571148 173.800172) (xy 213.473513 173.461272)
				(xy 213.338547 173.135436) (xy 213.167948 172.826759) (xy 212.96386 172.539125) (xy 212.728851 172.276149)
				(xy 212.465875 172.04114) (xy 212.178241 171.837052) (xy 211.869564 171.666453) (xy 211.543728 171.531487)
				(xy 211.204828 171.433852) (xy 210.857128 171.374775) (xy 210.505 171.355) (xy 210.152872 171.374775)
				(xy 209.805172 171.433852) (xy 209.466272 171.531487) (xy 209.140436 171.666453) (xy 208.831759 171.837052)
				(xy 208.544125 172.04114) (xy 208.281149 172.276149) (xy 208.04614 172.539125) (xy 207.842052 172.826759)
				(xy 207.671453 173.135436) (xy 207.536487 173.461272) (xy 207.438852 173.800172) (xy 207.379775 174.147872)
				(xy 207.36 174.5) (xy 207.379775 174.852128) (xy 207.438852 175.199828) (xy 207.536487 175.538728)
				(xy 207.671453 175.864564) (xy 207.842052 176.173241) (xy 208.04614 176.460875) (xy 208.281149 176.723851)
				(xy 208.544125 176.95886) (xy 208.831759 177.162948) (xy 209.140436 177.333547) (xy 209.466272 177.468513)
				(xy 209.805172 177.566148) (xy 210.152872 177.625225) (xy 210.505 177.645) (xy 210.857128 177.625225)
				(xy 211.204828 177.566148) (xy 211.543728 177.468513) (xy 211.869564 177.333547) (xy 212.178241 177.162948)
				(xy 212.465875 176.95886) (xy 212.728851 176.723851) (xy 212.96386 176.460875) (xy 213.167948 176.173241)
				(xy 213.338547 175.864564) (xy 213.473513 175.538728) (xy 213.571148 175.199828) (xy 213.630225 174.852128)
			)
		)
	)
	(zone
		(net 814)
		(net_name "Net-(Q29-D)")
		(layer "F.Cu")
		(hatch edge 0.5)
		(priority 49)
		(connect_pads yes
			(clearance 0.15)
		)
		(min_thickness 0.25)
		(filled_areas_thickness no)
		(fill yes
			(thermal_gap 0.5)
			(thermal_bridge_width 0.5)
		)
		(polygon
			(pts
				(xy 242.85 119.85) (xy 244.95 119.85) (xy 245.65 120.55) (xy 245.65 120.6) (xy 245.9 120.85) (xy 248.3 120.85)
				(xy 248.4 120.95) (xy 248.4 123.15) (xy 248.3 123.25) (xy 245.9 123.25) (xy 245.65 123) (xy 245.65 122)
				(xy 244.6 120.95) (xy 242.95 120.95) (xy 242.85 120.85)
			)
		)
	)
	(zone
		(net 172)
		(net_name "+1V2_MGTAVTT")
		(layer "F.Cu")
		(hatch edge 0.508)
		(priority 2)
		(connect_pads yes
			(clearance 0.12)
		)
		(min_thickness 0.254)
		(filled_areas_thickness no)
		(fill yes
			(thermal_gap 0.508)
			(thermal_bridge_width 0.508)
		)
		(polygon
			(pts
				(xy 245.544499 166.925) (xy 245.544499 168.869) (xy 246.224499 169.549) (xy 246.224499 172.641)
				(xy 243.407499 172.641) (xy 243.407499 166.925)
			)
		)
	)
	(zone
		(net 10)
		(net_name "+12V")
		(layer "F.Cu")
		(hatch edge 0.508)
		(priority 1)
		(connect_pads yes
			(clearance 0.2)
		)
		(min_thickness 0.254)
		(filled_areas_thickness no)
		(fill yes
			(thermal_gap 0.3)
			(thermal_bridge_width 0.256)
		)
		(polygon
			(pts
				(xy 148.324499 193.249) (xy 149.074499 193.249) (xy 149.074499 194.899) (xy 148.225 195.749) (xy 148.225 196.725)
				(xy 145.025 196.725) (xy 145.025 192.925) (xy 148.024499 192.925)
			)
		)
	)
	(zone
		(net 167)
		(net_name "Net-(U36-BST)")
		(layer "F.Cu")
		(hatch edge 0.5)
		(priority 10)
		(connect_pads yes
			(clearance 0.12)
		)
		(min_thickness 0.25)
		(filled_areas_thickness no)
		(fill yes
			(thermal_gap 0.5)
			(thermal_bridge_width 0.5)
		)
		(polygon
			(pts
				(xy 231.865001 180.675001) (xy 232.72 180.675001) (xy 232.86 180.535001) (xy 232.86 180.185) (xy 233.44 179.605)
				(xy 233.69 179.605) (xy 233.78 179.515) (xy 233.78 179.075) (xy 233.71 179.005) (xy 233.22 179.005)
				(xy 233.04 179.185) (xy 233.04 179.405) (xy 232.1 180.345) (xy 231.9 180.345) (xy 231.865001 180.379999)
			)
		)
	)
	(zone
		(net 159)
		(net_name "/Supply/DC-DC IO/1V2_local")
		(layer "F.Cu")
		(hatch edge 0.508)
		(priority 2)
		(connect_pads yes
			(clearance 0.12)
		)
		(min_thickness 0.254)
		(filled_areas_thickness no)
		(fill yes
			(thermal_gap 0.508)
			(thermal_bridge_width 0.508)
		)
		(polygon
			(pts
				(xy 257.618 159.643304) (xy 257.624206 160.961279) (xy 258.207696 161.542404) (xy 258.206114 163.309177)
				(xy 257.618653 163.906583) (xy 257.618 163.971) (xy 260.993 163.971) (xy 260.993 158.721) (xy 260.293 158.721)
				(xy 259.393 157.821) (xy 256.893 157.821) (xy 256.893 158.999)
			)
		)
	)
	(zone
		(net 158)
		(net_name "/Supply/DC-DC IO/VDDQ_local")
		(layer "F.Cu")
		(hatch edge 0.508)
		(priority 2)
		(connect_pads yes
			(clearance 0.12)
		)
		(min_thickness 0.254)
		(filled_areas_thickness no)
		(fill yes
			(thermal_gap 0.508)
			(thermal_bridge_width 0.508)
		)
		(polygon
			(pts
				(xy 257.568 150.621) (xy 257.568 147.121) (xy 260.993 147.121) (xy 260.993 151.921) (xy 260.293 151.921)
				(xy 259.393 152.821) (xy 256.893 152.821) (xy 256.893 151.121)
			)
		)
	)
	(zone
		(net 47)
		(net_name "/Supply/DC-DC AUX, MGT/MGTAVCC_local")
		(layer "F.Cu")
		(hatch edge 0.508)
		(priority 2)
		(connect_pads yes
			(clearance 0.12)
		)
		(min_thickness 0.254)
		(filled_areas_thickness no)
		(fill yes
			(thermal_gap 0.508)
			(thermal_bridge_width 0.508)
		)
		(polygon
			(pts
				(xy 257.9 167.755146) (xy 257.9 164.122) (xy 261.02 164.122) (xy 261.02 169.422) (xy 260.32 169.422)
				(xy 259.42 170.322) (xy 256.92 170.322) (xy 256.92 168.622)
			)
		)
	)
	(zone
		(net 1)
		(net_name "GND")
		(layer "F.Cu")
		(hatch edge 0.508)
		(connect_pads yes
			(clearance 0.12)
		)
		(min_thickness 0.254)
		(filled_areas_thickness no)
		(fill yes
			(thermal_gap 0.508)
			(thermal_bridge_width 0.508)
		)
		(polygon
			(pts
				(xy 249.993 154.221) (xy 249.993 149.821) (xy 249.993 149.471) (xy 256.868 149.471) (xy 256.868 151.021)
				(xy 259.793 151.021) (xy 259.793 155.521) (xy 263.993 155.521) (xy 263.993 165.171) (xy 261.118 165.171)
				(xy 261.118 159.021) (xy 257.393 159.021) (xy 257.393 161.121) (xy 249.993 161.121) (xy 249.993 160.721)
				(xy 249.993 156.321) (xy 246.243 156.321) (xy 246.243 154.221)
			)
		)
	)
	(zone
		(net 687)
		(net_name "VDDQ")
		(layer "F.Cu")
		(hatch edge 0.508)
		(priority 1)
		(connect_pads yes
			(clearance 0.1)
		)
		(min_thickness 0.254)
		(filled_areas_thickness no)
		(fill yes
			(thermal_gap 0.508)
			(thermal_bridge_width 0.508)
		)
		(polygon
			(pts
				(xy 255.791 149.196) (xy 243.395 149.196) (xy 243.395 147.129) (xy 255.791 147.129)
			)
		)
	)
	(zone
		(net 223)
		(net_name "/Supply/DC-DC VCCINT/0V85_REG0")
		(layer "F.Cu")
		(hatch edge 0.5)
		(priority 13)
		(connect_pads yes
			(clearance 0.12)
		)
		(min_thickness 0.1)
		(filled_areas_thickness no)
		(fill yes
			(thermal_gap 0.5)
			(thermal_bridge_width 0.5)
		)
		(polygon
			(pts
				(xy 215.16 175.795) (xy 222.15 175.795) (xy 222.15 171.075) (xy 222.15 167.925) (xy 215.9 167.925)
				(xy 215.9 170.725) (xy 215.16 171.465)
			)
		)
	)
	(zone
		(net 1)
		(net_name "GND")
		(layer "F.Cu")
		(hatch edge 0.5)
		(priority 7)
		(connect_pads yes
			(clearance 0.12)
		)
		(min_thickness 0.25)
		(filled_areas_thickness no)
		(fill yes
			(thermal_gap 0.5)
			(thermal_bridge_width 0.5)
		)
		(polygon
			(pts
				(xy 229.999882 185.015) (xy 230.19 184.82508) (xy 230.19 182.295) (xy 230.08 182.185032) (xy 229.26027 182.185274)
				(xy 229.06 181.985) (xy 229.06 180.125) (xy 228.9 179.965) (xy 228.39 179.965) (xy 227.98 179.555)
				(xy 227.98 179.015) (xy 227.81 178.845) (xy 227.29 178.845) (xy 226.56 178.845) (xy 226.56 179.585333)
				(xy 227.171284 180.266157) (xy 228.069216 180.274216) (xy 228.2 180.405) (xy 228.2 184.065) (xy 228.04 184.225)
				(xy 225.55 184.225) (xy 225.51 184.265) (xy 225.51 188.315) (xy 230.008555 188.315)
			)
		)
	)
	(zone
		(net 35)
		(net_name "VDC")
		(layer "F.Cu")
		(hatch edge 0.5)
		(priority 6)
		(connect_pads yes
			(clearance 0.12)
		)
		(min_thickness 0.25)
		(filled_areas_thickness no)
		(fill yes
			(thermal_gap 0.5)
			(thermal_bridge_width 0.5)
		)
		(polygon
			(pts
				(xy 220.51 178.865001) (xy 220.975001 178.865001) (xy 221.02 178.91) (xy 221.02 184.085) (xy 221.15 184.215)
				(xy 222.89 184.215) (xy 223.12 184.445) (xy 223.12 188.385) (xy 230.385 188.385) (xy 230.385 189.915)
				(xy 219.33 189.915) (xy 219.33 185.065) (xy 219.546658 184.848342) (xy 219.550212 182.315) (xy 219.663671 182.201329)
				(xy 219.994772 182.199792) (xy 220.1 182.094999) (xy 220.1 179.925) (xy 220.51 179.515)
			)
		)
	)
	(zone
		(net 573)
		(net_name "+1V8_MGTVCCAUX")
		(layer "F.Cu")
		(hatch edge 0.508)
		(priority 1)
		(connect_pads yes
			(clearance 0.1)
		)
		(min_thickness 0.254)
		(filled_areas_thickness no)
		(fill yes
			(thermal_gap 0.508)
			(thermal_bridge_width 0.508)
		)
		(polygon
			(pts
				(xy 243.408499 178.757) (xy 255.649499 178.757) (xy 255.649499 180.874) (xy 243.408499 180.874)
			)
		)
	)
	(zone
		(net 152)
		(net_name "+5V")
		(layer "F.Cu")
		(hatch edge 0.508)
		(priority 3)
		(connect_pads yes
			(clearance 0.12)
		)
		(min_thickness 0.254)
		(filled_areas_thickness no)
		(fill yes
			(thermal_gap 0.508)
			(thermal_bridge_width 0.508)
		)
		(polygon
			(pts
				(xy 245.374499 149.399) (xy 245.374499 151.349) (xy 245.524499 151.499) (xy 246.174499 151.499)
				(xy 246.174499 155.215) (xy 243.407499 155.215) (xy 243.407499 149.399)
			)
		)
	)
	(zone
		(net 1)
		(net_name "GND")
		(layer "F.Cu")
		(hatch edge 0.5)
		(priority 9)
		(connect_pads yes
			(clearance 0.12)
		)
		(min_thickness 0.25)
		(filled_areas_thickness no)
		(fill yes
			(thermal_gap 0.5)
			(thermal_bridge_width 0.5)
		)
		(polygon
			(pts
				(xy 221.465 178.865) (xy 221.465 179.5) (xy 221.11 179.855) (xy 221.11 179.925) (xy 221.25 180.065)
				(xy 221.75 180.065) (xy 222.055 179.76) (xy 222.055 178.865)
			)
		)
	)
	(zone
		(net 45)
		(net_name "/Supply/DC-DC IO/3V3_local")
		(layer "F.Cu")
		(hatch edge 0.508)
		(priority 5)
		(connect_pads yes
			(clearance 0.12)
		)
		(min_thickness 0.254)
		(filled_areas_thickness no)
		(fill yes
			(thermal_gap 0.508)
			(thermal_bridge_width 0.508)
		)
		(polygon
			(pts
				(xy 251.193 156.421) (xy 251.493 156.621) (xy 253.193 156.621) (xy 253.193 157.921) (xy 251.593 157.921)
				(xy 249.893 161.121) (xy 247.193001 161.120788) (xy 247.2005 159.299) (xy 247.024499 159.099) (xy 246.243 159.099)
				(xy 246.243 156.421)
			)
		)
	)
	(zone
		(net 48)
		(net_name "/Supply/DC-DC AUX, MGT/MGTAVTT_local")
		(layer "F.Cu")
		(hatch edge 0.508)
		(priority 1)
		(connect_pads yes
			(clearance 0.12)
		)
		(min_thickness 0.254)
		(filled_areas_thickness no)
		(fill yes
			(thermal_gap 0.508)
			(thermal_bridge_width 0.508)
		)
		(polygon
			(pts
				(xy 251.22 171.622) (xy 251.52 171.422) (xy 253.22 171.422) (xy 253.22 170.122) (xy 251.62 170.122)
				(xy 249.92 166.922) (xy 247.049499 166.922) (xy 247.049499 168.837606) (xy 246.32 169.568349) (xy 246.32 171.622)
			)
		)
	)
	(zone
		(net 165)
		(net_name "Net-(C215-Pad2)")
		(layer "F.Cu")
		(hatch edge 0.5)
		(priority 8)
		(connect_pads yes
			(clearance 0.12)
		)
		(min_thickness 0.25)
		(filled_areas_thickness no)
		(fill yes
			(thermal_gap 0.5)
			(thermal_bridge_width 0.5)
		)
		(polygon
			(pts
				(xy 218.495001 182.095001) (xy 219.995001 182.095001) (xy 220.1 181.990002) (xy 220.1 179.875) (xy 220.5 179.475)
				(xy 220.5 178.785) (xy 220.619854 178.665065) (xy 222.978296 178.664998) (xy 223.07305 178.57351)
				(xy 223.0732 178.155032) (xy 222.981152 178.06502) (xy 220.71082 178.065401) (xy 220.505 177.860837)
				(xy 220.505 175.925) (xy 216.47 175.925) (xy 216.47 178.938818) (xy 217.475557 179.947383) (xy 218.19 179.945349)
				(xy 218.35 180.105) (xy 218.35 181.95)
			)
		)
	)
	(zone
		(net 225)
		(net_name "/Supply/DC-DC AUX, MGT/MGTAVCCAUX_local")
		(layer "F.Cu")
		(hatch edge 0.508)
		(priority 2)
		(connect_pads yes
			(clearance 0.12)
		)
		(min_thickness 0.254)
		(filled_areas_thickness no)
		(fill yes
			(thermal_gap 0.508)
			(thermal_bridge_width 0.508)
		)
		(polygon
			(pts
				(xy 257.22 177.433644) (xy 257.22 178.525) (xy 257.547337 178.849008) (xy 257.539564 180.807) (xy 261.02 180.807)
				(xy 261.02 176.122) (xy 260.32 176.122) (xy 259.42 175.222) (xy 256.92 175.222) (xy 256.92 177.183643)
			)
		)
	)
	(zone
		(net 1)
		(net_name "GND")
		(layer "F.Cu")
		(hatch edge 0.5)
		(priority 12)
		(connect_pads yes
			(clearance 0.12)
		)
		(min_thickness 0.1)
		(filled_areas_thickness no)
		(fill yes
			(thermal_gap 0.5)
			(thermal_bridge_width 0.5)
		)
		(polygon
			(pts
				(xy 231.840001 181.340001) (xy 232.774999 181.340001) (xy 233.195 180.92) (xy 233.675 180.92) (xy 233.725 180.97)
				(xy 233.725 181.45) (xy 233.675 181.5) (xy 233.255 181.5) (xy 233.215 181.54) (xy 231.875 181.54)
				(xy 231.835 181.5) (xy 231.835 181.345002)
			)
		)
	)
	(zone
		(net 0)
		(net_name "")
		(layer "F.Cu")
		(hatch edge 0.508)
		(connect_pads yes
			(clearance 0)
		)
		(min_thickness 0.254)
		(filled_areas_thickness no)
		(keepout
			(tracks allowed)
			(vias allowed)
			(pads allowed)
			(copperpour not_allowed)
			(footprints allowed)
		)
		(placement
			(enabled no)
			(sheetname "")
		)
		(fill
			(thermal_gap 0.508)
			(thermal_bridge_width 0.508)
		)
		(polygon
			(pts
				(xy 265.905976 187.035292) (xy 265.885836 186.637722) (xy 265.825622 186.244222) (xy 265.725951 185.858822)
				(xy 265.587843 185.485467) (xy 265.412712 185.12798) (xy 265.202351 184.790022) (xy 264.958914 184.475051)
				(xy 264.684894 184.186294) (xy 264.383096 183.926707) (xy 264.05661 183.698947) (xy 263.708778 183.505347)
				(xy 263.343163 183.347888) (xy 262.963508 183.228183) (xy 262.573699 183.147457) (xy 262.177727 183.106538)
				(xy 261.779648 183.105843) (xy 261.383536 183.14538) (xy 260.993448 183.224744) (xy 260.613376 183.343123)
				(xy 260.247214 183.499305) (xy 259.898709 183.69169) (xy 259.57143 183.918309) (xy 259.268727 184.176841)
				(xy 258.993701 184.46464) (xy 258.749166 184.778759) (xy 258.537627 185.115981) (xy 258.361249 185.472854)
				(xy 258.221839 185.845725) (xy 258.120823 186.230775) (xy 258.059236 186.624062) (xy 258.037708 187.021559)
				(xy 258.05646 187.419197) (xy 258.1153 187.812905) (xy 258.213625 188.198651) (xy 258.35043 188.572485)
				(xy 258.524312 188.930581) (xy 258.733491 189.269272) (xy 258.975827 189.58509) (xy 259.248838 189.874802)
				(xy 259.549728 190.135441) (xy 259.875417 190.364339) (xy 260.22257 190.559153) (xy 260.587634 190.717887)
				(xy 260.966869 190.838916) (xy 261.356394 190.921002) (xy 261.75222 190.963304) (xy 262.150295 190.965388)
				(xy 262.546542 190.927234) (xy 262.936905 190.849232) (xy 263.317387 190.73218) (xy 263.684093 190.577277)
				(xy 264.033267 190.38611) (xy 264.361335 190.160635) (xy 264.664938 189.903161) (xy 264.940968 189.616324)
				(xy 265.186597 189.303061) (xy 265.399312 188.966579) (xy 265.576935 188.610324) (xy 265.717646 188.237942)
				(xy 265.820005 187.853247) (xy 265.882965 187.460177) (xy 265.90588 187.062757)
			)
		)
	)
	(zone
		(net 150)
		(net_name "+1V2")
		(layer "F.Cu")
		(hatch edge 0.508)
		(priority 1)
		(connect_pads yes
			(clearance 0.1)
		)
		(min_thickness 0.254)
		(filled_areas_thickness no)
		(fill yes
			(thermal_gap 0.508)
			(thermal_bridge_width 0.508)
		)
		(polygon
			(pts
				(xy 243.408499 161.383) (xy 256.210782 161.383) (xy 256.20189 163.247697) (xy 256.624499 163.66)
				(xy 256.624499 164) (xy 243.408499 164)
			)
		)
	)
	(zone
		(net 325)
		(net_name "/Supply/12V_aux")
		(layer "F.Cu")
		(hatch edge 0.5)
		(priority 40)
		(connect_pads yes
			(clearance 0.15)
		)
		(min_thickness 0.25)
		(filled_areas_thickness no)
		(fill yes
			(thermal_gap 0.5)
			(thermal_bridge_width 0.5)
		)
		(polygon
			(pts
				(xy 263.88 122.45) (xy 263.88 126.8) (xy 252.45 126.8) (xy 252.2 126.55) (xy 252.194012 124.5) (xy 251.95 124.25)
				(xy 249.3 124.25) (xy 248.95 123.9) (xy 248.95 121.85) (xy 250 120.8) (xy 251.05 120.8) (xy 252.7 122.45)
			)
		)
	)
	(zone
		(net 797)
		(net_name "+1V8")
		(layer "F.Cu")
		(hatch edge 0.508)
		(priority 3)
		(connect_pads yes
			(clearance 0.12)
		)
		(min_thickness 0.254)
		(filled_areas_thickness no)
		(fill yes
			(thermal_gap 0.508)
			(thermal_bridge_width 0.508)
		)
		(polygon
			(pts
				(xy 246.220499 176.499) (xy 245.599499 176.499) (xy 245.424499 176.673787) (xy 245.420499 178.540787)
				(xy 243.404499 178.541) (xy 243.404499 172.749) (xy 246.220499 172.749)
			)
		)
	)
	(zone
		(net 803)
		(net_name "/DDR5 RDIMM/VIN_MGMT")
		(layer "F.Cu")
		(hatch edge 0.5)
		(priority 53)
		(connect_pads yes
			(clearance 0.12)
		)
		(min_thickness 0.25)
		(filled_areas_thickness no)
		(fill yes
			(thermal_gap 0.5)
			(thermal_bridge_width 0.5)
		)
		(polygon
			(pts
				(xy 250.235 106.9) (xy 250.235 105.1) (xy 251.185 104.15) (xy 255.3 104.15) (xy 255.375 104.075)
				(xy 255.375 101.45) (xy 250.1 101.45) (xy 249.675 101.875) (xy 249.675 106.89) (xy 249.665 106.9)
			)
		)
	)
	(zone
		(net 647)
		(net_name "/HDMI + SD Card/VCCB")
		(layer "F.Cu")
		(hatch edge 0.5)
		(priority 30)
		(connect_pads yes
			(clearance 0)
		)
		(min_thickness 0.25)
		(filled_areas_thickness no)
		(fill yes
			(thermal_gap 0.5)
			(thermal_bridge_width 0.5)
		)
		(polygon
			(pts
				(xy 122.95 164.4) (xy 122.95 163.65) (xy 122 163.65) (xy 121.8 163.9) (xy 119 163.9) (xy 119 162.05)
				(xy 119.45 161.5) (xy 119.45 160.2) (xy 119.8 160.2) (xy 119.8 162.85) (xy 122.95 162.85) (xy 122.95 162.05)
				(xy 123.4 162.05) (xy 123.4 164.4) (xy 122.9 164.4)
			)
		)
	)
	(zone
		(net 1)
		(net_name "GND")
		(layer "F.Cu")
		(hatch edge 0.5)
		(priority 16)
		(connect_pads yes
			(clearance 0.12)
		)
		(min_thickness 0.25)
		(filled_areas_thickness no)
		(fill yes
			(thermal_gap 0.5)
			(thermal_bridge_width 0.5)
		)
		(polygon
			(pts
				(xy 215.785 167.94) (xy 215.785 170.71) (xy 215.045358 171.449642) (xy 215.045 175.94) (xy 216.385 175.94)
				(xy 216.385 178.61) (xy 214.635 178.61) (xy 214.635 182.86) (xy 216.135 184.36) (xy 216.135 189.89)
				(xy 209.945 189.89) (xy 209.955 189.9) (xy 209.955 167.94)
			)
		)
	)
	(zone
		(net 1)
		(net_name "GND")
		(layer "F.Cu")
		(hatch edge 0.508)
		(connect_pads yes
			(clearance 0.12)
		)
		(min_thickness 0.3)
		(filled_areas_thickness no)
		(fill yes
			(thermal_gap 0.508)
			(thermal_bridge_width 0.508)
		)
		(polygon
			(pts
				(xy 249.82 171.672) (xy 249.82 166.922) (xy 257.32 166.922) (xy 257.32 168.472) (xy 259.82 168.472)
				(xy 259.82 172.972) (xy 264.02 172.972) (xy 264.02 181) (xy 261.024499 180.999) (xy 261.02 176.472)
				(xy 256.745 176.472) (xy 256.745 178.497) (xy 250.22 178.497) (xy 250.22 178.172) (xy 250.22 173.772)
				(xy 246.32 173.772) (xy 246.32 171.672)
			)
		)
	)
	(zone
		(net 1)
		(net_name "GND")
		(layer "F.Cu")
		(hatch edge 0.5)
		(priority 7)
		(connect_pads yes
			(clearance 0.12)
		)
		(min_thickness 0.25)
		(filled_areas_thickness no)
		(fill yes
			(thermal_gap 0.5)
			(thermal_bridge_width 0.5)
		)
		(polygon
			(pts
				(xy 219.279882 185.035) (xy 219.47 184.84508) (xy 219.47 182.315) (xy 219.36 182.205032) (xy 218.54027 182.205274)
				(xy 218.34 182.005) (xy 218.34 180.145) (xy 218.18 179.985) (xy 217.46 179.985) (xy 216.34 178.865)
				(xy 215.84 178.865) (xy 215.84 179.605333) (xy 216.451284 180.286157) (xy 217.349216 180.294216)
				(xy 217.48 180.425) (xy 217.48 184.085) (xy 217.32 184.245) (xy 214.83 184.245) (xy 214.79 184.285)
				(xy 214.79 189.885) (xy 219.292628 189.885)
			)
		)
	)
	(zone
		(net 164)
		(net_name "Net-(U4-BST)")
		(layer "F.Cu")
		(hatch edge 0.5)
		(priority 10)
		(connect_pads yes
			(clearance 0.12)
		)
		(min_thickness 0.25)
		(filled_areas_thickness no)
		(fill yes
			(thermal_gap 0.5)
			(thermal_bridge_width 0.5)
		)
		(polygon
			(pts
				(xy 221.145001 180.695001) (xy 222 180.695001) (xy 222.14 180.555001) (xy 222.14 180.405) (xy 222.92 179.625)
				(xy 223.345 179.625) (xy 223.46 179.51) (xy 223.46 179.17) (xy 223.315 179.025) (xy 222.5 179.025)
				(xy 222.32 179.205) (xy 222.32 179.575) (xy 221.53 180.365) (xy 221.18 180.365) (xy 221.145001 180.399999)
			)
		)
	)
	(zone
		(net 35)
		(net_name "VDC")
		(layer "F.Cu")
		(hatch edge 0.5)
		(priority 7)
		(connect_pads yes
			(clearance 0.12)
		)
		(min_thickness 0.25)
		(filled_areas_thickness no)
		(fill yes
			(thermal_gap 0.5)
			(thermal_bridge_width 0.5)
		)
		(polygon
			(pts
				(xy 231.23 178.845001) (xy 231.695001 178.845001) (xy 231.74 178.89) (xy 231.74 184.065) (xy 231.87 184.195)
				(xy 235.618 184.195) (xy 235.618 189.895) (xy 230.05 189.895) (xy 230.05 185.045) (xy 230.266658 184.828342)
				(xy 230.270212 182.295) (xy 230.383671 182.181329) (xy 230.714772 182.179792) (xy 230.82 182.074999)
				(xy 230.82 179.905) (xy 231.23 179.495)
			)
		)
	)
	(zone
		(net 1)
		(net_name "GND")
		(layer "F.Cu")
		(hatch edge 0.5)
		(priority 9)
		(connect_pads yes
			(clearance 0.12)
		)
		(min_thickness 0.25)
		(filled_areas_thickness no)
		(fill yes
			(thermal_gap 0.5)
			(thermal_bridge_width 0.5)
		)
		(polygon
			(pts
				(xy 232.185 178.845) (xy 232.185 179.33) (xy 231.83 179.685) (xy 231.83 179.905) (xy 231.97 180.045)
				(xy 232.17 180.045) (xy 232.775 179.44) (xy 232.775 178.845)
			)
		)
	)
	(zone
		(net 35)
		(net_name "VDC")
		(layer "F.Cu")
		(hatch edge 0.508)
		(priority 3)
		(connect_pads yes
			(clearance 0.1)
		)
		(min_thickness 0.254)
		(filled_areas_thickness no)
		(fill yes
			(thermal_gap 0.508)
			(thermal_bridge_width 0.508)
		)
		(polygon
			(pts
				(xy 249.441258 129) (xy 249.441258 130.956099) (xy 242.591258 130.956099) (xy 242.591258 127.316099)
				(xy 247.825 127.316099) (xy 247.825 128.998728)
			)
		)
	)
	(zone
		(net 35)
		(net_name "VDC")
		(layer "F.Cu")
		(hatch edge 0.5)
		(priority 50)
		(connect_pads yes
			(clearance 0.15)
		)
		(min_thickness 0.25)
		(filled_areas_thickness no)
		(fill yes
			(thermal_gap 0.5)
			(thermal_bridge_width 0.5)
		)
		(polygon
			(pts
				(xy 245.8 116.45) (xy 247.95 116.45) (xy 247.95 117.65) (xy 248.1 117.8) (xy 248.7 117.8) (xy 248.85 117.65)
				(xy 250.75 117.65) (xy 250.8 117.7) (xy 250.8 118.5) (xy 249.05 120.25) (xy 249 120.25) (xy 248.8 120.45)
				(xy 246.6 120.45) (xy 246.55 120.4) (xy 246.55 118.7) (xy 245.8 117.95)
			)
		)
	)
	(zone
		(net 1)
		(net_name "GND")
		(layer "F.Cu")
		(hatch edge 0.508)
		(priority 2)
		(connect_pads yes
			(clearance 0.12)
		)
		(min_thickness 0.254)
		(filled_areas_thickness no)
		(fill yes
			(thermal_gap 0.508)
			(thermal_bridge_width 0.508)
		)
		(polygon
			(pts
				(xy 112.824499 138.249) (xy 112.824499 141.249) (xy 112.474499 141.599) (xy 111.774499 141.599)
				(xy 111.474499 141.299) (xy 111.474499 139.849) (xy 110.274499 139.849) (xy 110.274499 139.249)
				(xy 111.474499 139.249) (xy 111.474499 138.249) (xy 111.724499 137.999) (xy 112.574499 137.999)
			)
		)
	)
	(zone
		(net 163)
		(net_name "/Supply/DC-DC VCCINT/V_{CC}")
		(layer "F.Cu")
		(hatch edge 0.5)
		(priority 11)
		(connect_pads yes
			(clearance 0.12)
		)
		(min_thickness 0.1)
		(filled_areas_thickness no)
		(fill yes
			(thermal_gap 0.5)
			(thermal_bridge_width 0.5)
		)
		(polygon
			(pts
				(xy 221.145001 180.945001) (xy 221.9 180.945001) (xy 222.18 180.665001) (xy 222.18 180.555001) (xy 222.775001 179.96)
				(xy 222.975 179.96) (xy 223.04 180.025) (xy 223.04 180.705) (xy 222.93 180.815) (xy 222.58 180.815)
				(xy 222.249999 181.145001) (xy 221.145001 181.145001)
			)
		)
	)
	(zone
		(net 0)
		(net_name "")
		(layers "F.Cu" "B.Cu" "In1.Cu" "In2.Cu")
		(hatch edge 0.508)
		(connect_pads
			(clearance 0)
		)
		(min_thickness 0.254)
		(filled_areas_thickness no)
		(keepout
			(tracks not_allowed)
			(vias not_allowed)
			(pads allowed)
			(copperpour not_allowed)
			(footprints allowed)
		)
		(placement
			(enabled no)
			(sheetname "")
		)
		(fill
			(thermal_gap 0.508)
			(thermal_bridge_width 0.508)
		)
		(polygon
			(pts
				(xy 133.35 194.75) (xy 141.35 194.75) (xy 141.35 198.25) (xy 133.35 198.25)
			)
		)
	)
	(zone
		(net 0)
		(net_name "")
		(layers "F.Cu" "B.Cu" "In1.Cu" "In2.Cu")
		(hatch edge 0.508)
		(connect_pads
			(clearance 0)
		)
		(min_thickness 0.254)
		(filled_areas_thickness no)
		(keepout
			(tracks not_allowed)
			(vias not_allowed)
			(pads allowed)
			(copperpour allowed)
			(footprints allowed)
		)
		(placement
			(enabled no)
			(sheetname "")
		)
		(fill
			(thermal_gap 0.508)
			(thermal_bridge_width 0.508)
		)
		(polygon
			(pts
				(xy 100 189) (xy 145 189) (xy 145 191.825) (xy 141.35 191.825) (xy 141.35 194.75) (xy 133.35 194.75)
				(xy 133.35 190) (xy 115 190) (xy 115 198.25) (xy 100 198.25)
			)
		)
	)
	(zone
		(net 0)
		(net_name "")
		(layers "F.Cu" "B.Cu" "In1.Cu" "In2.Cu" "In3.Cu" "In4.Cu" "In5.Cu" "In6.Cu"
			"In7.Cu" "In8.Cu" "In9.Cu" "In10.Cu"
		)
		(hatch edge 0.508)
		(connect_pads yes
			(clearance 0)
		)
		(min_thickness 0.254)
		(filled_areas_thickness no)
		(keepout
			(tracks allowed)
			(vias allowed)
			(pads allowed)
			(copperpour not_allowed)
			(footprints allowed)
		)
		(placement
			(enabled no)
			(sheetname "")
		)
		(fill
			(thermal_gap 0.508)
			(thermal_bridge_width 0.508)
		)
		(polygon
			(pts
				(xy 196.75 161.526501) (xy 196.75 162.576501) (xy 196.25 162.576501) (xy 196.25 161.526502)
			)
		)
	)
	(zone
		(net 0)
		(net_name "")
		(layers "F.Cu" "B.Cu" "In1.Cu" "In2.Cu" "In3.Cu" "In4.Cu" "In5.Cu" "In6.Cu"
			"In7.Cu" "In8.Cu" "In9.Cu" "In10.Cu"
		)
		(hatch edge 0.508)
		(connect_pads yes
			(clearance 0)
		)
		(min_thickness 0.254)
		(filled_areas_thickness no)
		(keepout
			(tracks allowed)
			(vias allowed)
			(pads allowed)
			(copperpour not_allowed)
			(footprints allowed)
		)
		(placement
			(enabled no)
			(sheetname "")
		)
		(fill
			(thermal_gap 0.508)
			(thermal_bridge_width 0.508)
		)
		(polygon
			(pts
				(xy 222.655664 176.11) (xy 222.637555 175.995664) (xy 222.585 175.892519) (xy 222.503145 175.810664)
				(xy 222.4 175.758109) (xy 222.285664 175.74) (xy 222.171328 175.758109) (xy 222.068183 175.810664)
				(xy 221.986328 175.892519) (xy 221.933773 175.995664) (xy 221.915664 176.11) (xy 221.933773 176.224336)
				(xy 221.986328 176.327481) (xy 222.068183 176.409336) (xy 222.171328 176.461891) (xy 222.285664 176.48)
				(xy 222.4 176.461891) (xy 222.503145 176.409336) (xy 222.585 176.327481) (xy 222.637555 176.224336)
			)
		)
	)
	(zone
		(net 0)
		(net_name "")
		(layers "F.Cu" "B.Cu" "In1.Cu" "In2.Cu" "In3.Cu" "In4.Cu" "In5.Cu" "In6.Cu"
			"In7.Cu" "In8.Cu" "In9.Cu" "In10.Cu"
		)
		(hatch edge 0.508)
		(connect_pads yes
			(clearance 0)
		)
		(min_thickness 0.254)
		(filled_areas_thickness no)
		(keepout
			(tracks allowed)
			(vias allowed)
			(pads allowed)
			(copperpour not_allowed)
			(footprints allowed)
		)
		(placement
			(enabled no)
			(sheetname "")
		)
		(fill
			(thermal_gap 0.508)
			(thermal_bridge_width 0.508)
		)
		(polygon
			(pts
				(xy 198.75 161.476501) (xy 198.75 162.526501) (xy 198.25 162.526501) (xy 198.25 161.476502)
			)
		)
	)
	(zone
		(net 0)
		(net_name "")
		(layers "F.Cu" "B.Cu" "In1.Cu" "In2.Cu" "In3.Cu" "In4.Cu" "In5.Cu" "In6.Cu"
			"In7.Cu" "In8.Cu" "In9.Cu" "In10.Cu"
		)
		(hatch edge 0.508)
		(connect_pads yes
			(clearance 0)
		)
		(min_thickness 0.254)
		(filled_areas_thickness no)
		(keepout
			(tracks allowed)
			(vias allowed)
			(pads allowed)
			(copperpour not_allowed)
			(footprints allowed)
		)
		(placement
			(enabled no)
			(sheetname "")
		)
		(fill
			(thermal_gap 0.508)
			(thermal_bridge_width 0.508)
		)
		(polygon
			(pts
				(xy 192.75 161.526501) (xy 192.75 162.576501) (xy 192.25 162.576501) (xy 192.25 161.526502)
			)
		)
	)
	(zone
		(net 0)
		(net_name "")
		(layers "F.Cu" "B.Cu" "In1.Cu" "In2.Cu" "In3.Cu" "In4.Cu" "In5.Cu" "In6.Cu"
			"In7.Cu" "In8.Cu" "In9.Cu" "In10.Cu"
		)
		(hatch edge 0.508)
		(connect_pads yes
			(clearance 0)
		)
		(min_thickness 0.254)
		(filled_areas_thickness no)
		(keepout
			(tracks allowed)
			(vias allowed)
			(pads allowed)
			(copperpour not_allowed)
			(footprints allowed)
		)
		(placement
			(enabled no)
			(sheetname "")
		)
		(fill
			(thermal_gap 0.508)
			(thermal_bridge_width 0.508)
		)
		(polygon
			(pts
				(xy 190.75 161.526501) (xy 190.75 162.576501) (xy 190.25 162.576501) (xy 190.25 161.526502)
			)
		)
	)
	(zone
		(net 0)
		(net_name "")
		(layers "F.Cu" "B.Cu" "In1.Cu" "In2.Cu" "In3.Cu" "In4.Cu" "In5.Cu" "In6.Cu"
			"In7.Cu" "In8.Cu" "In9.Cu" "In10.Cu"
		)
		(hatch edge 0.508)
		(connect_pads yes
			(clearance 0)
		)
		(min_thickness 0.254)
		(filled_areas_thickness no)
		(keepout
			(tracks allowed)
			(vias allowed)
			(pads allowed)
			(copperpour not_allowed)
			(footprints allowed)
		)
		(placement
			(enabled no)
			(sheetname "")
		)
		(fill
			(thermal_gap 0.508)
			(thermal_bridge_width 0.508)
		)
		(polygon
			(pts
				(xy 201.75 159.526501) (xy 201.75 160.576501) (xy 201.25 160.576501) (xy 201.25 159.526502)
			)
		)
	)
	(zone
		(net 0)
		(net_name "")
		(layers "F.Cu" "B.Cu" "In1.Cu" "In2.Cu" "In3.Cu" "In4.Cu" "In5.Cu" "In6.Cu"
			"In7.Cu" "In8.Cu" "In9.Cu" "In10.Cu"
		)
		(hatch edge 0.508)
		(connect_pads yes
			(clearance 0)
		)
		(min_thickness 0.254)
		(filled_areas_thickness no)
		(keepout
			(tracks allowed)
			(vias allowed)
			(pads allowed)
			(copperpour not_allowed)
			(footprints allowed)
		)
		(placement
			(enabled no)
			(sheetname "")
		)
		(fill
			(thermal_gap 0.508)
			(thermal_bridge_width 0.508)
		)
		(polygon
			(pts
				(xy 194.75 161.526501) (xy 194.75 162.576501) (xy 194.25 162.576501) (xy 194.25 161.526502)
			)
		)
	)
	(zone
		(net 0)
		(net_name "")
		(layers "F.Cu" "B.Cu" "In1.Cu" "In2.Cu" "In3.Cu" "In4.Cu" "In5.Cu" "In6.Cu"
			"In7.Cu" "In8.Cu" "In9.Cu" "In10.Cu"
		)
		(hatch edge 0.508)
		(connect_pads yes
			(clearance 0)
		)
		(min_thickness 0.254)
		(filled_areas_thickness no)
		(keepout
			(tracks allowed)
			(vias allowed)
			(pads allowed)
			(copperpour not_allowed)
			(footprints allowed)
		)
		(placement
			(enabled no)
			(sheetname "")
		)
		(fill
			(thermal_gap 0.508)
			(thermal_bridge_width 0.508)
		)
		(polygon
			(pts
				(xy 199.75 159.526501) (xy 199.75 160.576501) (xy 199.275 160.576501) (xy 199.275 159.526502)
			)
		)
	)
	(zone
		(net 0)
		(net_name "")
		(layers "F.Cu" "B.Cu" "In1.Cu" "In2.Cu" "In3.Cu" "In4.Cu" "In5.Cu" "In6.Cu"
			"In7.Cu" "In8.Cu" "In9.Cu" "In10.Cu"
		)
		(hatch edge 0.508)
		(connect_pads yes
			(clearance 0)
		)
		(min_thickness 0.254)
		(filled_areas_thickness no)
		(keepout
			(tracks allowed)
			(vias allowed)
			(pads allowed)
			(copperpour not_allowed)
			(footprints allowed)
		)
		(placement
			(enabled no)
			(sheetname "")
		)
		(fill
			(thermal_gap 0.508)
			(thermal_bridge_width 0.508)
		)
		(polygon
			(pts
				(xy 185.75 161.526501) (xy 185.75 162.576501) (xy 185.25 162.576501) (xy 185.25 161.526502)
			)
		)
	)
	(zone
		(net 0)
		(net_name "")
		(layers "F.Cu" "B.Cu" "In1.Cu" "In2.Cu" "In3.Cu" "In4.Cu" "In5.Cu" "In6.Cu"
			"In7.Cu" "In8.Cu" "In9.Cu" "In10.Cu"
		)
		(hatch edge 0.508)
		(connect_pads yes
			(clearance 0)
		)
		(min_thickness 0.254)
		(filled_areas_thickness no)
		(keepout
			(tracks allowed)
			(vias allowed)
			(pads allowed)
			(copperpour not_allowed)
			(footprints allowed)
		)
		(placement
			(enabled no)
			(sheetname "")
		)
		(fill
			(thermal_gap 0.508)
			(thermal_bridge_width 0.508)
		)
		(polygon
			(pts
				(xy 187.75 161.5) (xy 187.75 162.55) (xy 187.25 162.55) (xy 187.25 161.500001)
			)
		)
	)
	(zone
		(net 0)
		(net_name "")
		(layers "F.Cu" "B.Cu" "In1.Cu" "In2.Cu" "In3.Cu" "In4.Cu" "In5.Cu" "In6.Cu"
			"In7.Cu" "In8.Cu" "In9.Cu" "In10.Cu"
		)
		(hatch edge 0.508)
		(connect_pads yes
			(clearance 0)
		)
		(min_thickness 0.254)
		(filled_areas_thickness no)
		(keepout
			(tracks allowed)
			(vias allowed)
			(pads allowed)
			(copperpour not_allowed)
			(footprints allowed)
		)
		(placement
			(enabled no)
			(sheetname "")
		)
		(fill
			(thermal_gap 0.508)
			(thermal_bridge_width 0.508)
		)
		(polygon
			(pts
				(xy 221.855 176.11) (xy 221.836891 175.995664) (xy 221.784336 175.892519) (xy 221.702481 175.810664)
				(xy 221.599336 175.758109) (xy 221.485 175.74) (xy 221.370664 175.758109) (xy 221.267519 175.810664)
				(xy 221.185664 175.892519) (xy 221.133109 175.995664) (xy 221.115 176.11) (xy 221.133109 176.224336)
				(xy 221.185664 176.327481) (xy 221.267519 176.409336) (xy 221.370664 176.461891) (xy 221.485 176.48)
				(xy 221.599336 176.461891) (xy 221.702481 176.409336) (xy 221.784336 176.327481) (xy 221.836891 176.224336)
			)
		)
	)
	(zone
		(net 0)
		(net_name "")
		(layers "F.Cu" "B.Cu" "In1.Cu" "In2.Cu" "In3.Cu" "In4.Cu" "In5.Cu" "In6.Cu"
			"In7.Cu" "In8.Cu" "In9.Cu" "In10.Cu"
		)
		(hatch edge 0.508)
		(connect_pads yes
			(clearance 0)
		)
		(min_thickness 0.254)
		(filled_areas_thickness no)
		(keepout
			(tracks allowed)
			(vias allowed)
			(pads allowed)
			(copperpour not_allowed)
			(footprints allowed)
		)
		(placement
			(enabled no)
			(sheetname "")
		)
		(fill
			(thermal_gap 0.508)
			(thermal_bridge_width 0.508)
		)
		(polygon
			(pts
				(xy 183.75 161.5) (xy 183.75 162.55) (xy 183.25 162.55) (xy 183.25 161.500001)
			)
		)
	)
	(zone
		(net 0)
		(net_name "")
		(layers "F.Cu" "B.Cu" "In1.Cu" "In2.Cu" "In3.Cu" "In4.Cu" "In5.Cu" "In6.Cu"
			"In7.Cu" "In8.Cu" "In9.Cu" "In10.Cu"
		)
		(hatch edge 0.508)
		(connect_pads yes
			(clearance 0)
		)
		(min_thickness 0.254)
		(filled_areas_thickness no)
		(keepout
			(tracks allowed)
			(vias allowed)
			(pads allowed)
			(copperpour not_allowed)
			(footprints allowed)
		)
		(placement
			(enabled no)
			(sheetname "")
		)
		(fill
			(thermal_gap 0.508)
			(thermal_bridge_width 0.508)
		)
		(polygon
			(pts
				(xy 186.75 159.476501) (xy 186.75 160.526501) (xy 186.25 160.526501) (xy 186.25 159.476502)
			)
		)
	)
	(zone
		(net 0)
		(net_name "")
		(layers "F.Cu" "B.Cu" "In1.Cu" "In2.Cu" "In3.Cu" "In4.Cu" "In5.Cu" "In6.Cu"
			"In7.Cu" "In8.Cu" "In9.Cu" "In10.Cu"
		)
		(hatch edge 0.508)
		(connect_pads yes
			(clearance 0)
		)
		(min_thickness 0.254)
		(filled_areas_thickness no)
		(keepout
			(tracks allowed)
			(vias allowed)
			(pads allowed)
			(copperpour not_allowed)
			(footprints allowed)
		)
		(placement
			(enabled no)
			(sheetname "")
		)
		(fill
			(thermal_gap 0.508)
			(thermal_bridge_width 0.508)
		)
		(polygon
			(pts
				(xy 200.75 157.499999) (xy 200.75 158.549999) (xy 200.25 158.549999) (xy 200.25 157.5)
			)
		)
	)
	(zone
		(net 0)
		(net_name "")
		(layers "F.Cu" "B.Cu" "In1.Cu" "In2.Cu" "In3.Cu" "In4.Cu" "In5.Cu" "In6.Cu"
			"In7.Cu" "In8.Cu" "In9.Cu" "In10.Cu"
		)
		(hatch edge 0.508)
		(connect_pads yes
			(clearance 0)
		)
		(min_thickness 0.254)
		(filled_areas_thickness no)
		(keepout
			(tracks allowed)
			(vias allowed)
			(pads allowed)
			(copperpour not_allowed)
			(footprints allowed)
		)
		(placement
			(enabled no)
			(sheetname "")
		)
		(fill
			(thermal_gap 0.508)
			(thermal_bridge_width 0.508)
		)
		(polygon
			(pts
				(xy 181.75 161.5) (xy 181.75 162.55) (xy 181.25 162.55) (xy 181.25 161.500001)
			)
		)
	)
	(zone
		(net 223)
		(net_name "/Supply/DC-DC VCCINT/0V85_REG0")
		(layer "B.Cu")
		(hatch edge 0.5)
		(priority 18)
		(connect_pads yes
			(clearance 0.12)
		)
		(min_thickness 0.25)
		(filled_areas_thickness no)
		(fill yes
			(thermal_gap 0.5)
			(thermal_bridge_width 0.5)
		)
		(polygon
			(pts
				(xy 216.26 172.06) (xy 221.635 172.06) (xy 221.635 167.935) (xy 216.235 167.935) (xy 216.235 172.035)
			)
		)
	)
	(zone
		(net 35)
		(net_name "VDC")
		(layer "B.Cu")
		(hatch edge 0.5)
		(priority 21)
		(connect_pads yes
			(clearance 0.12)
		)
		(min_thickness 0.25)
		(filled_areas_thickness no)
		(fill yes
			(thermal_gap 0.5)
			(thermal_bridge_width 0.5)
		)
		(polygon
			(pts
				(xy 230.085 184.935) (xy 233.535 184.935) (xy 233.56 184.96) (xy 233.56 189.86) (xy 222.81 189.86)
				(xy 222.81 188.41) (xy 230.06 188.41) (xy 230.06 184.96)
			)
		)
	)
	(zone
		(net 151)
		(net_name "+3V3")
		(layer "B.Cu")
		(hatch edge 0.508)
		(priority 35)
		(connect_pads yes
			(clearance 0.12)
		)
		(min_thickness 0.2)
		(filled_areas_thickness no)
		(fill yes
			(thermal_gap 0.3)
			(thermal_bridge_width 0.2)
		)
		(polygon
			(pts
				(xy 194.825 151.7) (xy 201.685862 151.714138) (xy 202.2 151.2) (xy 203.9 151.2) (xy 204.575 150.479997)
				(xy 204.575 150.125) (xy 204.65 150.05) (xy 204.1 149.5) (xy 195.5 149.5) (xy 194.825 150.175)
			)
		)
	)
	(zone
		(net 1)
		(net_name "GND")
		(layer "B.Cu")
		(hatch edge 0.508)
		(priority 52)
		(connect_pads yes
			(clearance 0.1)
		)
		(min_thickness 0.254)
		(filled_areas_thickness no)
		(fill yes
			(thermal_gap 0.508)
			(thermal_bridge_width 0.508)
		)
		(polygon
			(pts
				(xy 246.44 121.77) (xy 248.82 121.77) (xy 248.83 121.78) (xy 248.83 122.44) (xy 249.07 122.68) (xy 249.24 122.68)
				(xy 249.415 122.855) (xy 249.415 124.295) (xy 248.53 125.18) (xy 247.37 125.18) (xy 246.44 124.25)
			)
		)
	)
	(zone
		(net 0)
		(net_name "")
		(layer "B.Cu")
		(hatch edge 0.508)
		(connect_pads
			(clearance 0)
		)
		(min_thickness 0.254)
		(filled_areas_thickness no)
		(keepout
			(tracks allowed)
			(vias allowed)
			(pads allowed)
			(copperpour not_allowed)
			(footprints allowed)
		)
		(placement
			(enabled no)
			(sheetname "")
		)
		(fill
			(thermal_gap 0.508)
			(thermal_bridge_width 0.508)
		)
		(polygon
			(pts
				(xy 113.624499 113.199) (xy 99.874499 113.199) (xy 99.874499 99.949) (xy 113.624499 99.949)
			)
		)
	)
	(zone
		(net 803)
		(net_name "/DDR5 RDIMM/VIN_MGMT")
		(layer "B.Cu")
		(hatch edge 0.5)
		(priority 43)
		(connect_pads yes
			(clearance 0.12)
		)
		(min_thickness 0.25)
		(filled_areas_thickness no)
		(fill yes
			(thermal_gap 0.5)
			(thermal_bridge_width 0.5)
		)
		(polygon
			(pts
				(xy 254.45 104.325) (xy 254.45 101.925) (xy 254.05 101.525) (xy 251.6 101.525) (xy 251.075 102.05)
				(xy 251.075 103.975) (xy 251.425 104.325)
			)
		)
	)
	(zone
		(net 325)
		(net_name "/Supply/12V_aux")
		(layer "B.Cu")
		(hatch edge 0.5)
		(priority 56)
		(connect_pads
			(clearance 0.15)
		)
		(min_thickness 0.25)
		(filled_areas_thickness no)
		(fill yes
			(thermal_gap 0.5)
			(thermal_bridge_width 0.5)
		)
		(polygon
			(pts
				(xy 254.09 123.46) (xy 254.39 123.16) (xy 263.39 123.16) (xy 263.8 123.57) (xy 263.8 126.32) (xy 263.49 126.63)
				(xy 254.45 126.63) (xy 254.09 126.27)
			)
		)
	)
	(zone
		(net 151)
		(net_name "+3V3")
		(layer "B.Cu")
		(hatch edge 0.508)
		(priority 34)
		(connect_pads yes
			(clearance 0.12)
		)
		(min_thickness 0.2)
		(filled_areas_thickness no)
		(fill yes
			(thermal_gap 0.3)
			(thermal_bridge_width 0.2)
		)
		(polygon
			(pts
				(xy 156.551088 157.851084) (xy 159.749885 157.852928) (xy 160.4 157.2) (xy 160.85 157.2) (xy 161.8 158.15)
				(xy 162.15 158.15) (xy 168.58 158.15) (xy 169.53 159.1) (xy 171.1 159.1) (xy 176.7 153.5) (xy 178.500001 153.5)
				(xy 178.9 153.100001) (xy 178.9 151.45) (xy 179.85 150.5) (xy 181.45 150.5) (xy 181.6 150.35) (xy 181.6 149.75)
				(xy 181.8 149.55) (xy 182.5 149.55) (xy 182.65 149.7) (xy 182.65 151.35) (xy 182.15 151.85) (xy 180.65 151.85)
				(xy 180.35 152.15) (xy 180.35 153.35) (xy 182.5 155.5) (xy 182.5 157.5) (xy 181.5 158.5) (xy 175.5 158.5)
				(xy 173.05 160.95) (xy 173.05 167.25) (xy 154.9 167.25) (xy 154.907671 159.5)
			)
		)
	)
	(zone
		(net 553)
		(net_name "+0V85")
		(layer "B.Cu")
		(hatch edge 0.5)
		(priority 15)
		(connect_pads yes
			(clearance 0.12)
		)
		(min_thickness 0.25)
		(filled_areas_thickness no)
		(fill yes
			(thermal_gap 0.5)
			(thermal_bridge_width 0.5)
		)
		(polygon
			(pts
				(xy 232.15 165.180423) (xy 232.15 167.92) (xy 206.29 167.92) (xy 202.855 164.485) (xy 202.855 152.730083)
				(xy 203.376928 152.2) (xy 204.61626 152.2) (xy 205.314661 152.882524) (xy 205.320227 155.486204)
				(xy 208.299911 158.527588) (xy 223.441658 158.516658) (xy 230.1 165.17793)
			)
		)
	)
	(zone
		(net 553)
		(net_name "+0V85")
		(layer "B.Cu")
		(hatch edge 0.5)
		(priority 41)
		(connect_pads yes
			(clearance 0.12)
		)
		(min_thickness 0.25)
		(filled_areas_thickness no)
		(fill yes
			(thermal_gap 0.5)
			(thermal_bridge_width 0.5)
		)
		(polygon
			(pts
				(xy 177.7 168.15) (xy 177.7 166.2) (xy 176.3 166.2) (xy 176.3 168.149999)
			)
		)
	)
	(zone
		(net 10)
		(net_name "+12V")
		(layer "B.Cu")
		(hatch edge 0.508)
		(priority 1)
		(connect_pads yes
			(clearance 0.2)
		)
		(min_thickness 0.254)
		(filled_areas_thickness no)
		(fill yes
			(mode hatch)
			(thermal_gap 0.3)
			(thermal_bridge_width 0.3)
			(hatch_thickness 1)
			(hatch_gap 1.5)
			(hatch_orientation 0)
			(hatch_border_algorithm hatch_thickness)
			(hatch_min_hole_area 0.3)
		)
		(polygon
			(pts
				(xy 148.225 196.725) (xy 145.425 196.725) (xy 145.425 191.825) (xy 148.225 191.825)
			)
		)
	)
	(zone
		(net 1)
		(net_name "GND")
		(layer "B.Cu")
		(hatch edge 0.5)
		(priority 19)
		(connect_pads yes
			(clearance 0.12)
		)
		(min_thickness 0.25)
		(filled_areas_thickness no)
		(fill yes
			(thermal_gap 0.5)
			(thermal_bridge_width 0.5)
		)
		(polygon
			(pts
				(xy 216.134906 167.935) (xy 216.135 172.21) (xy 221.76 172.21) (xy 221.76 167.93365) (xy 226.66 167.929782)
				(xy 226.66 172.21) (xy 232.285 172.21) (xy 232.285 167.86) (xy 232.285 168.27903) (xy 232.283668 165.078384)
				(xy 230.200831 165.084688) (xy 223.54727 158.415329) (xy 208.342987 158.411878) (xy 206.442429 156.505716)
				(xy 206.440507 155.41) (xy 235.635 155.41) (xy 235.635 189.835) (xy 235.61 189.86) (xy 209.96 189.86)
				(xy 209.91 189.81) (xy 209.91 167.935)
			)
		)
	)
	(zone
		(net 35)
		(net_name "VDC")
		(layer "B.Cu")
		(hatch edge 0.508)
		(priority 51)
		(connect_pads yes
			(clearance 0.1)
		)
		(min_thickness 0.254)
		(filled_areas_thickness no)
		(fill yes
			(thermal_gap 0.508)
			(thermal_bridge_width 0.508)
		)
		(polygon
			(pts
				(xy 246.44 121.17) (xy 248.82 121.17) (xy 248.82 120.85) (xy 249.649413 120.849395) (xy 249.9 120.85)
				(xy 249.9 118.88) (xy 250.05 118.73) (xy 250.26 118.73) (xy 250.35 118.64) (xy 250.35 118.18) (xy 249.82 117.65)
				(xy 247.47 117.65) (xy 246.44 118.68)
			)
		)
	)
	(zone
		(net 1)
		(net_name "GND")
		(layer "B.Cu")
		(hatch edge 0.508)
		(connect_pads yes
			(clearance 0.2)
		)
		(min_thickness 0.254)
		(filled_areas_thickness no)
		(fill yes
			(thermal_gap 0.3)
			(thermal_bridge_width 0.3)
		)
		(polygon
			(pts
				(xy 151.125 196.725) (xy 148.325 196.725) (xy 148.325 191.825) (xy 151.125 191.825)
			)
		)
	)
	(zone
		(net 0)
		(net_name "")
		(layer "B.Cu")
		(hatch edge 0.5)
		(connect_pads
			(clearance 0)
		)
		(min_thickness 0.25)
		(filled_areas_thickness no)
		(keepout
			(tracks allowed)
			(vias allowed)
			(pads allowed)
			(copperpour not_allowed)
			(footprints allowed)
		)
		(placement
			(enabled no)
			(sheetname "")
		)
		(fill
			(thermal_gap 0.5)
			(thermal_bridge_width 0.5)
		)
		(polygon
			(pts
				(xy 214.63 174.5) (xy 214.610137 174.095679) (xy 214.550739 173.695252) (xy 214.452379 173.302576)
				(xy 214.316003 172.921431) (xy 214.142925 172.555488) (xy 213.934812 172.208273) (xy 213.693668 171.883128)
				(xy 213.421815 171.583185) (xy 213.121872 171.311332) (xy 212.796727 171.070188) (xy 212.449512 170.862075)
				(xy 212.083569 170.688997) (xy 211.702424 170.552621) (xy 211.309748 170.454261) (xy 210.909321 170.394863)
				(xy 210.505 170.375) (xy 210.100679 170.394863) (xy 209.700252 170.454261) (xy 209.307576 170.552621)
				(xy 208.926431 170.688997) (xy 208.560488 170.862075) (xy 208.213273 171.070188) (xy 207.888128 171.311332)
				(xy 207.588185 171.583185) (xy 207.316332 171.883128) (xy 207.075188 172.208273) (xy 206.867075 172.555488)
				(xy 206.693997 172.921431) (xy 206.557621 173.302576) (xy 206.459261 173.695252) (xy 206.399863 174.095679)
				(xy 206.38 174.5) (xy 206.399863 174.904321) (xy 206.459261 175.304748) (xy 206.557621 175.697424)
				(xy 206.693997 176.078569) (xy 206.867075 176.444512) (xy 207.075188 176.791727) (xy 207.316332 177.116872)
				(xy 207.588185 177.416815) (xy 207.888128 177.688668) (xy 208.213273 177.929812) (xy 208.560488 178.137925)
				(xy 208.926431 178.311003) (xy 209.307576 178.447379) (xy 209.700252 178.545739) (xy 210.100679 178.605137)
				(xy 210.505 178.625) (xy 210.909321 178.605137) (xy 211.309748 178.545739) (xy 211.702424 178.447379)
				(xy 212.083569 178.311003) (xy 212.449512 178.137925) (xy 212.796727 177.929812) (xy 213.121872 177.688668)
				(xy 213.421815 177.416815) (xy 213.693668 177.116872) (xy 213.934812 176.791727) (xy 214.142925 176.444512)
				(xy 214.316003 176.078569) (xy 214.452379 175.697424) (xy 214.550739 175.304748) (xy 214.610137 174.904321)
			)
		)
	)
	(zone
		(net 35)
		(net_name "VDC")
		(layer "B.Cu")
		(hatch edge 0.5)
		(priority 20)
		(connect_pads yes
			(clearance 0.12)
		)
		(min_thickness 0.25)
		(filled_areas_thickness no)
		(fill yes
			(thermal_gap 0.5)
			(thermal_bridge_width 0.5)
		)
		(polygon
			(pts
				(xy 219.51 184.935) (xy 222.96 184.935) (xy 222.985 184.96) (xy 222.985 189.86) (xy 219.485 189.86)
				(xy 219.485 184.96)
			)
		)
	)
	(zone
		(net 1)
		(net_name "GND")
		(layer "B.Cu")
		(hatch edge 0.5)
		(priority 28)
		(connect_pads yes
			(clearance 0.12)
		)
		(min_thickness 0.25)
		(filled_areas_thickness no)
		(fill yes
			(thermal_gap 0.5)
			(thermal_bridge_width 0.5)
		)
		(polygon
			(pts
				(xy 202.225 154.85) (xy 204.7 154.85) (xy 204.7 154.875) (xy 204.7 156.075) (xy 202.825 156.075)
				(xy 202.825 163.85) (xy 202.225 163.85)
			)
		)
	)
	(zone
		(net 1)
		(net_name "GND")
		(layer "B.Cu")
		(hatch edge 0.508)
		(connect_pads
			(clearance 0.1)
		)
		(min_thickness 0.254)
		(filled_areas_thickness no)
		(fill yes
			(thermal_gap 0.508)
			(thermal_bridge_width 0.508)
		)
		(polygon
			(pts
				(xy 259.824499 159.449) (xy 246.549499 159.449) (xy 246.549499 150.949) (xy 259.824499 150.949)
			)
		)
	)
	(zone
		(net 1)
		(net_name "GND")
		(layer "B.Cu")
		(hatch edge 0.5)
		(priority 41)
		(connect_pads yes
			(clearance 0.12)
		)
		(min_thickness 0.25)
		(filled_areas_thickness no)
		(fill yes
			(thermal_gap 0.5)
			(thermal_bridge_width 0.5)
		)
		(polygon
			(pts
				(xy 179.7 168.15) (xy 179.7 166.2) (xy 178.3 166.2) (xy 178.3 168.149999)
			)
		)
	)
	(zone
		(net 1)
		(net_name "GND")
		(layer "B.Cu")
		(hatch edge 0.5)
		(priority 29)
		(connect_pads yes
			(clearance 0.12)
		)
		(min_thickness 0.25)
		(filled_areas_thickness no)
		(fill yes
			(thermal_gap 0.5)
			(thermal_bridge_width 0.5)
		)
		(polygon
			(pts
				(xy 202.225 162.9) (xy 204.75 162.9) (xy 204.75 163.025) (xy 204.75 164.225) (xy 202.6 164.225)
				(xy 202.275 163.899009) (xy 202.225 163.848857)
			)
		)
	)
	(zone
		(net 1)
		(net_name "GND")
		(layer "B.Cu")
		(hatch edge 0.5)
		(priority 55)
		(connect_pads yes
			(clearance 0.12)
		)
		(min_thickness 0.25)
		(filled_areas_thickness no)
		(fill yes
			(thermal_gap 0.5)
			(thermal_bridge_width 0.5)
		)
		(polygon
			(pts
				(xy 254.475 104.475) (xy 255.65 105.65) (xy 255.65 106.975) (xy 255.325 107.3) (xy 252.3 107.3)
				(xy 251.275 106.275) (xy 251.275 104.65) (xy 251.45 104.475)
			)
		)
	)
	(zone
		(net 0)
		(net_name "")
		(layer "B.Cu")
		(hatch edge 0.508)
		(connect_pads
			(clearance 0)
		)
		(min_thickness 0.254)
		(filled_areas_thickness no)
		(keepout
			(tracks allowed)
			(vias not_allowed)
			(pads allowed)
			(copperpour allowed)
			(footprints allowed)
		)
		(placement
			(enabled no)
			(sheetname "")
		)
		(fill
			(thermal_gap 0.508)
			(thermal_bridge_width 0.508)
		)
		(polygon
			(pts
				(xy 100 189) (xy 105.08 189) (xy 105.08 113.05) (xy 100 113.05)
			)
		)
	)
	(zone
		(net 0)
		(net_name "")
		(layer "B.Cu")
		(hatch edge 0.5)
		(connect_pads
			(clearance 0)
		)
		(min_thickness 0.25)
		(filled_areas_thickness no)
		(keepout
			(tracks allowed)
			(vias allowed)
			(pads allowed)
			(copperpour not_allowed)
			(footprints allowed)
		)
		(placement
			(enabled no)
			(sheetname "")
		)
		(fill
			(thermal_gap 0.5)
			(thermal_bridge_width 0.5)
		)
		(polygon
			(pts
				(xy 221.885 176.7235) (xy 221.885 175.91) (xy 221.735 175.76) (xy 221.235 175.76) (xy 221.135 175.86)
				(xy 221.135 176.41) (xy 221.4485 176.7235)
			)
		)
	)
	(zone
		(net 1)
		(net_name "GND")
		(layer "B.Cu")
		(hatch edge 0.5)
		(priority 29)
		(connect_pads yes
			(clearance 0.12)
		)
		(min_thickness 0.25)
		(filled_areas_thickness no)
		(fill yes
			(thermal_gap 0.5)
			(thermal_bridge_width 0.5)
		)
		(polygon
			(pts
				(xy 202.275 158.875) (xy 204.75 158.875) (xy 204.75 158.9) (xy 204.75 160.1) (xy 202.275 160.1)
			)
		)
	)
	(zone
		(net 224)
		(net_name "/Supply/DC-DC VCCINT/0V85_REG1")
		(layer "B.Cu")
		(hatch edge 0.5)
		(priority 18)
		(connect_pads yes
			(clearance 0.12)
		)
		(min_thickness 0.25)
		(filled_areas_thickness no)
		(fill yes
			(thermal_gap 0.5)
			(thermal_bridge_width 0.5)
		)
		(polygon
			(pts
				(xy 226.81 172.06) (xy 232.185 172.06) (xy 232.185 167.935) (xy 226.785 167.935) (xy 226.785 172.035)
			)
		)
	)
	(zone
		(net 1)
		(net_name "GND")
		(layers "B.Cu" "In4.Cu")
		(hatch edge 0.508)
		(connect_pads
			(clearance 0.1)
		)
		(min_thickness 0.254)
		(filled_areas_thickness no)
		(fill yes
			(thermal_gap 0.508)
			(thermal_bridge_width 0.508)
		)
		(polygon
			(pts
				(xy 259.824499 176.974) (xy 247.175 176.974) (xy 246.499499 176.3) (xy 246.499499 168.474) (xy 259.824499 168.474)
			)
		)
	)
	(zone
		(net 1)
		(net_name "GND")
		(layers "In1.Cu" "In3.Cu" "In5.Cu" "In7.Cu" "In10.Cu")
		(hatch edge 0.508)
		(connect_pads
			(clearance 0.12)
		)
		(min_thickness 0.254)
		(filled_areas_thickness no)
		(fill yes
			(thermal_gap 0.508)
			(thermal_bridge_width 0.508)
		)
		(polygon
			(pts
				(xy 265 203) (xy 100 202.75) (xy 100 100) (xy 265 100)
			)
		)
	)
	(zone
		(net 553)
		(net_name "+0V85")
		(layer "In2.Cu")
		(hatch edge 0.5)
		(priority 39)
		(connect_pads
			(clearance 0.12)
		)
		(min_thickness 0.25)
		(filled_areas_thickness no)
		(fill yes
			(thermal_gap 0.5)
			(thermal_bridge_width 0.5)
		)
		(polygon
			(pts
				(xy 185 153) (xy 186 153) (xy 187 152) (xy 187 151.15) (xy 184.275 151.15) (xy 184.275 150.272623)
				(xy 188.274965 150.285731) (xy 189.152044 149.400926) (xy 191.499942 149.399958) (xy 191.500634 150.6)
				(xy 190.85 150.6) (xy 190.475 150.975) (xy 190.475 153.875) (xy 191.1 154.5) (xy 192.500001 154.5)
				(xy 193.500001 155.5) (xy 193.5 156.5) (xy 194.500001 157.500001) (xy 196.500001 157.500001) (xy 197.5 158.5)
				(xy 201.499 158.5) (xy 201.4995 158.4995) (xy 226.7495 158.4995) (xy 233.1 164.85) (xy 233.1 174.05)
				(xy 231.5 175.65) (xy 210.2 175.65) (xy 204.45 181.4) (xy 192.85 181.4) (xy 187.9 176.45) (xy 187.9 157.899999)
				(xy 187.500001 157.5) (xy 184.85 157.5) (xy 184.5 157.15) (xy 184.5 153.5)
			)
		)
	)
	(zone
		(net 1)
		(net_name "GND")
		(layer "In2.Cu")
		(hatch edge 0.508)
		(priority 48)
		(connect_pads
			(clearance 0.1)
		)
		(min_thickness 0.254)
		(filled_areas_thickness no)
		(fill yes
			(thermal_gap 0.508)
			(thermal_bridge_width 0.508)
		)
		(polygon
			(pts
				(xy 257.325 153.875) (xy 257.325 157.825) (xy 256.925 158.225) (xy 255.175 158.225) (xy 252.5 160.9)
				(xy 252.5 169.1) (xy 253.6 170.2) (xy 256.875 170.2) (xy 257.65 170.975) (xy 257.65 173.825) (xy 255.575 175.9)
				(xy 254.4 175.9) (xy 254.175 176.125) (xy 254.175 178.45) (xy 252.625 180) (xy 245.925 180) (xy 244.475 178.55)
				(xy 244.475 166.275) (xy 242.35 164.15) (xy 242.35 149.225) (xy 243.45 148.125) (xy 248.65 148.125)
				(xy 253.775 153.25) (xy 256.7 153.25)
			)
		)
	)
	(zone
		(net 0)
		(net_name "")
		(layer "In4.Cu")
		(hatch edge 0.508)
		(connect_pads
			(clearance 0)
		)
		(min_thickness 0.254)
		(filled_areas_thickness no)
		(keepout
			(tracks allowed)
			(vias allowed)
			(pads allowed)
			(copperpour not_allowed)
			(footprints allowed)
		)
		(placement
			(enabled no)
			(sheetname "")
		)
		(fill
			(thermal_gap 0.508)
			(thermal_bridge_width 0.508)
		)
		(polygon
			(pts
				(xy 187.95 182.825) (xy 202.275 182.825) (xy 209.025 176.075) (xy 231.375 176.075) (xy 231.5 175.95)
				(xy 231.5 184.05) (xy 229.3 186.25) (xy 187.95 186.25)
			)
		)
	)
	(zone
		(net 0)
		(net_name "")
		(layer "In4.Cu")
		(hatch edge 0.5)
		(connect_pads
			(clearance 0)
		)
		(min_thickness 0.25)
		(filled_areas_thickness no)
		(keepout
			(tracks allowed)
			(vias allowed)
			(pads allowed)
			(copperpour not_allowed)
			(footprints allowed)
		)
		(placement
			(enabled no)
			(sheetname "")
		)
		(fill
			(thermal_gap 0.5)
			(thermal_bridge_width 0.5)
		)
		(polygon
			(pts
				(xy 202.084698 157.5) (xy 216.7 157.5) (xy 218.898499 155.301501) (xy 218.898499 154.389) (xy 205.195698 154.389)
			)
		)
	)
	(zone
		(net 0)
		(net_name "")
		(layer "In4.Cu")
		(hatch edge 0.508)
		(connect_pads
			(clearance 0)
		)
		(min_thickness 0.254)
		(filled_areas_thickness no)
		(keepout
			(tracks allowed)
			(vias allowed)
			(pads allowed)
			(copperpour not_allowed)
			(footprints allowed)
		)
		(placement
			(enabled no)
			(sheetname "")
		)
		(fill
			(thermal_gap 0.3)
			(thermal_bridge_width 0.3)
		)
		(polygon
			(pts
				(xy 183.5 147.5) (xy 183.5 154.5) (xy 182.5 155.5) (xy 175.5 155.5) (xy 175.5 147.5)
			)
		)
	)
	(zone
		(net 150)
		(net_name "+1V2")
		(layer "In4.Cu")
		(hatch edge 0.508)
		(priority 33)
		(connect_pads
			(clearance 0.15)
		)
		(min_thickness 0.254)
		(filled_areas_thickness no)
		(fill yes
			(thermal_gap 0.508)
			(thermal_bridge_width 0.508)
		)
		(polygon
			(pts
				(xy 148.15 144.5) (xy 144.75 147.9) (xy 131.55 147.9) (xy 127.2625 143.6125) (xy 123.25 143.619479)
				(xy 121.949498 144.924989) (xy 121.938099 171.310505) (xy 113.325 171.314926) (xy 113.325 139.5)
				(xy 115.325 137.5) (xy 143.65 137.5) (xy 148.15 142)
			)
		)
	)
	(zone
		(net 0)
		(net_name "")
		(layer "In4.Cu")
		(hatch edge 0.5)
		(connect_pads
			(clearance 0)
		)
		(min_thickness 0.25)
		(filled_areas_thickness no)
		(keepout
			(tracks allowed)
			(vias allowed)
			(pads allowed)
			(copperpour not_allowed)
			(footprints allowed)
		)
		(placement
			(enabled no)
			(sheetname "")
		)
		(fill
			(thermal_gap 0.5)
			(thermal_bridge_width 0.5)
		)
		(polygon
			(pts
				(xy 181.5 163.49) (xy 184.512622 163.5) (xy 184.515 159.525) (xy 185.54 158.5) (xy 187.5 158.5)
				(xy 188 159) (xy 188 174.5) (xy 188 183.35) (xy 174.93 183.35) (xy 174.93 166.661125) (xy 178.341713 166.658927)
			)
		)
	)
	(zone
		(net 0)
		(net_name "")
		(layer "In4.Cu")
		(hatch edge 0.508)
		(connect_pads
			(clearance 0)
		)
		(min_thickness 0.2)
		(filled_areas_thickness no)
		(keepout
			(tracks allowed)
			(vias allowed)
			(pads allowed)
			(copperpour not_allowed)
			(footprints allowed)
		)
		(placement
			(enabled no)
			(sheetname "")
		)
		(fill
			(thermal_gap 0.3)
			(thermal_bridge_width 0.2)
		)
		(polygon
			(pts
				(xy 194.475 148.5) (xy 193.65 149.325) (xy 193.65 156.5) (xy 198.5 156.5) (xy 199.170001 156.5)
				(xy 200.170001 157.5) (xy 202.084698 157.5) (xy 205.669698 153.915) (xy 206.265 153.915) (xy 206.8 154.45)
				(xy 213 154.45) (xy 213.85 155.3) (xy 218.883669 155.3) (xy 220.42707 153.709091) (xy 220.425459 148.825459)
				(xy 220.1 148.5)
			)
		)
	)
	(zone
		(net 1)
		(net_name "GND")
		(layer "In4.Cu")
		(hatch edge 0.508)
		(priority 47)
		(connect_pads
			(clearance 0.1)
		)
		(min_thickness 0.254)
		(filled_areas_thickness no)
		(fill yes
			(thermal_gap 0.508)
			(thermal_bridge_width 0.508)
		)
		(polygon
			(pts
				(xy 246.55 154.7) (xy 246.55 158.975) (xy 247.3 159.725) (xy 257.3 159.725) (xy 258.25 158.775)
				(xy 258.25 156.825) (xy 259.15 155.925) (xy 259.85 155.925) (xy 260.1 155.675) (xy 260.1 151.475)
				(xy 259.525 150.9) (xy 258.325 150.9) (xy 257.75 151.475) (xy 257.15 151.475) (xy 256.875 151.2)
				(xy 256.875 151.025) (xy 256.75 150.9) (xy 256.45 150.9) (xy 256.35 151) (xy 256.35 151.35) (xy 256.225 151.475)
				(xy 255.5 151.475) (xy 254.9 150.875) (xy 250.375 150.875)
			)
		)
	)
	(zone
		(net 553)
		(net_name "+0V85")
		(layers "In4.Cu" "In6.Cu" "In9.Cu")
		(hatch edge 0.5)
		(priority 26)
		(connect_pads
			(clearance 0.12)
		)
		(min_thickness 0.25)
		(filled_areas_thickness no)
		(fill yes
			(thermal_gap 0.5)
			(thermal_bridge_width 0.5)
		)
		(polygon
			(pts
				(xy 175.525 147.734659) (xy 189.114333 147.760087) (xy 189.485117 148.125) (xy 192.875 148.125)
				(xy 194.125 148.125) (xy 195.5 149.5) (xy 198.5 149.5) (xy 199.5 150.5) (xy 231.428751 150.5) (xy 231.394 178.816)
				(xy 226.114084 183.175) (xy 175.525 183.175)
			)
		)
	)
	(zone
		(net 1)
		(net_name "GND")
		(layer "In6.Cu")
		(hatch edge 0.508)
		(priority 46)
		(connect_pads
			(clearance 0.15)
		)
		(min_thickness 0.254)
		(filled_areas_thickness no)
		(fill yes
			(thermal_gap 0.508)
			(thermal_bridge_width 0.508)
		)
		(polygon
			(pts
				(xy 246.375 173.6) (xy 247.9 175.125) (xy 247.9 178.525) (xy 252.425 183.05) (xy 265 183.05) (xy 265.05 183)
				(xy 265.05 147) (xy 264.95 146.9) (xy 252.275 146.9) (xy 251.5 147.675) (xy 251.5 148.975) (xy 248.625 151.85)
				(xy 247.125 151.85) (xy 246.375 152.6)
			)
		)
	)
	(zone
		(net 151)
		(net_name "+3V3")
		(layer "In6.Cu")
		(hatch edge 0.508)
		(priority 36)
		(connect_pads yes
			(clearance 0.12)
		)
		(min_thickness 0.2)
		(filled_areas_thickness no)
		(fill yes
			(thermal_gap 0.3)
			(thermal_bridge_width 0.2)
		)
		(polygon
			(pts
				(xy 146.275 143.075) (xy 146.275 154.95) (xy 145.325 155.9) (xy 134.25 155.9) (xy 130.825 159.325)
				(xy 130.825 167.1) (xy 133.525 169.8) (xy 143.975 169.8) (xy 144 169.775) (xy 144.875 170.65) (xy 144.875 174.7)
				(xy 160.525 190.35) (xy 160.525 192.85) (xy 160.1 193.275) (xy 149.1 193.275) (xy 144.9 189.075)
				(xy 144.9 188.8) (xy 101.1 188.8) (xy 100.1 189.8) (xy 100.025 189.725) (xy 100.025 137.5) (xy 140.7 137.5)
			)
		)
	)
	(zone
		(net 0)
		(net_name "")
		(layer "In6.Cu")
		(hatch edge 0.508)
		(connect_pads
			(clearance 0)
		)
		(min_thickness 0.254)
		(filled_areas_thickness no)
		(keepout
			(tracks allowed)
			(vias allowed)
			(pads allowed)
			(copperpour not_allowed)
			(footprints allowed)
		)
		(placement
			(enabled no)
			(sheetname "")
		)
		(fill
			(thermal_gap 0.3)
			(thermal_bridge_width 0.3)
		)
		(polygon
			(pts
				(xy 193.55 148.125) (xy 193.725 148.3) (xy 193.725 150) (xy 193.724106 150.049106) (xy 196.025 152.35)
				(xy 197.35 152.35) (xy 198.5 153.5) (xy 199.96 153.5) (xy 200.949746 152.51898) (xy 203.268658 152.521342)
				(xy 204.565 151.225) (xy 224.525 151.225) (xy 221.425 148.125)
			)
		)
	)
	(zone
		(net 0)
		(net_name "")
		(layer "In6.Cu")
		(hatch edge 0.5)
		(connect_pads
			(clearance 0)
		)
		(min_thickness 0.25)
		(filled_areas_thickness no)
		(keepout
			(tracks allowed)
			(vias allowed)
			(pads allowed)
			(copperpour not_allowed)
			(footprints allowed)
		)
		(placement
			(enabled no)
			(sheetname "")
		)
		(fill
			(thermal_gap 0.5)
			(thermal_bridge_width 0.5)
		)
		(polygon
			(pts
				(xy 174.98 150.473216) (xy 184.101892 150.501892) (xy 184.5 150.9) (xy 184.5 157.500001) (xy 186.319375 159.275001)
				(xy 187.475 159.275001) (xy 187.925091 158.974939) (xy 189.977453 158.977453) (xy 190.5 159.5) (xy 190.5 160.5)
				(xy 190.004321 160.995679) (xy 187.777473 160.99337) (xy 187.50247 160.725) (xy 174.98 160.725)
			)
		)
	)
	(zone
		(net 6)
		(net_name "/Debug FTDI + VNA/FTDI_3V3")
		(layer "In6.Cu")
		(hatch edge 0.5)
		(priority 31)
		(connect_pads yes
			(clearance 0)
		)
		(min_thickness 0.25)
		(filled_areas_thickness no)
		(fill yes
			(thermal_gap 0.5)
			(thermal_bridge_width 0.5)
		)
		(polygon
			(pts
				(xy 145.325 155.9) (xy 150.375 160.95) (xy 150.375 167) (xy 152.303122 168.905935) (xy 152.295 169.8)
				(xy 133.525 169.8) (xy 130.825 167.1) (xy 130.825 159.325) (xy 134.25 155.9)
			)
		)
	)
	(zone
		(net 573)
		(net_name "+1V8_MGTVCCAUX")
		(layer "In8.Cu")
		(hatch edge 0.5)
		(priority 25)
		(connect_pads
			(clearance 0.12)
		)
		(min_thickness 0.25)
		(filled_areas_thickness no)
		(fill yes
			(thermal_gap 0.5)
			(thermal_bridge_width 0.5)
		)
		(polygon
			(pts
				(xy 192.75 159.6) (xy 192.75 153.55) (xy 192.46 153.26) (xy 169.055 153.26) (xy 169.055 176.729078)
				(xy 182.48203 190.12256) (xy 265.055633 189.866927) (xy 265.045259 178.71) (xy 187.710334 178.71)
				(xy 174.43 165.520524) (xy 174.43 158.7) (xy 188.771554 158.7) (xy 189.681554 159.6)
			)
		)
	)
	(zone
		(net 797)
		(net_name "+1V8")
		(layer "In8.Cu")
		(hatch edge 0.5)
		(priority 22)
		(connect_pads
			(clearance 0.12)
		)
		(min_thickness 0.25)
		(filled_areas_thickness no)
		(fill yes
			(thermal_gap 0.5)
			(thermal_bridge_width 0.5)
		)
		(polygon
			(pts
				(xy 190.5 146.5) (xy 190.5 144.9) (xy 190.3 144.7) (xy 184.4 144.7) (xy 183.3 143.6) (xy 180.5 143.6)
				(xy 179.0352 142.131507) (xy 179.044716 139.517091) (xy 178.115473 138.596277) (xy 172.522532 138.599015)
				(xy 166.473529 132.47) (xy 133.83 132.47) (xy 125.15 141.15) (xy 125.15 149.55) (xy 119.65 155.05)
				(xy 119.65 168.68) (xy 123.189568 172.219568) (xy 141.45 172.35) (xy 141.5 166.8) (xy 141.51 157.62)
				(xy 142.72 156.4) (xy 152.3 156.4) (xy 152.936281 155.756807) (xy 168.9 155.77075) (xy 168.9 153.11)
				(xy 192.45 153.11) (xy 192.85 153.51) (xy 192.85 157.5) (xy 194.9 157.5) (xy 195.611636 157.5) (xy 198.611735 154.494523)
				(xy 228.526602 154.536588) (xy 238.031057 164.049972) (xy 247.076567 164.04973) (xy 247.105452 172.760141)
				(xy 243.51 172.76) (xy 243.51 178.538126) (xy 265.02 178.529798) (xy 265.02 157.575) (xy 244.05 157.575)
				(xy 243.376062 156.9) (xy 243.393808 149.163183) (xy 239 144.775) (xy 205.825 144.775) (xy 202.4 148.2)
				(xy 192.2 148.2)
			)
		)
	)
	(zone
		(net 810)
		(net_name "/HDMI + SD Card/HDMI_VDD")
		(layer "In8.Cu")
		(hatch edge 0.5)
		(priority 44)
		(connect_pads
			(clearance 0.2)
		)
		(min_thickness 0.25)
		(filled_areas_thickness no)
		(fill yes
			(thermal_gap 0.5)
			(thermal_bridge_width 0.5)
		)
		(polygon
			(pts
				(xy 117.85 170.775) (xy 121.65 170.775) (xy 123.171927 172.296927) (xy 123.171927 172.308078) (xy 123.176136 172.312287)
				(xy 127.552108 172.312287) (xy 127.581071 172.34125) (xy 127.581071 176.732539) (xy 128.9 178.051468)
				(xy 128.9 186.93) (xy 128.76 187.07) (xy 119.43 187.07) (xy 119.07 186.71) (xy 119.07 175.543786)
				(xy 117.85 174.323786) (xy 117.85 171.675)
			)
		)
	)
	(zone
		(net 687)
		(net_name "VDDQ")
		(layer "In8.Cu")
		(hatch edge 0.508)
		(priority 32)
		(connect_pads
			(clearance 0.15)
		)
		(min_thickness 0.254)
		(filled_areas_thickness no)
		(fill yes
			(thermal_gap 0.508)
			(thermal_bridge_width 0.508)
		)
		(polygon
			(pts
				(xy 117.851268 170.725794) (xy 117.843871 149.975) (xy 121.782171 146.035808) (xy 121.796743 134.849996)
				(xy 133.380209 123.396011) (xy 173.9 123.355144) (xy 173.9 132.38) (xy 133.749304 132.38) (xy 125.065482 141.047018)
				(xy 125.071774 149.466273) (xy 119.544597 155.02336) (xy 119.550206 168.676674) (xy 121.579785 170.716707)
			)
		)
	)
	(zone
		(net 820)
		(net_name "+0V9_MGTAVCC")
		(layer "In8.Cu")
		(hatch edge 0.5)
		(priority 23)
		(connect_pads
			(clearance 0.12)
		)
		(min_thickness 0.25)
		(filled_areas_thickness no)
		(fill yes
			(thermal_gap 0.5)
			(thermal_bridge_width 0.5)
		)
		(polygon
			(pts
				(xy 231.098026 168.46) (xy 227.702361 165.058274) (xy 210.200987 165.075987) (xy 203.425 158.3)
				(xy 199.96 158.3) (xy 196.91 161.35) (xy 183.3 161.35) (xy 183.3 158.8) (xy 188.78 158.8) (xy 189.631305 159.651305)
				(xy 192.8 159.64248) (xy 192.8 157.6) (xy 195.8 157.6) (xy 198.8 154.6) (xy 228.4 154.6) (xy 237.896603 164.160558)
				(xy 247.001485 164.185459) (xy 247.000304 168.46)
			)
		)
	)
	(zone
		(net 151)
		(net_name "+3V3")
		(layer "In8.Cu")
		(hatch edge 0.508)
		(connect_pads yes
			(clearance 0)
		)
		(min_thickness 0.254)
		(filled_areas_thickness no)
		(fill yes
			(thermal_gap 0.508)
			(thermal_bridge_width 0.508)
		)
		(polygon
			(pts
				(xy 100 100) (xy 265 100) (xy 265 202.7) (xy 100.114111 202.7)
			)
		)
	)
	(zone
		(net 172)
		(net_name "+1V2_MGTAVTT")
		(layer "In8.Cu")
		(hatch edge 0.5)
		(priority 24)
		(connect_pads
			(clearance 0.12)
		)
		(min_thickness 0.25)
		(filled_areas_thickness no)
		(fill yes
			(thermal_gap 0.5)
			(thermal_bridge_width 0.5)
		)
		(polygon
			(pts
				(xy 246.979231 172.599672) (xy 246.979231 168.545065) (xy 230.869464 168.538291) (xy 227.541077 165.209586)
				(xy 210.168469 165.214622) (xy 203.35 158.319672) (xy 199.728731 158.319672) (xy 199.239201 158.809202)
				(xy 199.24 159.08) (xy 197 161.319617) (xy 183.249231 161.319414) (xy 183.249231 158.719672) (xy 174.599231 158.719672)
				(xy 174.599231 165.205509) (xy 187.950481 178.519672) (xy 243.395556 178.519672) (xy 243.407315 172.599672)
			)
		)
	)
	(zone
		(net 687)
		(net_name "VDDQ")
		(layer "In8.Cu")
		(hatch edge 0.5)
		(priority 21)
		(connect_pads
			(clearance 0.12)
		)
		(min_thickness 0.25)
		(filled_areas_thickness no)
		(fill yes
			(thermal_gap 0.5)
			(thermal_bridge_width 0.5)
		)
		(polygon
			(pts
				(xy 166.259837 134.609837) (xy 167.25959 134.609914) (xy 171.302865 138.7) (xy 175.74 138.7) (xy 180.538339 143.498339)
				(xy 183.299888 143.499888) (xy 184.44 144.64) (xy 190.3 144.64) (xy 190.56 144.9) (xy 190.56 146.45)
				(xy 191.7 147.59) (xy 191.7 147.8) (xy 192.1 148.2) (xy 202.1 148.2) (xy 205.65 144.646313) (xy 239.05 144.648777)
				(xy 243.505543 149.117943) (xy 249.6 149.127205) (xy 249.6 136.825) (xy 243.234369 136.836814) (xy 243.240976 132.567937)
				(xy 249.637747 132.554268) (xy 249.600304 104.825) (xy 163.9 104.825) (xy 163.9 132.25)
			)
		)
	)
	(zone
		(net 35)
		(net_name "VDC")
		(layer "In9.Cu")
		(hatch edge 0.508)
		(priority 27)
		(connect_pads
			(clearance 0.12)
		)
		(min_thickness 0.254)
		(filled_areas_thickness no)
		(fill yes
			(thermal_gap 0.3)
			(thermal_bridge_width 0.3)
		)
		(polygon
			(pts
				(xy 265 190) (xy 144.875 190) (xy 144.875 180.819118) (xy 146.479363 179.224) (xy 231.19429 179.224)
				(xy 231.604 178.819966) (xy 231.604 100) (xy 265 100)
			)
		)
	)
	(zone
		(net 1)
		(net_name "GND")
		(layer "In9.Cu")
		(hatch edge 0.508)
		(priority 45)
		(connect_pads
			(clearance 0.15)
		)
		(min_thickness 0.254)
		(filled_areas_thickness no)
		(fill yes
			(thermal_gap 0.508)
			(thermal_bridge_width 0.508)
		)
		(polygon
			(pts
				(xy 121.575 118.75) (xy 121.575 129.925) (xy 125.025 133.375) (xy 138.55 133.375) (xy 151.15 120.775)
				(xy 151.15 114.1) (xy 150.6 113.55) (xy 126.775 113.55)
			)
		)
	)
	(zone
		(net 0)
		(net_name "")
		(layer "In9.Cu")
		(hatch edge 0.508)
		(connect_pads
			(clearance 0)
		)
		(min_thickness 0.254)
		(filled_areas_thickness no)
		(keepout
			(tracks allowed)
			(vias allowed)
			(pads allowed)
			(copperpour not_allowed)
			(footprints allowed)
		)
		(placement
			(enabled no)
			(sheetname "")
		)
		(fill
			(thermal_gap 0.3)
			(thermal_bridge_width 0.3)
		)
		(polygon
			(pts
				(xy 184.5 147.302012) (xy 184.5 157.175) (xy 181.4975 160.1775) (xy 181.5 163.5239) (xy 178.1475 163.5275)
				(xy 176.175 165.5) (xy 175.5 165.5) (xy 175.5 147.277012)
			)
		)
	)
)
